G04 ================== begin FILE IDENTIFICATION RECORD ==================*
G04 Layout Name:  DAT6MTH3AD0_t6m_cm_d_brd_103112_274.brd*
G04 Film Name:    ssb.art*
G04 File Format:  Gerber RS274X*
G04 File Origin:  Cadence Allegro 16.3-S048*
G04 Origin Date:  Tue Nov 26 10:18:26 2013*
G04 *
G04 Layer:  REF DES/SILKSCREEN_BOTTOM*
G04 Layer:  PACKAGE GEOMETRY/SILKSCREEN_BOTTOM*
G04 Layer:  MANUFACTURING/PHOTOPLOT_OUTLINE*
G04 Layer:  MANUFACTURING/TP_TEXT_BOTTOM*
G04 Layer:  DRAWING FORMAT/TITLE_BLOCK*
G04 Layer:  DRAWING FORMAT/TITLE_DATA_SSB*
G04 Layer:  BOARD GEOMETRY/OUTLINE*
G04 Layer:  BOARD GEOMETRY/SILKSCREEN_BOTTOM*
G04 *
G04 Offset:    (0.00 0.00)*
G04 Mirror:    No*
G04 Mode:      Positive*
G04 Rotation:  0*
G04 FullContactRelief:  No*
G04 UndefLineWidth:     6.00*
G04 ================== end FILE IDENTIFICATION RECORD ====================*
%FSLAX25Y25*MOIN*%
%IR0*IPPOS*OFA0.00000B0.00000*MIA0B0*SFA1.00000B1.00000*%
%ADD10C,.006*%
G75*
%LPD*%
G75*
G36*
G01X241359Y170876D02*
Y147254D01*
X438209D01*
Y170876D01*
X241359D01*
G37*
G36*
G01X387818Y672095D02*
X385518Y672995D01*
Y671295D01*
X387818Y672095D01*
G37*
G36*
G01X407350Y669796D02*
X409650Y668896D01*
Y670596D01*
X407350Y669796D01*
G37*
G36*
G01X510159Y210350D02*
X509259Y208050D01*
X510959D01*
X510159Y210350D01*
G37*
G36*
G01X520250Y216241D02*
X517950Y217141D01*
Y215441D01*
X520250Y216241D01*
G37*
G54D10*
G01X-42372Y125213D02*
G02I-2500J0D01*
G01X-44872Y127713D02*
G03Y122713I0J-2500D01*
G03Y127713I0J2500D01*
G01X-42372Y125213D02*
G03X-47372I-2500J0D01*
G03X-42372I2500J0D01*
G01X-44872Y127713D02*
G03I0J-2500D01*
G01X-42372Y141213D02*
G02I-2500J0D01*
G01X-44872Y143713D02*
G03Y138713I0J-2500D01*
G03Y143713I0J2500D01*
G01X-42372Y141213D02*
G03X-47372I-2500J0D01*
G03X-42372I2500J0D01*
G01X-44872Y143713D02*
G03I0J-2500D01*
G01X-42372Y232533D02*
G02I-2500J0D01*
G01X-44872Y235033D02*
G03Y230033I0J-2500D01*
G03Y235033I0J2500D01*
G01D02*
G03Y230033I0J-2500D01*
G03Y235033I0J2500D01*
G01X-42372Y232533D02*
G03X-47372I-2500J0D01*
G03X-42372I2500J0D01*
G01X-44872Y235033D02*
G03I0J-2500D01*
G01D02*
G02I0J-2500D01*
G01X-42372Y248533D02*
G02I-2500J0D01*
G01X-44872Y251033D02*
G03Y246033I0J-2500D01*
G03Y251033I0J2500D01*
G01D02*
G03Y246033I0J-2500D01*
G03Y251033I0J2500D01*
G01X-42372Y248533D02*
G03X-47372I-2500J0D01*
G03X-42372I2500J0D01*
G01X-44872Y251033D02*
G03I0J-2500D01*
G01D02*
G02I0J-2500D01*
G01X-42372Y738493D02*
G02I-2500J0D01*
G01X-44872Y735993D02*
G03Y740993I0J2500D01*
G03Y735993I0J-2500D01*
G01X-42372Y738493D02*
G03X-47372I-2500J0D01*
G03X-42372I2500J0D01*
G01X-44872Y735993D02*
G03I0J2500D01*
G01X-42372Y754493D02*
G02I-2500J0D01*
G01X-44872Y751993D02*
G03Y756993I0J2500D01*
G03Y751993I0J-2500D01*
G01X-42372Y754493D02*
G03X-47372I-2500J0D01*
G03X-42372I2500J0D01*
G01X-44872Y751993D02*
G03I0J2500D01*
G01X-24372Y125213D02*
G02I-2500J0D01*
G01X-26872Y127713D02*
G03Y122713I0J-2500D01*
G03Y127713I0J2500D01*
G01X-24372Y125213D02*
G03X-29372I-2500J0D01*
G03X-24372I2500J0D01*
G01X-26872Y127713D02*
G03I0J-2500D01*
G01X-24372Y141213D02*
G02I-2500J0D01*
G01X-26872Y143713D02*
G03Y138713I0J-2500D01*
G03Y143713I0J2500D01*
G01X-24372Y141213D02*
G03X-29372I-2500J0D01*
G03X-24372I2500J0D01*
G01X-26872Y143713D02*
G03I0J-2500D01*
G01X-24372Y232533D02*
G02I-2500J0D01*
G01X-26872Y235033D02*
G03Y230033I0J-2500D01*
G03Y235033I0J2500D01*
G01D02*
G03Y230033I0J-2500D01*
G03Y235033I0J2500D01*
G01X-24372Y232533D02*
G03X-29372I-2500J0D01*
G03X-24372I2500J0D01*
G01X-26872Y235033D02*
G03I0J-2500D01*
G01D02*
G02I0J-2500D01*
G01X-24372Y248533D02*
G02I-2500J0D01*
G01X-26872Y251033D02*
G03Y246033I0J-2500D01*
G03Y251033I0J2500D01*
G01D02*
G03Y246033I0J-2500D01*
G03Y251033I0J2500D01*
G01X-24372Y248533D02*
G03X-29372I-2500J0D01*
G03X-24372I2500J0D01*
G01X-26872Y251033D02*
G03I0J-2500D01*
G01D02*
G02I0J-2500D01*
G01X-24372Y738493D02*
G02I-2500J0D01*
G01X-26872Y735993D02*
G03Y740993I0J2500D01*
G03Y735993I0J-2500D01*
G01X-24372Y738493D02*
G03X-29372I-2500J0D01*
G03X-24372I2500J0D01*
G01X-26872Y735993D02*
G03I0J2500D01*
G01X-24372Y754493D02*
G02I-2500J0D01*
G01X-26872Y751993D02*
G03Y756993I0J2500D01*
G03Y751993I0J-2500D01*
G01X-24372Y754493D02*
G03X-29372I-2500J0D01*
G03X-24372I2500J0D01*
G01X-26872Y751993D02*
G03I0J2500D01*
G01X736866Y821652D02*
X738695Y819832D01*
X738819Y819708D01*
Y679921D01*
G03X746693Y672047I7874J0D01*
G01X779528D01*
G02X787402Y664173I0J-7874D01*
G01Y297835D01*
G02X781496Y291929I-5906J0D01*
G01X780315D01*
G03X774409Y286024I0J-5906D01*
G01Y132480D01*
G03X780315Y126575I5906J1D01*
G01X781496D01*
G02X787402Y120669I0J-5906D01*
G01Y7874D01*
G02X779528Y0I-7874J0D01*
G01X7874D01*
G02X0Y7874I0J7874D01*
G01Y115354D01*
G02X5906Y121260I5906J0D01*
G01X25591D01*
G03X31496Y127165I0J5905D01*
G01Y272835D01*
G03X25591Y278740I-5905J0D01*
G01X5906D01*
G02X0Y284646I0J5906D01*
G01Y664173D01*
G02X7874Y672047I7874J0D01*
G01X40787D01*
G03X48661Y679921I0J7874D01*
G01Y819674D01*
X49201Y820214D01*
X50646Y821652D01*
X327026D01*
X328915Y819773D01*
X328976Y819712D01*
Y792323D01*
G03X336457I3740J0D01*
G01Y819673D01*
X336476Y819692D01*
X338446Y821652D01*
X378606D01*
X380551Y819707D01*
Y741142D01*
G03X406929I13189J0D01*
G01Y819675D01*
X406946Y819692D01*
X408916Y821652D01*
X685296D01*
X686388Y820566D01*
X687244Y819710D01*
Y792323D01*
G03X694724I3740J0D01*
G01Y819670D01*
X694746Y819692D01*
X696716Y821652D01*
X736866D01*
G01X5906Y278740D02*
X25591D01*
G02X31496Y272835I0J-5905D01*
G01Y127165D01*
G02X25591Y121260I-5905J0D01*
G01X5906D01*
G03X0Y115354I0J-5906D01*
G01Y7874D01*
G03X7874Y0I7874J0D01*
G01X779528D01*
G03X787402Y7874I0J7874D01*
G01Y120669D01*
G03X781496Y126575I-5906J0D01*
G01X780315D01*
G02X774409Y132480I0J5906D01*
G01Y286024D01*
G02X780315Y291929I5906J-1D01*
G01X781496D01*
G03X787402Y297835I0J5906D01*
G01Y664173D01*
G03X779528Y672047I-7874J0D01*
G01X746693D01*
G02X738819Y679921I0J7874D01*
G01Y819708D01*
X738695Y819832D01*
X736866Y821652D01*
G01X5906Y278740D02*
G02X0Y284646I0J5906D01*
G01Y664173D01*
G02X7874Y672047I7874J0D01*
G01X40787D01*
G03X48661Y679921I0J7874D01*
G01Y819674D01*
X49201Y820214D01*
X50646Y821652D01*
G01X38493Y-241864D02*
Y-246864D01*
G01X37036Y-241864D02*
X39950D01*
G01X44860Y-246864D02*
X42326D01*
Y-241864D01*
X44860D01*
G01X43846Y-244281D02*
X42326D01*
G01X47426Y-241864D02*
Y-246864D01*
X49960D01*
G01X53793Y-247031D02*
X53666Y-246947D01*
Y-246781D01*
X53793Y-246697D01*
X53920Y-246781D01*
Y-246947D01*
X53793Y-247031D01*
G01Y-244781D02*
X53666Y-244697D01*
Y-244531D01*
X53793Y-244447D01*
X53920Y-244531D01*
Y-244697D01*
X53793Y-244781D01*
G01X58576Y-248531D02*
X57943Y-247697D01*
X57626Y-246864D01*
Y-243531D01*
X57943Y-242697D01*
X58576Y-241864D01*
G01X63993D02*
X63486Y-242031D01*
X63106Y-242447D01*
X62853Y-242947D01*
X62663Y-243614D01*
X62600Y-244364D01*
X62663Y-245114D01*
X62853Y-245781D01*
X63106Y-246281D01*
X63486Y-246697D01*
X63993Y-246864D01*
X64500Y-246697D01*
X64880Y-246281D01*
X65133Y-245781D01*
X65323Y-245114D01*
X65386Y-244364D01*
X65323Y-243614D01*
X65133Y-242947D01*
X64880Y-242447D01*
X64500Y-242031D01*
X63993Y-241864D01*
G01X67700Y-245864D02*
X68080Y-246447D01*
X68586Y-246781D01*
X69156Y-246864D01*
X69663Y-246781D01*
X70170Y-246364D01*
X70486Y-245864D01*
X70550Y-245364D01*
X70423Y-244781D01*
X69980Y-244364D01*
X69536Y-244197D01*
X68966D01*
G01X69536D02*
X69916Y-243947D01*
X70233Y-243531D01*
X70360Y-243031D01*
X70233Y-242531D01*
X69916Y-242114D01*
X69346Y-241864D01*
X68776Y-241947D01*
X68206Y-242281D01*
G01X74510Y-248531D02*
X75143Y-247697D01*
X75460Y-246864D01*
Y-243531D01*
X75143Y-242697D01*
X74510Y-241864D01*
G01X77900Y-245864D02*
X78280Y-246447D01*
X78786Y-246781D01*
X79356Y-246864D01*
X79863Y-246781D01*
X80370Y-246364D01*
X80686Y-245864D01*
X80750Y-245364D01*
X80623Y-244781D01*
X80180Y-244364D01*
X79736Y-244197D01*
X79166D01*
G01X79736D02*
X80116Y-243947D01*
X80433Y-243531D01*
X80560Y-243031D01*
X80433Y-242531D01*
X80116Y-242114D01*
X79546Y-241864D01*
X78976Y-241947D01*
X78406Y-242281D01*
G01X83190Y-242697D02*
X83570Y-242197D01*
X84013Y-241947D01*
X84520Y-241864D01*
X85153Y-242031D01*
X85596Y-242447D01*
X85723Y-242947D01*
X85660Y-243447D01*
X85406Y-243864D01*
X84140Y-244697D01*
X83570Y-245281D01*
X83190Y-246114D01*
X83063Y-246864D01*
X85723D01*
G01X89366D02*
X89493Y-245781D01*
X89683Y-244864D01*
X89936Y-244031D01*
X90253Y-243114D01*
X90760Y-241864D01*
X88226D01*
G01X93770Y-245197D02*
X95416D01*
G01X98490Y-242697D02*
X98870Y-242197D01*
X99313Y-241947D01*
X99820Y-241864D01*
X100453Y-242031D01*
X100896Y-242447D01*
X101023Y-242947D01*
X100960Y-243447D01*
X100706Y-243864D01*
X99440Y-244697D01*
X98870Y-245281D01*
X98490Y-246114D01*
X98363Y-246864D01*
X101023D01*
G01X103400Y-245864D02*
X103780Y-246447D01*
X104286Y-246781D01*
X104856Y-246864D01*
X105363Y-246781D01*
X105870Y-246364D01*
X106186Y-245864D01*
X106250Y-245364D01*
X106123Y-244781D01*
X105680Y-244364D01*
X105236Y-244197D01*
X104666D01*
G01X105236D02*
X105616Y-243947D01*
X105933Y-243531D01*
X106060Y-243031D01*
X105933Y-242531D01*
X105616Y-242114D01*
X105046Y-241864D01*
X104476Y-241947D01*
X103906Y-242281D01*
G01X110653Y-246864D02*
Y-241864D01*
X108310Y-245447D01*
X111476D01*
G01X113600Y-246114D02*
X113980Y-246531D01*
X114423Y-246781D01*
X114993Y-246864D01*
X115563Y-246697D01*
X116006Y-246364D01*
X116323Y-245781D01*
X116386Y-245114D01*
X116260Y-244447D01*
X115943Y-244031D01*
X115500Y-243697D01*
X115056Y-243614D01*
X114613Y-243697D01*
X114043Y-244031D01*
X114233Y-241864D01*
X115943D01*
G01X123990Y-246864D02*
Y-241864D01*
X126396D01*
G01X125510Y-244281D02*
X123990D01*
G01X128710Y-246864D02*
X130293Y-241864D01*
X131876Y-246864D01*
G01X131306Y-245114D02*
X129280D01*
G01X134063Y-246864D02*
X136723Y-241864D01*
G01X134063D02*
X136723Y-246864D01*
G01X140493Y-247031D02*
X140366Y-246947D01*
Y-246781D01*
X140493Y-246697D01*
X140620Y-246781D01*
Y-246947D01*
X140493Y-247031D01*
G01Y-244781D02*
X140366Y-244697D01*
Y-244531D01*
X140493Y-244447D01*
X140620Y-244531D01*
Y-244697D01*
X140493Y-244781D01*
G01X145276Y-248531D02*
X144643Y-247697D01*
X144326Y-246864D01*
Y-243531D01*
X144643Y-242697D01*
X145276Y-241864D01*
G01X150693D02*
X150186Y-242031D01*
X149806Y-242447D01*
X149553Y-242947D01*
X149363Y-243614D01*
X149300Y-244364D01*
X149363Y-245114D01*
X149553Y-245781D01*
X149806Y-246281D01*
X150186Y-246697D01*
X150693Y-246864D01*
X151200Y-246697D01*
X151580Y-246281D01*
X151833Y-245781D01*
X152023Y-245114D01*
X152086Y-244364D01*
X152023Y-243614D01*
X151833Y-242947D01*
X151580Y-242447D01*
X151200Y-242031D01*
X150693Y-241864D01*
G01X154400Y-245864D02*
X154780Y-246447D01*
X155286Y-246781D01*
X155856Y-246864D01*
X156363Y-246781D01*
X156870Y-246364D01*
X157186Y-245864D01*
X157250Y-245364D01*
X157123Y-244781D01*
X156680Y-244364D01*
X156236Y-244197D01*
X155666D01*
G01X156236D02*
X156616Y-243947D01*
X156933Y-243531D01*
X157060Y-243031D01*
X156933Y-242531D01*
X156616Y-242114D01*
X156046Y-241864D01*
X155476Y-241947D01*
X154906Y-242281D01*
G01X161210Y-248531D02*
X161843Y-247697D01*
X162160Y-246864D01*
Y-243531D01*
X161843Y-242697D01*
X161210Y-241864D01*
G01X164600Y-245864D02*
X164980Y-246447D01*
X165486Y-246781D01*
X166056Y-246864D01*
X166563Y-246781D01*
X167070Y-246364D01*
X167386Y-245864D01*
X167450Y-245364D01*
X167323Y-244781D01*
X166880Y-244364D01*
X166436Y-244197D01*
X165866D01*
G01X166436D02*
X166816Y-243947D01*
X167133Y-243531D01*
X167260Y-243031D01*
X167133Y-242531D01*
X166816Y-242114D01*
X166246Y-241864D01*
X165676Y-241947D01*
X165106Y-242281D01*
G01X170016Y-246281D02*
X170460Y-246697D01*
X170966Y-246864D01*
X171473Y-246697D01*
X171916Y-246197D01*
X172233Y-245447D01*
X172360Y-244697D01*
Y-243781D01*
X172233Y-243031D01*
X171916Y-242364D01*
X171536Y-242031D01*
X171093Y-241864D01*
X170586Y-242031D01*
X170206Y-242364D01*
X169953Y-242864D01*
X169826Y-243531D01*
X169953Y-244114D01*
X170270Y-244697D01*
X170650Y-245031D01*
X171093Y-245114D01*
X171600Y-244947D01*
X171980Y-244531D01*
X172360Y-243781D01*
G01X176066Y-246864D02*
X176193Y-245781D01*
X176383Y-244864D01*
X176636Y-244031D01*
X176953Y-243114D01*
X177460Y-241864D01*
X174926D01*
G01X180470Y-245197D02*
X182116D01*
G01X185000Y-245864D02*
X185380Y-246447D01*
X185886Y-246781D01*
X186456Y-246864D01*
X186963Y-246781D01*
X187470Y-246364D01*
X187786Y-245864D01*
X187850Y-245364D01*
X187723Y-244781D01*
X187280Y-244364D01*
X186836Y-244197D01*
X186266D01*
G01X186836D02*
X187216Y-243947D01*
X187533Y-243531D01*
X187660Y-243031D01*
X187533Y-242531D01*
X187216Y-242114D01*
X186646Y-241864D01*
X186076Y-241947D01*
X185506Y-242281D01*
G01X190290Y-244781D02*
X190733Y-244197D01*
X191113Y-243864D01*
X191620Y-243697D01*
X192063Y-243864D01*
X192380Y-244197D01*
X192633Y-244697D01*
X192696Y-245281D01*
X192633Y-245781D01*
X192380Y-246281D01*
X192000Y-246697D01*
X191556Y-246864D01*
X191050Y-246697D01*
X190606Y-246197D01*
X190353Y-245447D01*
X190290Y-244614D01*
X190416Y-243531D01*
X190606Y-242947D01*
X190923Y-242364D01*
X191366Y-241947D01*
X191810Y-241864D01*
X192253Y-242031D01*
X192570Y-242447D01*
G01X196593Y-246864D02*
Y-241864D01*
X195833Y-242864D01*
G01Y-246864D02*
X197353D01*
G01X202453D02*
Y-241864D01*
X200110Y-245447D01*
X203276D01*
G01X26493Y-176864D02*
Y-251864D01*
X526493D01*
Y-176864D01*
X26493D01*
G01X327026Y821652D02*
X50646D01*
G01X106999Y96614D02*
G02X89851I-8574J-10787D01*
G03X91339Y99696I-2449J3083D01*
G01Y105512D01*
G02X105512I7086J0D01*
G01Y99696D01*
G03X106999Y96614I3937J0D01*
G01D02*
G02X89851I-8574J-10787D01*
G03X91339Y99696I-2449J3083D01*
G01Y105512D01*
G02X105512I7086J0D01*
G01Y99696D01*
G03X106999Y96614I3937J0D01*
G01D02*
G02X89851I-8574J-10787D01*
G03X91339Y99696I-2449J3083D01*
G01Y105512D01*
G02X105512I7086J0D01*
G01Y99696D01*
G03X106999Y96614I3937J0D01*
G01D02*
G02X89851I-8574J-10787D01*
G03X91339Y99696I-2449J3083D01*
G01Y105512D01*
G02X105512I7086J0D01*
G01Y99696D01*
G03X106999Y96614I3937J0D01*
G01Y710787D02*
G02X89851I-8574J-10787D01*
G03X91339Y713869I-2449J3083D01*
G01Y719685D01*
G02X105512I7086J0D01*
G01Y713869D01*
G03X106999Y710787I3937J0D01*
G01D02*
G02X89851I-8574J-10787D01*
G03X91339Y713869I-2449J3083D01*
G01Y719685D01*
G02X105512I7086J0D01*
G01Y713869D01*
G03X106999Y710787I3937J0D01*
G01D02*
G02X89851I-8574J-10787D01*
G03X91339Y713869I-2449J3083D01*
G01Y719685D01*
G02X105512I7086J0D01*
G01Y713869D01*
G03X106999Y710787I3937J0D01*
G01D02*
G02X89851I-8574J-10787D01*
G03X91339Y713869I-2449J3083D01*
G01Y719685D01*
G02X105512I7086J0D01*
G01Y713869D01*
G03X106999Y710787I3937J0D01*
G01X221493Y-176864D02*
Y-251864D01*
G01Y-226864D02*
X324493D01*
Y-201864D01*
G01X221493D02*
X324493D01*
G01X332000Y-236864D02*
Y-231864D01*
X333266D01*
X333773Y-232114D01*
X334153Y-232447D01*
X334470Y-232947D01*
X334723Y-233531D01*
X334786Y-234364D01*
X334723Y-235197D01*
X334470Y-235781D01*
X334153Y-236281D01*
X333773Y-236614D01*
X333266Y-236864D01*
X332000D01*
G01X336910D02*
X338493Y-231864D01*
X340076Y-236864D01*
G01X339506Y-235114D02*
X337480D01*
G01X343593Y-231864D02*
Y-236864D01*
G01X342136Y-231864D02*
X345050D01*
G01X349960Y-236864D02*
X347426D01*
Y-231864D01*
X349960D01*
G01X348946Y-234281D02*
X347426D01*
G01X353793Y-237031D02*
X353666Y-236947D01*
Y-236781D01*
X353793Y-236697D01*
X353920Y-236781D01*
Y-236947D01*
X353793Y-237031D01*
G01Y-234781D02*
X353666Y-234697D01*
Y-234531D01*
X353793Y-234447D01*
X353920Y-234531D01*
Y-234697D01*
X353793Y-234781D01*
G01X326493Y-176864D02*
Y-251864D01*
G01X324493Y-176864D02*
Y-251864D01*
G01X326493Y-226864D02*
X526493D01*
G01X332126Y-211864D02*
Y-206864D01*
X333646D01*
X334153Y-207114D01*
X334533Y-207697D01*
X334660Y-208364D01*
X334533Y-209031D01*
X334216Y-209531D01*
X333646Y-209781D01*
X332126D01*
G01X337353Y-212031D02*
X339633Y-206864D01*
G01X342136Y-211864D02*
Y-206864D01*
X345050Y-211864D01*
Y-206864D01*
G01X348693Y-212031D02*
X348566Y-211947D01*
Y-211781D01*
X348693Y-211697D01*
X348820Y-211781D01*
Y-211947D01*
X348693Y-212031D01*
G01Y-209781D02*
X348566Y-209697D01*
Y-209531D01*
X348693Y-209447D01*
X348820Y-209531D01*
Y-209697D01*
X348693Y-209781D01*
G01X326493Y-201864D02*
X526493D01*
G01X332126Y-186864D02*
Y-181864D01*
X333646D01*
X334153Y-182114D01*
X334533Y-182697D01*
X334660Y-183364D01*
X334533Y-184031D01*
X334216Y-184531D01*
X333646Y-184781D01*
X332126D01*
G01X337226Y-186864D02*
Y-181864D01*
X338810D01*
X339316Y-182114D01*
X339633Y-182447D01*
X339760Y-183114D01*
X339633Y-183781D01*
X339253Y-184197D01*
X338810Y-184447D01*
X337226D01*
G01X338810D02*
X339760Y-186864D01*
G01X343593D02*
X343086Y-186781D01*
X342643Y-186447D01*
X342263Y-185947D01*
X342010Y-185364D01*
X341883Y-184697D01*
Y-184031D01*
X342010Y-183364D01*
X342263Y-182781D01*
X342643Y-182281D01*
X343086Y-181947D01*
X343593Y-181864D01*
X344100Y-181947D01*
X344543Y-182281D01*
X344923Y-182781D01*
X345176Y-183364D01*
X345303Y-184031D01*
Y-184697D01*
X345176Y-185364D01*
X344923Y-185947D01*
X344543Y-186447D01*
X344100Y-186781D01*
X343593Y-186864D01*
G01X347426Y-185864D02*
X347743Y-186364D01*
X348123Y-186697D01*
X348566Y-186864D01*
X349073Y-186697D01*
X349453Y-186364D01*
X349833Y-185864D01*
X349960Y-185197D01*
Y-181864D01*
G01X355060Y-186864D02*
X352526D01*
Y-181864D01*
X355060D01*
G01X354046Y-184281D02*
X352526D01*
G01X360286Y-182281D02*
X359906Y-182031D01*
X359463Y-181864D01*
X358956D01*
X358386Y-182114D01*
X357943Y-182531D01*
X357626Y-183031D01*
X357373Y-183864D01*
X357310Y-184614D01*
X357436Y-185364D01*
X357626Y-185864D01*
X358006Y-186364D01*
X358450Y-186697D01*
X358893Y-186864D01*
X359336D01*
X359780Y-186697D01*
X360160Y-186447D01*
X360476Y-186114D01*
G01X363993Y-181864D02*
Y-186864D01*
G01X362536Y-181864D02*
X365450D01*
G01X369093Y-187031D02*
X368966Y-186947D01*
Y-186781D01*
X369093Y-186697D01*
X369220Y-186781D01*
Y-186947D01*
X369093Y-187031D01*
G01Y-184781D02*
X368966Y-184697D01*
Y-184531D01*
X369093Y-184447D01*
X369220Y-184531D01*
Y-184697D01*
X369093Y-184781D01*
G01X327026Y821652D02*
X328915Y819773D01*
X328976Y819712D01*
Y792323D01*
G03X336457I3740J0D01*
G01Y819673D01*
X336476Y819692D01*
X338446Y821652D01*
G01X378606D02*
X338446D01*
G01X378606D02*
X380551Y819707D01*
Y741142D01*
G01X406929D02*
Y819675D01*
X406946Y819692D01*
X408916Y821652D01*
G01X685296D02*
X408916D01*
G01X447126Y-236864D02*
Y-231864D01*
X448710D01*
X449216Y-232114D01*
X449533Y-232447D01*
X449660Y-233114D01*
X449533Y-233781D01*
X449153Y-234197D01*
X448710Y-234447D01*
X447126D01*
G01X448710D02*
X449660Y-236864D01*
G01X454760D02*
X452226D01*
Y-231864D01*
X454760D01*
G01X453746Y-234281D02*
X452226D01*
G01X457010Y-231864D02*
X458593Y-236864D01*
X460176Y-231864D01*
G01X463693Y-237031D02*
X463566Y-236947D01*
Y-236781D01*
X463693Y-236697D01*
X463820Y-236781D01*
Y-236947D01*
X463693Y-237031D01*
G01Y-234781D02*
X463566Y-234697D01*
Y-234531D01*
X463693Y-234447D01*
X463820Y-234531D01*
Y-234697D01*
X463693Y-234781D01*
G01X441493Y-226864D02*
Y-251864D01*
G01X490493Y-226864D02*
Y-251864D01*
G01X697857Y96166D02*
G02X680096I-8880J-10536D01*
G03X681496Y99177I-2537J3011D01*
G01Y105315D01*
G02X696457I7481J0D01*
G01Y99177D01*
G03X697857Y96166I3937J0D01*
G01D02*
G02X680096I-8880J-10536D01*
G03X681496Y99177I-2537J3011D01*
G01Y105315D01*
G02X696457I7481J0D01*
G01Y99177D01*
G03X697857Y96166I3937J0D01*
G01D02*
G02X680096I-8880J-10536D01*
G03X681496Y99177I-2537J3011D01*
G01Y105315D01*
G02X696457I7481J0D01*
G01Y99177D01*
G03X697857Y96166I3937J0D01*
G01D02*
G02X680096I-8880J-10536D01*
G03X681496Y99177I-2537J3011D01*
G01Y105315D01*
G02X696457I7481J0D01*
G01Y99177D01*
G03X697857Y96166I3937J0D01*
G01X681496Y713350D02*
Y719488D01*
G02X696457I7481J0D01*
G01Y713350D01*
G03X697857Y710340I3937J0D01*
G02X680096I-8880J-10537D01*
G03X681496Y713350I-2537J3011D01*
G01D02*
Y719488D01*
G02X696457I7481J0D01*
G01Y713350D01*
G03X697857Y710340I3937J0D01*
G02X680096I-8880J-10537D01*
G03X681496Y713350I-2537J3011D01*
G01D02*
Y719488D01*
G02X696457I7481J0D01*
G01Y713350D01*
G03X697857Y710340I3937J0D01*
G02X680096I-8880J-10537D01*
G03X681496Y713350I-2537J3011D01*
G01D02*
Y719488D01*
G02X696457I7481J0D01*
G01Y713350D01*
G03X697857Y710340I3937J0D01*
G02X680096I-8880J-10537D01*
G03X681496Y713350I-2537J3011D01*
G01X696716Y821652D02*
X694746Y819692D01*
X694724Y819670D01*
Y792323D01*
G02X687244I-3740J0D01*
G01Y819710D01*
X686388Y820566D01*
X685296Y821652D01*
G01X736866D02*
X696716D01*
G01X-1043962Y-705877D02*
Y2342823D01*
X2300638D01*
Y-705877D01*
X-1043962D01*
G01X-299435Y1041738D02*
Y1044838D01*
G01X-301045D02*
Y1041738D01*
G01Y1043288D02*
X-299435D01*
G01X-303340Y1041738D02*
Y1044838D01*
X-302880Y1044218D01*
G01Y1041738D02*
X-303800D01*
G01X-306440Y1044838D02*
X-306133Y1044735D01*
X-305903Y1044476D01*
X-305750Y1044166D01*
X-305635Y1043753D01*
X-305597Y1043288D01*
X-305635Y1042823D01*
X-305750Y1042410D01*
X-305903Y1042100D01*
X-306133Y1041841D01*
X-306440Y1041738D01*
X-306747Y1041841D01*
X-306977Y1042100D01*
X-307130Y1042410D01*
X-307245Y1042823D01*
X-307283Y1043288D01*
X-307245Y1043753D01*
X-307130Y1044166D01*
X-306977Y1044476D01*
X-306747Y1044735D01*
X-306440Y1044838D01*
G01X-308390Y1040705D02*
X-310690D01*
G01X-311758Y1041738D02*
Y1044838D01*
X-313522Y1041738D01*
Y1044838D01*
G01X-314897D02*
Y1042616D01*
X-315050Y1042151D01*
X-315357Y1041841D01*
X-315740Y1041738D01*
X-316123Y1041841D01*
X-316430Y1042151D01*
X-316583Y1042616D01*
Y1044838D01*
G01X-318840D02*
Y1041738D01*
G01X-317958Y1044838D02*
X-319722D01*
G01X-281115Y1050258D02*
Y1053358D01*
G01X-282725D02*
Y1050258D01*
G01Y1051808D02*
X-281115D01*
G01X-285020Y1050258D02*
Y1053358D01*
X-284560Y1052738D01*
G01Y1050258D02*
X-285480D01*
G01X-288120Y1053358D02*
X-287813Y1053255D01*
X-287583Y1052996D01*
X-287430Y1052686D01*
X-287315Y1052273D01*
X-287277Y1051808D01*
X-287315Y1051343D01*
X-287430Y1050930D01*
X-287583Y1050620D01*
X-287813Y1050361D01*
X-288120Y1050258D01*
X-288427Y1050361D01*
X-288657Y1050620D01*
X-288810Y1050930D01*
X-288925Y1051343D01*
X-288963Y1051808D01*
X-288925Y1052273D01*
X-288810Y1052686D01*
X-288657Y1052996D01*
X-288427Y1053255D01*
X-288120Y1053358D01*
G01X-290070Y1049225D02*
X-292370D01*
G01X-293515Y1050671D02*
X-293822Y1050413D01*
X-294167Y1050258D01*
X-294473D01*
X-294780Y1050413D01*
X-295010Y1050671D01*
X-295125Y1051033D01*
X-295048Y1051395D01*
X-294857Y1051705D01*
X-294512Y1051911D01*
X-294052Y1052015D01*
X-293783Y1052221D01*
X-293668Y1052583D01*
X-293745Y1052945D01*
X-293937Y1053203D01*
X-294205Y1053358D01*
X-294473D01*
X-294742Y1053255D01*
X-294972Y1052996D01*
G01X-296653Y1050258D02*
Y1053358D01*
X-297612D01*
X-297918Y1053203D01*
X-298110Y1052996D01*
X-298187Y1052583D01*
X-298110Y1052170D01*
X-297880Y1051911D01*
X-297612Y1051756D01*
X-296653D01*
G01X-297612D02*
X-298187Y1050258D01*
G01X-299370Y1053358D02*
X-299907Y1050258D01*
X-300520Y1053358D01*
X-301133Y1050258D01*
X-301670Y1053358D01*
G01X-245077Y1044721D02*
X-245230Y1044876D01*
X-245345Y1045135D01*
X-245422Y1045496D01*
X-245345Y1045806D01*
X-245192Y1046013D01*
X-244923Y1046168D01*
X-243888D01*
Y1043068D01*
X-245153D01*
X-245422Y1043275D01*
X-245575Y1043585D01*
X-245652Y1043946D01*
X-245575Y1044308D01*
X-245345Y1044618D01*
X-245077Y1044721D01*
X-243888D01*
G01X-247870Y1046168D02*
Y1043068D01*
G01X-246988Y1046168D02*
X-248752D01*
G01X-250970Y1043068D02*
Y1046168D01*
X-250510Y1045548D01*
G01Y1043068D02*
X-251430D01*
G01X-252920Y1042035D02*
X-255220D01*
G01X-257477Y1044721D02*
X-257630Y1044876D01*
X-257745Y1045135D01*
X-257822Y1045496D01*
X-257745Y1045806D01*
X-257592Y1046013D01*
X-257323Y1046168D01*
X-256288D01*
Y1043068D01*
X-257553D01*
X-257822Y1043275D01*
X-257975Y1043585D01*
X-258052Y1043946D01*
X-257975Y1044308D01*
X-257745Y1044618D01*
X-257477Y1044721D01*
X-256288D01*
G01X-259312Y1043068D02*
X-260270Y1046168D01*
X-261228Y1043068D01*
G01X-260883Y1044153D02*
X-259657D01*
G01X-263370Y1046168D02*
Y1043068D01*
G01X-262488Y1046168D02*
X-264252D01*
G01X-266470D02*
Y1043068D01*
G01X-265588Y1046168D02*
X-267352D01*
G01X-270337Y1043068D02*
X-268803D01*
Y1046168D01*
X-270337D01*
G01X-269723Y1044670D02*
X-268803D01*
G01X-271903Y1043068D02*
Y1046168D01*
X-272862D01*
X-273168Y1046013D01*
X-273360Y1045806D01*
X-273437Y1045393D01*
X-273360Y1044980D01*
X-273130Y1044721D01*
X-272862Y1044566D01*
X-271903D01*
G01X-272862D02*
X-273437Y1043068D01*
G01X-275770D02*
Y1044463D01*
X-275003Y1046168D01*
G01X-276537D02*
X-275770Y1044463D01*
G01X-278870Y1043068D02*
Y1046168D01*
X-278410Y1045548D01*
G01Y1043068D02*
X-279330D01*
G01X-269695Y1048716D02*
Y1051816D01*
X-270615D01*
X-270922Y1051661D01*
X-271152Y1051299D01*
X-271229Y1050886D01*
X-271152Y1050473D01*
X-270960Y1050163D01*
X-270615Y1050008D01*
X-269695D01*
G01X-274405Y1051558D02*
X-274175Y1051713D01*
X-273907Y1051816D01*
X-273600D01*
X-273255Y1051661D01*
X-272987Y1051403D01*
X-272795Y1051093D01*
X-272642Y1050576D01*
X-272604Y1050111D01*
X-272680Y1049646D01*
X-272795Y1049336D01*
X-273025Y1049026D01*
X-273294Y1048819D01*
X-273562Y1048716D01*
X-273830D01*
X-274099Y1048819D01*
X-274329Y1048974D01*
X-274520Y1049181D01*
G01X-276969Y1050369D02*
X-277122Y1050524D01*
X-277237Y1050783D01*
X-277314Y1051144D01*
X-277237Y1051454D01*
X-277084Y1051661D01*
X-276815Y1051816D01*
X-275780D01*
Y1048716D01*
X-277045D01*
X-277314Y1048923D01*
X-277467Y1049233D01*
X-277544Y1049594D01*
X-277467Y1049956D01*
X-277237Y1050266D01*
X-276969Y1050369D01*
X-275780D01*
G01X-33558Y255948D02*
X-33750Y255638D01*
X-33980Y255431D01*
X-34248Y255328D01*
X-34555Y255431D01*
X-34785Y255638D01*
X-35015Y255948D01*
X-35092Y256361D01*
Y258428D01*
G01X-36697Y257911D02*
X-36927Y258221D01*
X-37195Y258376D01*
X-37502Y258428D01*
X-37885Y258325D01*
X-38153Y258066D01*
X-38230Y257756D01*
X-38192Y257446D01*
X-38038Y257188D01*
X-37272Y256671D01*
X-36927Y256310D01*
X-36697Y255793D01*
X-36620Y255328D01*
X-38230D01*
G01X-39873Y255690D02*
X-40142Y255431D01*
X-40448Y255328D01*
X-40755Y255431D01*
X-41023Y255741D01*
X-41215Y256206D01*
X-41292Y256671D01*
Y257240D01*
X-41215Y257705D01*
X-41023Y258118D01*
X-40793Y258325D01*
X-40525Y258428D01*
X-40218Y258325D01*
X-39988Y258118D01*
X-39835Y257808D01*
X-39758Y257395D01*
X-39835Y257033D01*
X-40027Y256671D01*
X-40257Y256465D01*
X-40525Y256413D01*
X-40832Y256516D01*
X-41062Y256775D01*
X-41292Y257240D01*
G01X5450Y108500D02*
Y111600D01*
X5910Y110980D01*
G01Y108500D02*
X4990D01*
G01X15912Y320223D02*
Y323323D01*
X17330Y321101D01*
X15414D01*
G01X17952Y337787D02*
X17722Y337425D01*
X17416Y337219D01*
X17071Y337167D01*
X16764Y337219D01*
X16457Y337477D01*
X16266Y337787D01*
X16227Y338097D01*
X16304Y338459D01*
X16572Y338717D01*
X16841Y338820D01*
X17186D01*
G01X16841D02*
X16611Y338975D01*
X16419Y339234D01*
X16342Y339544D01*
X16419Y339854D01*
X16611Y340112D01*
X16956Y340267D01*
X17301Y340215D01*
X17646Y340009D01*
G01X37198Y-238524D02*
X37825Y-239049D01*
X38530Y-239364D01*
X39156D01*
X39783Y-239049D01*
X40253Y-238524D01*
X40488Y-237789D01*
X40331Y-237054D01*
X39940Y-236424D01*
X39235Y-236004D01*
X38295Y-235794D01*
X37746Y-235374D01*
X37511Y-234639D01*
X37668Y-233904D01*
X38060Y-233379D01*
X38608Y-233064D01*
X39156D01*
X39705Y-233274D01*
X40175Y-233799D01*
G01X43498Y-239364D02*
Y-233064D01*
G01X46788D02*
Y-239364D01*
G01Y-236214D02*
X43498D01*
G01X50503Y-233064D02*
X52383D01*
G01X51443D02*
Y-239364D01*
G01X50503D02*
X52383D01*
G01X59310D02*
X56176D01*
Y-233064D01*
X59310D01*
G01X58056Y-236109D02*
X56176D01*
G01X62241Y-239364D02*
Y-233064D01*
X65845Y-239364D01*
Y-233064D01*
G01X70186Y-240519D02*
X70500Y-239154D01*
G01X76643Y-233064D02*
Y-239364D01*
G01X74841Y-233064D02*
X78445D01*
G01X80985Y-239364D02*
X82943Y-233064D01*
X84901Y-239364D01*
G01X84196Y-237159D02*
X81690D01*
G01X88303Y-233064D02*
X90183D01*
G01X89243D02*
Y-239364D01*
G01X88303D02*
X90183D01*
G01X93193Y-233064D02*
X94290Y-239364D01*
X95543Y-233064D01*
X96796Y-239364D01*
X97893Y-233064D01*
G01X99885Y-239364D02*
X101843Y-233064D01*
X103801Y-239364D01*
G01X103096Y-237159D02*
X100590D01*
G01X106341Y-239364D02*
Y-233064D01*
X109945Y-239364D01*
Y-233064D01*
G01X119176Y-239364D02*
Y-233064D01*
X121135D01*
X121761Y-233379D01*
X122153Y-233799D01*
X122310Y-234639D01*
X122153Y-235479D01*
X121683Y-236004D01*
X121135Y-236319D01*
X119176D01*
G01X121135D02*
X122310Y-239364D01*
G01X127043Y-239574D02*
X126886Y-239469D01*
Y-239259D01*
X127043Y-239154D01*
X127200Y-239259D01*
Y-239469D01*
X127043Y-239574D01*
G01X133343Y-239364D02*
X132716Y-239259D01*
X132168Y-238839D01*
X131698Y-238209D01*
X131385Y-237474D01*
X131228Y-236634D01*
Y-235794D01*
X131385Y-234954D01*
X131698Y-234219D01*
X132168Y-233589D01*
X132716Y-233169D01*
X133343Y-233064D01*
X133970Y-233169D01*
X134518Y-233589D01*
X134988Y-234219D01*
X135301Y-234954D01*
X135458Y-235794D01*
Y-236634D01*
X135301Y-237474D01*
X134988Y-238209D01*
X134518Y-238839D01*
X133970Y-239259D01*
X133343Y-239364D01*
G01X139643Y-239574D02*
X139486Y-239469D01*
Y-239259D01*
X139643Y-239154D01*
X139800Y-239259D01*
Y-239469D01*
X139643Y-239574D01*
G01X147666Y-233589D02*
X147196Y-233274D01*
X146648Y-233064D01*
X146021D01*
X145316Y-233379D01*
X144768Y-233904D01*
X144376Y-234534D01*
X144063Y-235584D01*
X143985Y-236529D01*
X144141Y-237474D01*
X144376Y-238104D01*
X144846Y-238734D01*
X145395Y-239154D01*
X145943Y-239364D01*
X146491D01*
X147040Y-239154D01*
X147510Y-238839D01*
X147901Y-238419D01*
G01X152243Y-239574D02*
X152086Y-239469D01*
Y-239259D01*
X152243Y-239154D01*
X152400Y-239259D01*
Y-239469D01*
X152243Y-239574D01*
G01X37120Y-229364D02*
Y-223064D01*
G01X40096D02*
X37120Y-226949D01*
G01X40566Y-229364D02*
X38451Y-225164D01*
G01X43420Y-223064D02*
Y-227579D01*
X43733Y-228524D01*
X44360Y-229154D01*
X45143Y-229364D01*
X45926Y-229154D01*
X46553Y-228524D01*
X46866Y-227579D01*
Y-223064D01*
G01X53010Y-229364D02*
X49876D01*
Y-223064D01*
X53010D01*
G01X51756Y-226109D02*
X49876D01*
G01X56803Y-223064D02*
X58683D01*
G01X57743D02*
Y-229364D01*
G01X56803D02*
X58683D01*
G01X68698Y-228524D02*
X69325Y-229049D01*
X70030Y-229364D01*
X70656D01*
X71283Y-229049D01*
X71753Y-228524D01*
X71988Y-227789D01*
X71831Y-227054D01*
X71440Y-226424D01*
X70735Y-226004D01*
X69795Y-225794D01*
X69246Y-225374D01*
X69011Y-224639D01*
X69168Y-223904D01*
X69560Y-223379D01*
X70108Y-223064D01*
X70656D01*
X71205Y-223274D01*
X71675Y-223799D01*
G01X74998Y-229364D02*
Y-223064D01*
G01X78288D02*
Y-229364D01*
G01Y-226214D02*
X74998D01*
G01X80985Y-229364D02*
X82943Y-223064D01*
X84901Y-229364D01*
G01X84196Y-227159D02*
X81690D01*
G01X87441Y-229364D02*
Y-223064D01*
X91045Y-229364D01*
Y-223064D01*
G01X100198Y-229364D02*
Y-223064D01*
G01X103488D02*
Y-229364D01*
G01Y-226214D02*
X100198D01*
G01X106498Y-228524D02*
X107125Y-229049D01*
X107830Y-229364D01*
X108456D01*
X109083Y-229049D01*
X109553Y-228524D01*
X109788Y-227789D01*
X109631Y-227054D01*
X109240Y-226424D01*
X108535Y-226004D01*
X107595Y-225794D01*
X107046Y-225374D01*
X106811Y-224639D01*
X106968Y-223904D01*
X107360Y-223379D01*
X107908Y-223064D01*
X108456D01*
X109005Y-223274D01*
X109475Y-223799D01*
G01X113503Y-223064D02*
X115383D01*
G01X114443D02*
Y-229364D01*
G01X113503D02*
X115383D01*
G01X118785D02*
X120743Y-223064D01*
X122701Y-229364D01*
G01X121996Y-227159D02*
X119490D01*
G01X125241Y-229364D02*
Y-223064D01*
X128845Y-229364D01*
Y-223064D01*
G01X133813Y-226214D02*
X135380D01*
Y-228104D01*
X134910Y-228734D01*
X134361Y-229154D01*
X133578Y-229364D01*
X132795Y-229154D01*
X132246Y-228734D01*
X131776Y-228104D01*
X131463Y-227369D01*
X131306Y-226529D01*
Y-225794D01*
X131463Y-225164D01*
X131776Y-224429D01*
X132246Y-223799D01*
X132716Y-223379D01*
X133343Y-223064D01*
X133891D01*
X134518Y-223274D01*
X134988Y-223694D01*
G01X139486Y-230519D02*
X139800Y-229154D01*
G01X145943Y-223064D02*
Y-229364D01*
G01X144141Y-223064D02*
X147745D01*
G01X150285Y-229364D02*
X152243Y-223064D01*
X154201Y-229364D01*
G01X153496Y-227159D02*
X150990D01*
G01X158543Y-229364D02*
X157916Y-229259D01*
X157368Y-228839D01*
X156898Y-228209D01*
X156585Y-227474D01*
X156428Y-226634D01*
Y-225794D01*
X156585Y-224954D01*
X156898Y-224219D01*
X157368Y-223589D01*
X157916Y-223169D01*
X158543Y-223064D01*
X159170Y-223169D01*
X159718Y-223589D01*
X160188Y-224219D01*
X160501Y-224954D01*
X160658Y-225794D01*
Y-226634D01*
X160501Y-227474D01*
X160188Y-228209D01*
X159718Y-228839D01*
X159170Y-229259D01*
X158543Y-229364D01*
G01X171143D02*
Y-226529D01*
X169576Y-223064D01*
G01X172710D02*
X171143Y-226529D01*
G01X175720Y-223064D02*
Y-227579D01*
X176033Y-228524D01*
X176660Y-229154D01*
X177443Y-229364D01*
X178226Y-229154D01*
X178853Y-228524D01*
X179166Y-227579D01*
Y-223064D01*
G01X181785Y-229364D02*
X183743Y-223064D01*
X185701Y-229364D01*
G01X184996Y-227159D02*
X182490D01*
G01X188241Y-229364D02*
Y-223064D01*
X191845Y-229364D01*
Y-223064D01*
G01X37041Y-219364D02*
Y-213064D01*
X40645Y-219364D01*
Y-213064D01*
G01X45143Y-219364D02*
X44516Y-219259D01*
X43968Y-218839D01*
X43498Y-218209D01*
X43185Y-217474D01*
X43028Y-216634D01*
Y-215794D01*
X43185Y-214954D01*
X43498Y-214219D01*
X43968Y-213589D01*
X44516Y-213169D01*
X45143Y-213064D01*
X45770Y-213169D01*
X46318Y-213589D01*
X46788Y-214219D01*
X47101Y-214954D01*
X47258Y-215794D01*
Y-216634D01*
X47101Y-217474D01*
X46788Y-218209D01*
X46318Y-218839D01*
X45770Y-219259D01*
X45143Y-219364D01*
G01X51443Y-219574D02*
X51286Y-219469D01*
Y-219259D01*
X51443Y-219154D01*
X51600Y-219259D01*
Y-219469D01*
X51443Y-219574D01*
G01X57743Y-219364D02*
Y-213064D01*
X56803Y-214324D01*
G01Y-219364D02*
X58683D01*
G01X64043D02*
X64591Y-219259D01*
X65218Y-218944D01*
X65610Y-218419D01*
X65766Y-217684D01*
X65610Y-216949D01*
X65140Y-216319D01*
X64435Y-216004D01*
X63651D01*
X63181Y-215794D01*
X62790Y-215269D01*
X62633Y-214534D01*
X62868Y-213799D01*
X63416Y-213274D01*
X64043Y-213064D01*
X64670Y-213274D01*
X65218Y-213799D01*
X65453Y-214534D01*
X65296Y-215269D01*
X64905Y-215794D01*
X64435Y-216004D01*
X63651D01*
X62946Y-216319D01*
X62476Y-216949D01*
X62320Y-217684D01*
X62476Y-218419D01*
X62868Y-218944D01*
X63495Y-219259D01*
X64043Y-219364D01*
G01X70343D02*
X70891Y-219259D01*
X71518Y-218944D01*
X71910Y-218419D01*
X72066Y-217684D01*
X71910Y-216949D01*
X71440Y-216319D01*
X70735Y-216004D01*
X69951D01*
X69481Y-215794D01*
X69090Y-215269D01*
X68933Y-214534D01*
X69168Y-213799D01*
X69716Y-213274D01*
X70343Y-213064D01*
X70970Y-213274D01*
X71518Y-213799D01*
X71753Y-214534D01*
X71596Y-215269D01*
X71205Y-215794D01*
X70735Y-216004D01*
X69951D01*
X69246Y-216319D01*
X68776Y-216949D01*
X68620Y-217684D01*
X68776Y-218419D01*
X69168Y-218944D01*
X69795Y-219259D01*
X70343Y-219364D01*
G01X76486Y-220519D02*
X76800Y-219154D01*
G01X80593Y-213064D02*
X81690Y-219364D01*
X82943Y-213064D01*
X84196Y-219364D01*
X85293Y-213064D01*
G01X90810Y-219364D02*
X87676D01*
Y-213064D01*
X90810D01*
G01X89556Y-216109D02*
X87676D01*
G01X93741Y-219364D02*
Y-213064D01*
X97345Y-219364D01*
Y-213064D01*
G01X106498Y-219364D02*
Y-213064D01*
G01X109788D02*
Y-219364D01*
G01Y-216214D02*
X106498D01*
G01X112093Y-213064D02*
X113190Y-219364D01*
X114443Y-213064D01*
X115696Y-219364D01*
X116793Y-213064D01*
G01X118785Y-219364D02*
X120743Y-213064D01*
X122701Y-219364D01*
G01X121996Y-217159D02*
X119490D01*
G01X131855Y-214114D02*
X132325Y-213484D01*
X132873Y-213169D01*
X133500Y-213064D01*
X134283Y-213274D01*
X134831Y-213799D01*
X134988Y-214429D01*
X134910Y-215059D01*
X134596Y-215584D01*
X133030Y-216634D01*
X132325Y-217369D01*
X131855Y-218419D01*
X131698Y-219364D01*
X134988D01*
G01X137841D02*
Y-213064D01*
X141445Y-219364D01*
Y-213064D01*
G01X144220Y-219364D02*
Y-213064D01*
X145786D01*
X146413Y-213379D01*
X146883Y-213799D01*
X147275Y-214429D01*
X147588Y-215164D01*
X147666Y-216214D01*
X147588Y-217264D01*
X147275Y-217999D01*
X146883Y-218629D01*
X146413Y-219049D01*
X145786Y-219364D01*
X144220D01*
G01X156976D02*
Y-213064D01*
X158935D01*
X159561Y-213379D01*
X159953Y-213799D01*
X160110Y-214639D01*
X159953Y-215479D01*
X159483Y-216004D01*
X158935Y-216319D01*
X156976D01*
G01X158935D02*
X160110Y-219364D01*
G01X163120D02*
Y-213064D01*
X164686D01*
X165313Y-213379D01*
X165783Y-213799D01*
X166175Y-214429D01*
X166488Y-215164D01*
X166566Y-216214D01*
X166488Y-217264D01*
X166175Y-217999D01*
X165783Y-218629D01*
X165313Y-219049D01*
X164686Y-219364D01*
X163120D01*
G01X171143Y-219574D02*
X170986Y-219469D01*
Y-219259D01*
X171143Y-219154D01*
X171300Y-219259D01*
Y-219469D01*
X171143Y-219574D01*
G01X26478Y111483D02*
X26248Y111793D01*
X25980Y111948D01*
X25673Y112000D01*
X25290Y111897D01*
X25022Y111638D01*
X24945Y111328D01*
X24983Y111018D01*
X25137Y110760D01*
X25903Y110243D01*
X26248Y109882D01*
X26478Y109365D01*
X26555Y108900D01*
X24945D01*
G01X37083Y174317D02*
Y177417D01*
X37543Y176797D01*
G01Y174317D02*
X36623D01*
G01X33983D02*
Y177417D01*
X34443Y176797D01*
G01Y174317D02*
X33523D01*
G01X37143Y220522D02*
Y223622D01*
X37603Y223002D01*
G01Y220522D02*
X36683D01*
G01X34886Y220987D02*
X34656Y220729D01*
X34388Y220574D01*
X34043Y220522D01*
X33698Y220625D01*
X33430Y220832D01*
X33238Y221194D01*
X33200Y221607D01*
X33276Y222020D01*
X33468Y222279D01*
X33736Y222485D01*
X34005Y222537D01*
X34273Y222485D01*
X34618Y222279D01*
X34503Y223622D01*
X33468D01*
G01X33810Y276070D02*
Y262390D01*
G01D02*
X66050D01*
G01X33810Y312300D02*
Y279650D01*
G01X44103Y284092D02*
X44333Y284247D01*
X44601Y284350D01*
X44908D01*
X45253Y284195D01*
X45521Y283937D01*
X45713Y283627D01*
X45866Y283110D01*
X45904Y282645D01*
X45828Y282180D01*
X45713Y281870D01*
X45483Y281560D01*
X45214Y281353D01*
X44946Y281250D01*
X44678D01*
X44409Y281353D01*
X44179Y281508D01*
X43988Y281715D01*
G01X42574Y283833D02*
X42344Y284143D01*
X42076Y284298D01*
X41769Y284350D01*
X41386Y284247D01*
X41118Y283988D01*
X41041Y283678D01*
X41079Y283368D01*
X41233Y283110D01*
X41999Y282593D01*
X42344Y282232D01*
X42574Y281715D01*
X42651Y281250D01*
X41041D01*
G01X38746D02*
X38478Y281302D01*
X38171Y281457D01*
X37979Y281715D01*
X37903Y282077D01*
X37979Y282438D01*
X38209Y282748D01*
X38554Y282903D01*
X38938D01*
X39168Y283007D01*
X39359Y283265D01*
X39436Y283627D01*
X39321Y283988D01*
X39053Y284247D01*
X38746Y284350D01*
X38439Y284247D01*
X38171Y283988D01*
X38056Y283627D01*
X38133Y283265D01*
X38324Y283007D01*
X38554Y282903D01*
X38938D01*
X39283Y282748D01*
X39513Y282438D01*
X39589Y282077D01*
X39513Y281715D01*
X39321Y281457D01*
X39014Y281302D01*
X38746Y281250D01*
G01X36374Y282542D02*
X36106Y282903D01*
X35876Y283110D01*
X35569Y283213D01*
X35301Y283110D01*
X35109Y282903D01*
X34956Y282593D01*
X34918Y282232D01*
X34956Y281922D01*
X35109Y281612D01*
X35339Y281353D01*
X35608Y281250D01*
X35914Y281353D01*
X36183Y281663D01*
X36336Y282128D01*
X36374Y282645D01*
X36298Y283317D01*
X36183Y283678D01*
X35991Y284040D01*
X35723Y284298D01*
X35454Y284350D01*
X35186Y284247D01*
X34994Y283988D01*
G01X38239Y271121D02*
X35139D01*
Y272655D01*
G01Y274988D02*
X38239D01*
X37619Y274528D01*
G01X35139D02*
Y275448D01*
G01X35501Y277436D02*
X35242Y277705D01*
X35139Y278011D01*
X35242Y278318D01*
X35552Y278586D01*
X36017Y278778D01*
X36482Y278855D01*
X37051D01*
X37516Y278778D01*
X37929Y278586D01*
X38136Y278356D01*
X38239Y278088D01*
X38136Y277781D01*
X37929Y277551D01*
X37619Y277398D01*
X37206Y277321D01*
X36844Y277398D01*
X36482Y277590D01*
X36276Y277820D01*
X36224Y278088D01*
X36327Y278395D01*
X36586Y278625D01*
X37051Y278855D01*
G01X69170Y312300D02*
X33810D01*
G01X41405Y487518D02*
Y490618D01*
X40485D01*
X40178Y490463D01*
X39948Y490101D01*
X39871Y489688D01*
X39948Y489275D01*
X40140Y488965D01*
X40485Y488810D01*
X41405D01*
G01X36695Y490360D02*
X36925Y490515D01*
X37193Y490618D01*
X37500D01*
X37845Y490463D01*
X38113Y490205D01*
X38305Y489895D01*
X38458Y489378D01*
X38496Y488913D01*
X38420Y488448D01*
X38305Y488138D01*
X38075Y487828D01*
X37806Y487621D01*
X37538Y487518D01*
X37270D01*
X37001Y487621D01*
X36771Y487776D01*
X36580Y487983D01*
G01X35281D02*
X35051Y487725D01*
X34783Y487570D01*
X34438Y487518D01*
X34093Y487621D01*
X33825Y487828D01*
X33633Y488190D01*
X33595Y488603D01*
X33671Y489016D01*
X33863Y489275D01*
X34131Y489481D01*
X34400Y489533D01*
X34668Y489481D01*
X35013Y489275D01*
X34898Y490618D01*
X33863D01*
G01X31415Y487518D02*
X31338Y488190D01*
X31223Y488758D01*
X31070Y489275D01*
X30878Y489843D01*
X30571Y490618D01*
X32105D01*
G01X45441Y493682D02*
Y496782D01*
X44521D01*
X44214Y496627D01*
X43984Y496265D01*
X43907Y495852D01*
X43984Y495439D01*
X44176Y495129D01*
X44521Y494974D01*
X45441D01*
G01X40731Y496524D02*
X40961Y496679D01*
X41229Y496782D01*
X41536D01*
X41881Y496627D01*
X42149Y496369D01*
X42341Y496059D01*
X42494Y495542D01*
X42532Y495077D01*
X42456Y494612D01*
X42341Y494302D01*
X42111Y493992D01*
X41842Y493785D01*
X41574Y493682D01*
X41306D01*
X41037Y493785D01*
X40807Y493940D01*
X40616Y494147D01*
G01X39317D02*
X39087Y493889D01*
X38819Y493734D01*
X38474Y493682D01*
X38129Y493785D01*
X37861Y493992D01*
X37669Y494354D01*
X37631Y494767D01*
X37707Y495180D01*
X37899Y495439D01*
X38167Y495645D01*
X38436Y495697D01*
X38704Y495645D01*
X39049Y495439D01*
X38934Y496782D01*
X37899D01*
G01X34914Y493682D02*
Y496782D01*
X36332Y494560D01*
X34416D01*
G01X61143Y-206664D02*
X58623Y-206247D01*
X56418Y-204581D01*
X54528Y-202081D01*
X53268Y-199164D01*
X52638Y-195831D01*
Y-192497D01*
X53268Y-189164D01*
X54528Y-186247D01*
X56418Y-183748D01*
X58623Y-182081D01*
X61143Y-181664D01*
X63663Y-182081D01*
X65868Y-183748D01*
X67758Y-186247D01*
X69018Y-189164D01*
X69648Y-192497D01*
Y-195831D01*
X69018Y-199164D01*
X67758Y-202081D01*
X65868Y-204581D01*
X63663Y-206247D01*
X61143Y-206664D01*
G01X63663Y-199997D02*
X67443Y-206664D01*
G01X80988Y-189998D02*
Y-201664D01*
X82248Y-204581D01*
X84138Y-206247D01*
X86343Y-206664D01*
X88548Y-206247D01*
X90438Y-204581D01*
X91698Y-201664D01*
G01Y-206664D02*
Y-189998D01*
G01X117213Y-206664D02*
Y-189998D01*
G01Y-192914D02*
X115953Y-191248D01*
X114063Y-190414D01*
X111858Y-189998D01*
X109653Y-190831D01*
X107763Y-192497D01*
X106503Y-194998D01*
X105873Y-198331D01*
X106503Y-201664D01*
X107763Y-204165D01*
X109653Y-205831D01*
X111858Y-206664D01*
X114063Y-206247D01*
X115953Y-204998D01*
X117213Y-203331D01*
G01X131388Y-206664D02*
Y-189998D01*
G01Y-194164D02*
X132648Y-192081D01*
X134538Y-190414D01*
X137058Y-189998D01*
X139263Y-190414D01*
X141153Y-192081D01*
X142098Y-194998D01*
Y-206664D01*
G01X161943Y-181664D02*
Y-206664D01*
G01X157533Y-189998D02*
X166353D01*
G01X192813Y-206664D02*
Y-189998D01*
G01Y-192914D02*
X191553Y-191248D01*
X189663Y-190414D01*
X187458Y-189998D01*
X185253Y-190831D01*
X183363Y-192497D01*
X182103Y-194998D01*
X181473Y-198331D01*
X182103Y-201664D01*
X183363Y-204165D01*
X185253Y-205831D01*
X187458Y-206664D01*
X189663Y-206247D01*
X191553Y-204998D01*
X192813Y-203331D01*
G01X47878Y177990D02*
X47610Y178351D01*
X47380Y178558D01*
X47073Y178661D01*
X46805Y178558D01*
X46613Y178351D01*
X46460Y178041D01*
X46422Y177680D01*
X46460Y177370D01*
X46613Y177060D01*
X46843Y176801D01*
X47112Y176698D01*
X47418Y176801D01*
X47687Y177111D01*
X47840Y177576D01*
X47878Y178093D01*
X47802Y178765D01*
X47687Y179126D01*
X47495Y179488D01*
X47227Y179746D01*
X46958Y179798D01*
X46690Y179695D01*
X46498Y179436D01*
G01X46883Y218412D02*
X46653Y218154D01*
X46385Y217999D01*
X46040Y217947D01*
X45695Y218050D01*
X45427Y218257D01*
X45235Y218619D01*
X45197Y219032D01*
X45273Y219445D01*
X45465Y219704D01*
X45733Y219910D01*
X46002Y219962D01*
X46270Y219910D01*
X46615Y219704D01*
X46500Y221047D01*
X45465D01*
G01X43101Y269815D02*
X43256Y269585D01*
X43359Y269317D01*
Y269010D01*
X43204Y268665D01*
X42946Y268397D01*
X42636Y268205D01*
X42119Y268052D01*
X41654Y268014D01*
X41189Y268090D01*
X40879Y268205D01*
X40569Y268435D01*
X40362Y268704D01*
X40259Y268972D01*
Y269240D01*
X40362Y269509D01*
X40517Y269739D01*
X40724Y269930D01*
G01X42842Y271344D02*
X43152Y271574D01*
X43307Y271842D01*
X43359Y272149D01*
X43256Y272532D01*
X42997Y272800D01*
X42687Y272877D01*
X42377Y272839D01*
X42119Y272685D01*
X41602Y271919D01*
X41241Y271574D01*
X40724Y271344D01*
X40259Y271267D01*
Y272877D01*
G01X40621Y274520D02*
X40362Y274789D01*
X40259Y275095D01*
X40362Y275402D01*
X40672Y275670D01*
X41137Y275862D01*
X41602Y275939D01*
X42171D01*
X42636Y275862D01*
X43049Y275670D01*
X43256Y275440D01*
X43359Y275172D01*
X43256Y274865D01*
X43049Y274635D01*
X42739Y274482D01*
X42326Y274405D01*
X41964Y274482D01*
X41602Y274674D01*
X41396Y274904D01*
X41344Y275172D01*
X41447Y275479D01*
X41706Y275709D01*
X42171Y275939D01*
G01X41551Y277544D02*
X41912Y277812D01*
X42119Y278042D01*
X42222Y278349D01*
X42119Y278617D01*
X41912Y278809D01*
X41602Y278962D01*
X41241Y279000D01*
X40931Y278962D01*
X40621Y278809D01*
X40362Y278579D01*
X40259Y278310D01*
X40362Y278004D01*
X40672Y277735D01*
X41137Y277582D01*
X41654Y277544D01*
X42326Y277620D01*
X42687Y277735D01*
X43049Y277927D01*
X43307Y278195D01*
X43359Y278464D01*
X43256Y278732D01*
X42997Y278924D01*
G01X47374Y269815D02*
X47529Y269585D01*
X47632Y269317D01*
Y269010D01*
X47477Y268665D01*
X47219Y268397D01*
X46909Y268205D01*
X46392Y268052D01*
X45927Y268014D01*
X45462Y268090D01*
X45152Y268205D01*
X44842Y268435D01*
X44635Y268704D01*
X44532Y268972D01*
Y269240D01*
X44635Y269509D01*
X44790Y269739D01*
X44997Y269930D01*
G01X47115Y271344D02*
X47425Y271574D01*
X47580Y271842D01*
X47632Y272149D01*
X47529Y272532D01*
X47270Y272800D01*
X46960Y272877D01*
X46650Y272839D01*
X46392Y272685D01*
X45875Y271919D01*
X45514Y271574D01*
X44997Y271344D01*
X44532Y271267D01*
Y272877D01*
G01X44894Y274520D02*
X44635Y274789D01*
X44532Y275095D01*
X44635Y275402D01*
X44945Y275670D01*
X45410Y275862D01*
X45875Y275939D01*
X46444D01*
X46909Y275862D01*
X47322Y275670D01*
X47529Y275440D01*
X47632Y275172D01*
X47529Y274865D01*
X47322Y274635D01*
X47012Y274482D01*
X46599Y274405D01*
X46237Y274482D01*
X45875Y274674D01*
X45669Y274904D01*
X45617Y275172D01*
X45720Y275479D01*
X45979Y275709D01*
X46444Y275939D01*
G01X44532Y278195D02*
X45204Y278272D01*
X45772Y278387D01*
X46289Y278540D01*
X46857Y278732D01*
X47632Y279039D01*
Y277505D01*
G01X52071Y269815D02*
X52226Y269585D01*
X52329Y269317D01*
Y269010D01*
X52174Y268665D01*
X51916Y268397D01*
X51606Y268205D01*
X51089Y268052D01*
X50624Y268014D01*
X50159Y268090D01*
X49849Y268205D01*
X49539Y268435D01*
X49332Y268704D01*
X49229Y268972D01*
Y269240D01*
X49332Y269509D01*
X49487Y269739D01*
X49694Y269930D01*
G01X51812Y271344D02*
X52122Y271574D01*
X52277Y271842D01*
X52329Y272149D01*
X52226Y272532D01*
X51967Y272800D01*
X51657Y272877D01*
X51347Y272839D01*
X51089Y272685D01*
X50572Y271919D01*
X50211Y271574D01*
X49694Y271344D01*
X49229Y271267D01*
Y272877D01*
G01X49591Y274520D02*
X49332Y274789D01*
X49229Y275095D01*
X49332Y275402D01*
X49642Y275670D01*
X50107Y275862D01*
X50572Y275939D01*
X51141D01*
X51606Y275862D01*
X52019Y275670D01*
X52226Y275440D01*
X52329Y275172D01*
X52226Y274865D01*
X52019Y274635D01*
X51709Y274482D01*
X51296Y274405D01*
X50934Y274482D01*
X50572Y274674D01*
X50366Y274904D01*
X50314Y275172D01*
X50417Y275479D01*
X50676Y275709D01*
X51141Y275939D01*
G01X49694Y277429D02*
X49436Y277659D01*
X49281Y277927D01*
X49229Y278272D01*
X49332Y278617D01*
X49539Y278885D01*
X49901Y279077D01*
X50314Y279115D01*
X50727Y279039D01*
X50986Y278847D01*
X51192Y278579D01*
X51244Y278310D01*
X51192Y278042D01*
X50986Y277697D01*
X52329Y277812D01*
Y278847D01*
G01X52880Y281527D02*
X49780D01*
Y283061D01*
G01Y285394D02*
X52880D01*
X52260Y284934D01*
G01X49780D02*
Y285854D01*
G01X50245Y287651D02*
X49987Y287881D01*
X49832Y288149D01*
X49780Y288494D01*
X49883Y288839D01*
X50090Y289107D01*
X50452Y289299D01*
X50865Y289337D01*
X51278Y289261D01*
X51537Y289069D01*
X51743Y288801D01*
X51795Y288532D01*
X51743Y288264D01*
X51537Y287919D01*
X52880Y288034D01*
Y289069D01*
G01X52899Y298135D02*
X53129Y298290D01*
X53397Y298393D01*
X53704D01*
X54049Y298238D01*
X54317Y297980D01*
X54509Y297670D01*
X54662Y297153D01*
X54700Y296688D01*
X54624Y296223D01*
X54509Y295913D01*
X54279Y295603D01*
X54010Y295396D01*
X53742Y295293D01*
X53474D01*
X53205Y295396D01*
X52975Y295551D01*
X52784Y295758D01*
G01X51370Y297876D02*
X51140Y298186D01*
X50872Y298341D01*
X50565Y298393D01*
X50182Y298290D01*
X49914Y298031D01*
X49837Y297721D01*
X49875Y297411D01*
X50029Y297153D01*
X50795Y296636D01*
X51140Y296275D01*
X51370Y295758D01*
X51447Y295293D01*
X49837D01*
G01X48270Y296585D02*
X48002Y296946D01*
X47772Y297153D01*
X47465Y297256D01*
X47197Y297153D01*
X47005Y296946D01*
X46852Y296636D01*
X46814Y296275D01*
X46852Y295965D01*
X47005Y295655D01*
X47235Y295396D01*
X47504Y295293D01*
X47810Y295396D01*
X48079Y295706D01*
X48232Y296171D01*
X48270Y296688D01*
X48194Y297360D01*
X48079Y297721D01*
X47887Y298083D01*
X47619Y298341D01*
X47350Y298393D01*
X47082Y298290D01*
X46890Y298031D01*
G01X45170Y296585D02*
X44902Y296946D01*
X44672Y297153D01*
X44365Y297256D01*
X44097Y297153D01*
X43905Y296946D01*
X43752Y296636D01*
X43714Y296275D01*
X43752Y295965D01*
X43905Y295655D01*
X44135Y295396D01*
X44404Y295293D01*
X44710Y295396D01*
X44979Y295706D01*
X45132Y296171D01*
X45170Y296688D01*
X45094Y297360D01*
X44979Y297721D01*
X44787Y298083D01*
X44519Y298341D01*
X44250Y298393D01*
X43982Y298290D01*
X43790Y298031D01*
G01X52899Y293853D02*
X53129Y294008D01*
X53397Y294111D01*
X53704D01*
X54049Y293956D01*
X54317Y293698D01*
X54509Y293388D01*
X54662Y292871D01*
X54700Y292406D01*
X54624Y291941D01*
X54509Y291631D01*
X54279Y291321D01*
X54010Y291114D01*
X53742Y291011D01*
X53474D01*
X53205Y291114D01*
X52975Y291269D01*
X52784Y291476D01*
G01X51370Y293594D02*
X51140Y293904D01*
X50872Y294059D01*
X50565Y294111D01*
X50182Y294008D01*
X49914Y293749D01*
X49837Y293439D01*
X49875Y293129D01*
X50029Y292871D01*
X50795Y292354D01*
X51140Y291993D01*
X51370Y291476D01*
X51447Y291011D01*
X49837D01*
G01X48270Y292303D02*
X48002Y292664D01*
X47772Y292871D01*
X47465Y292974D01*
X47197Y292871D01*
X47005Y292664D01*
X46852Y292354D01*
X46814Y291993D01*
X46852Y291683D01*
X47005Y291373D01*
X47235Y291114D01*
X47504Y291011D01*
X47810Y291114D01*
X48079Y291424D01*
X48232Y291889D01*
X48270Y292406D01*
X48194Y293078D01*
X48079Y293439D01*
X47887Y293801D01*
X47619Y294059D01*
X47350Y294111D01*
X47082Y294008D01*
X46890Y293749D01*
G01X45285Y291476D02*
X45055Y291218D01*
X44787Y291063D01*
X44442Y291011D01*
X44097Y291114D01*
X43829Y291321D01*
X43637Y291683D01*
X43599Y292096D01*
X43675Y292509D01*
X43867Y292768D01*
X44135Y292974D01*
X44404Y293026D01*
X44672Y292974D01*
X45017Y292768D01*
X44902Y294111D01*
X43867D01*
G01X52899Y302187D02*
X53129Y302342D01*
X53397Y302445D01*
X53704D01*
X54049Y302290D01*
X54317Y302032D01*
X54509Y301722D01*
X54662Y301205D01*
X54700Y300740D01*
X54624Y300275D01*
X54509Y299965D01*
X54279Y299655D01*
X54010Y299448D01*
X53742Y299345D01*
X53474D01*
X53205Y299448D01*
X52975Y299603D01*
X52784Y299810D01*
G01X51370Y301928D02*
X51140Y302238D01*
X50872Y302393D01*
X50565Y302445D01*
X50182Y302342D01*
X49914Y302083D01*
X49837Y301773D01*
X49875Y301463D01*
X50029Y301205D01*
X50795Y300688D01*
X51140Y300327D01*
X51370Y299810D01*
X51447Y299345D01*
X49837D01*
G01X48270Y300637D02*
X48002Y300998D01*
X47772Y301205D01*
X47465Y301308D01*
X47197Y301205D01*
X47005Y300998D01*
X46852Y300688D01*
X46814Y300327D01*
X46852Y300017D01*
X47005Y299707D01*
X47235Y299448D01*
X47504Y299345D01*
X47810Y299448D01*
X48079Y299758D01*
X48232Y300223D01*
X48270Y300740D01*
X48194Y301412D01*
X48079Y301773D01*
X47887Y302135D01*
X47619Y302393D01*
X47350Y302445D01*
X47082Y302342D01*
X46890Y302083D01*
G01X44519Y299345D02*
X44442Y300017D01*
X44327Y300585D01*
X44174Y301102D01*
X43982Y301670D01*
X43675Y302445D01*
X45209D01*
G01X53107Y322622D02*
X52877Y322932D01*
X52609Y323087D01*
X52302Y323139D01*
X51919Y323036D01*
X51651Y322777D01*
X51574Y322467D01*
X51612Y322157D01*
X51766Y321899D01*
X52532Y321382D01*
X52877Y321021D01*
X53107Y320504D01*
X53184Y320039D01*
X51574D01*
G01X51826Y336891D02*
Y339991D01*
X52286Y339371D01*
G01Y336891D02*
X51366D01*
G01X51354Y484857D02*
Y492257D01*
G01X42654Y484857D02*
X60054D01*
G01X42654Y492257D02*
Y484857D01*
G01X48310Y496218D02*
Y493018D01*
G01D02*
X54510D01*
G01X51410Y496118D02*
Y493118D01*
G01X54510Y496218D02*
X48310D01*
G01X60054Y492257D02*
X42654D01*
G01X380571Y782281D02*
X48681D01*
G01X58824Y794448D02*
X57866Y797548D01*
X56908Y794448D01*
G01X57253Y795533D02*
X58479D01*
G01X54766Y794448D02*
X54498Y794500D01*
X54191Y794655D01*
X53999Y794913D01*
X53923Y795275D01*
X53999Y795636D01*
X54229Y795946D01*
X54574Y796101D01*
X54958D01*
X55188Y796205D01*
X55379Y796463D01*
X55456Y796825D01*
X55341Y797186D01*
X55073Y797445D01*
X54766Y797548D01*
X54459Y797445D01*
X54191Y797186D01*
X54076Y796825D01*
X54153Y796463D01*
X54344Y796205D01*
X54574Y796101D01*
X54958D01*
X55303Y795946D01*
X55533Y795636D01*
X55609Y795275D01*
X55533Y794913D01*
X55341Y794655D01*
X55034Y794500D01*
X54766Y794448D01*
G01X52394Y797031D02*
X52164Y797341D01*
X51896Y797496D01*
X51589Y797548D01*
X51206Y797445D01*
X50938Y797186D01*
X50861Y796876D01*
X50899Y796566D01*
X51053Y796308D01*
X51819Y795791D01*
X52164Y795430D01*
X52394Y794913D01*
X52471Y794448D01*
X50861D01*
G01X64666Y20092D02*
Y23192D01*
X65126Y22572D01*
G01Y20092D02*
X64206D01*
G01X66050Y262390D02*
Y271240D01*
G01Y271490D02*
Y270790D01*
G01X95940Y271490D02*
X66050D01*
G01X68830Y280757D02*
X68985Y280527D01*
X69088Y280259D01*
Y279952D01*
X68933Y279607D01*
X68675Y279339D01*
X68365Y279147D01*
X67848Y278994D01*
X67383Y278956D01*
X66918Y279032D01*
X66608Y279147D01*
X66298Y279377D01*
X66091Y279646D01*
X65988Y279914D01*
Y280182D01*
X66091Y280451D01*
X66246Y280681D01*
X66453Y280872D01*
G01X68571Y282286D02*
X68881Y282516D01*
X69036Y282784D01*
X69088Y283091D01*
X68985Y283474D01*
X68726Y283742D01*
X68416Y283819D01*
X68106Y283781D01*
X67848Y283627D01*
X67331Y282861D01*
X66970Y282516D01*
X66453Y282286D01*
X65988Y282209D01*
Y283819D01*
G01X67280Y285386D02*
X67641Y285654D01*
X67848Y285884D01*
X67951Y286191D01*
X67848Y286459D01*
X67641Y286651D01*
X67331Y286804D01*
X66970Y286842D01*
X66660Y286804D01*
X66350Y286651D01*
X66091Y286421D01*
X65988Y286152D01*
X66091Y285846D01*
X66401Y285577D01*
X66866Y285424D01*
X67383Y285386D01*
X68055Y285462D01*
X68416Y285577D01*
X68778Y285769D01*
X69036Y286037D01*
X69088Y286306D01*
X68985Y286574D01*
X68726Y286766D01*
G01X66350Y288562D02*
X66091Y288831D01*
X65988Y289137D01*
X66091Y289444D01*
X66401Y289712D01*
X66866Y289904D01*
X67331Y289981D01*
X67900D01*
X68365Y289904D01*
X68778Y289712D01*
X68985Y289482D01*
X69088Y289214D01*
X68985Y288907D01*
X68778Y288677D01*
X68468Y288524D01*
X68055Y288447D01*
X67693Y288524D01*
X67331Y288716D01*
X67125Y288946D01*
X67073Y289214D01*
X67176Y289521D01*
X67435Y289751D01*
X67900Y289981D01*
G01X66407Y278100D02*
Y275000D01*
X64873D01*
G01X62540D02*
Y278100D01*
X63000Y277480D01*
G01Y275000D02*
X62080D01*
G01X60168Y276292D02*
X59900Y276653D01*
X59670Y276860D01*
X59363Y276963D01*
X59095Y276860D01*
X58903Y276653D01*
X58750Y276343D01*
X58712Y275982D01*
X58750Y275672D01*
X58903Y275362D01*
X59133Y275103D01*
X59402Y275000D01*
X59708Y275103D01*
X59977Y275413D01*
X60130Y275878D01*
X60168Y276395D01*
X60092Y277067D01*
X59977Y277428D01*
X59785Y277790D01*
X59517Y278048D01*
X59248Y278100D01*
X58980Y277997D01*
X58788Y277738D01*
G01X68920Y291656D02*
Y294756D01*
X67961D01*
X67655Y294601D01*
X67463Y294394D01*
X67386Y293981D01*
X67463Y293568D01*
X67693Y293309D01*
X67961Y293154D01*
X68920D01*
G01X67961D02*
X67386Y291656D01*
G01X65781Y294239D02*
X65551Y294549D01*
X65283Y294704D01*
X64976Y294756D01*
X64593Y294653D01*
X64325Y294394D01*
X64248Y294084D01*
X64286Y293774D01*
X64440Y293516D01*
X65206Y292999D01*
X65551Y292638D01*
X65781Y292121D01*
X65858Y291656D01*
X64248D01*
G01X62605Y292018D02*
X62336Y291759D01*
X62030Y291656D01*
X61723Y291759D01*
X61455Y292069D01*
X61263Y292534D01*
X61186Y292999D01*
Y293568D01*
X61263Y294033D01*
X61455Y294446D01*
X61685Y294653D01*
X61953Y294756D01*
X62260Y294653D01*
X62490Y294446D01*
X62643Y294136D01*
X62720Y293723D01*
X62643Y293361D01*
X62451Y292999D01*
X62221Y292793D01*
X61953Y292741D01*
X61646Y292844D01*
X61416Y293103D01*
X61186Y293568D01*
G01X58393Y291656D02*
Y294756D01*
X59811Y292534D01*
X57895D01*
G01X69170Y349318D02*
Y312300D01*
G01X65749Y303858D02*
X65979Y304013D01*
X66247Y304116D01*
X66554D01*
X66899Y303961D01*
X67167Y303703D01*
X67359Y303393D01*
X67512Y302876D01*
X67550Y302411D01*
X67474Y301946D01*
X67359Y301636D01*
X67129Y301326D01*
X66860Y301119D01*
X66592Y301016D01*
X66324D01*
X66055Y301119D01*
X65825Y301274D01*
X65634Y301481D01*
G01X64220Y303599D02*
X63990Y303909D01*
X63722Y304064D01*
X63415Y304116D01*
X63032Y304013D01*
X62764Y303754D01*
X62687Y303444D01*
X62725Y303134D01*
X62879Y302876D01*
X63645Y302359D01*
X63990Y301998D01*
X64220Y301481D01*
X64297Y301016D01*
X62687D01*
G01X60392D02*
X60124Y301068D01*
X59817Y301223D01*
X59625Y301481D01*
X59549Y301843D01*
X59625Y302204D01*
X59855Y302514D01*
X60200Y302669D01*
X60584D01*
X60814Y302773D01*
X61005Y303031D01*
X61082Y303393D01*
X60967Y303754D01*
X60699Y304013D01*
X60392Y304116D01*
X60085Y304013D01*
X59817Y303754D01*
X59702Y303393D01*
X59779Y303031D01*
X59970Y302773D01*
X60200Y302669D01*
X60584D01*
X60929Y302514D01*
X61159Y302204D01*
X61235Y301843D01*
X61159Y301481D01*
X60967Y301223D01*
X60660Y301068D01*
X60392Y301016D01*
G01X57292D02*
X57024Y301068D01*
X56717Y301223D01*
X56525Y301481D01*
X56449Y301843D01*
X56525Y302204D01*
X56755Y302514D01*
X57100Y302669D01*
X57484D01*
X57714Y302773D01*
X57905Y303031D01*
X57982Y303393D01*
X57867Y303754D01*
X57599Y304013D01*
X57292Y304116D01*
X56985Y304013D01*
X56717Y303754D01*
X56602Y303393D01*
X56679Y303031D01*
X56870Y302773D01*
X57100Y302669D01*
X57484D01*
X57829Y302514D01*
X58059Y302204D01*
X58135Y301843D01*
X58059Y301481D01*
X57867Y301223D01*
X57560Y301068D01*
X57292Y301016D01*
G01X67359Y305298D02*
Y308398D01*
X66400D01*
X66094Y308243D01*
X65902Y308036D01*
X65825Y307623D01*
X65902Y307210D01*
X66132Y306951D01*
X66400Y306796D01*
X67359D01*
G01X66400D02*
X65825Y305298D01*
G01X64220Y307881D02*
X63990Y308191D01*
X63722Y308346D01*
X63415Y308398D01*
X63032Y308295D01*
X62764Y308036D01*
X62687Y307726D01*
X62725Y307416D01*
X62879Y307158D01*
X63645Y306641D01*
X63990Y306280D01*
X64220Y305763D01*
X64297Y305298D01*
X62687D01*
G01X61235Y305763D02*
X61005Y305505D01*
X60737Y305350D01*
X60392Y305298D01*
X60047Y305401D01*
X59779Y305608D01*
X59587Y305970D01*
X59549Y306383D01*
X59625Y306796D01*
X59817Y307055D01*
X60085Y307261D01*
X60354Y307313D01*
X60622Y307261D01*
X60967Y307055D01*
X60852Y308398D01*
X59817D01*
G01X57369Y305298D02*
X57292Y305970D01*
X57177Y306538D01*
X57024Y307055D01*
X56832Y307623D01*
X56525Y308398D01*
X58059D01*
G01X69390Y340310D02*
X80080D01*
G01X60054Y484857D02*
Y492257D01*
G01X54510Y493018D02*
Y496218D01*
G01X76474Y531596D02*
Y534696D01*
X75554D01*
X75247Y534541D01*
X75017Y534179D01*
X74940Y533766D01*
X75017Y533353D01*
X75209Y533043D01*
X75554Y532888D01*
X76474D01*
G01X73374Y531596D02*
Y534696D01*
X72415D01*
X72109Y534541D01*
X71917Y534334D01*
X71840Y533921D01*
X71917Y533508D01*
X72147Y533249D01*
X72415Y533094D01*
X73374D01*
G01X72415D02*
X71840Y531596D01*
G01X70235Y534179D02*
X70005Y534489D01*
X69737Y534644D01*
X69430Y534696D01*
X69047Y534593D01*
X68779Y534334D01*
X68702Y534024D01*
X68740Y533714D01*
X68894Y533456D01*
X69660Y532939D01*
X70005Y532578D01*
X70235Y532061D01*
X70312Y531596D01*
X68702D01*
G01X67250Y532061D02*
X67020Y531803D01*
X66752Y531648D01*
X66407Y531596D01*
X66062Y531699D01*
X65794Y531906D01*
X65602Y532268D01*
X65564Y532681D01*
X65640Y533094D01*
X65832Y533353D01*
X66100Y533559D01*
X66369Y533611D01*
X66637Y533559D01*
X66982Y533353D01*
X66867Y534696D01*
X65832D01*
G01X67079Y526377D02*
Y529577D01*
G01X60879Y526377D02*
X67079D01*
G01Y529577D02*
X60879D01*
G01D02*
Y526377D01*
G01X80579Y40383D02*
X80349Y40693D01*
X80081Y40848D01*
X79774Y40900D01*
X79391Y40797D01*
X79123Y40538D01*
X79046Y40228D01*
X79084Y39918D01*
X79238Y39660D01*
X80004Y39143D01*
X80349Y38782D01*
X80579Y38265D01*
X80656Y37800D01*
X79046D01*
G01X76890Y148070D02*
Y151170D01*
X77350Y150550D01*
G01Y148070D02*
X76430D01*
G01X82840Y312531D02*
X83070Y312686D01*
X83338Y312789D01*
X83645D01*
X83990Y312634D01*
X84258Y312376D01*
X84450Y312066D01*
X84603Y311549D01*
X84641Y311084D01*
X84565Y310619D01*
X84450Y310309D01*
X84220Y309999D01*
X83951Y309792D01*
X83683Y309689D01*
X83415D01*
X83146Y309792D01*
X82916Y309947D01*
X82725Y310154D01*
G01X81311Y312272D02*
X81081Y312582D01*
X80813Y312737D01*
X80506Y312789D01*
X80123Y312686D01*
X79855Y312427D01*
X79778Y312117D01*
X79816Y311807D01*
X79970Y311549D01*
X80736Y311032D01*
X81081Y310671D01*
X81311Y310154D01*
X81388Y309689D01*
X79778D01*
G01X77560D02*
X77483Y310361D01*
X77368Y310929D01*
X77215Y311446D01*
X77023Y312014D01*
X76716Y312789D01*
X78250D01*
G01X75226Y310309D02*
X74996Y309947D01*
X74690Y309741D01*
X74345Y309689D01*
X74038Y309741D01*
X73731Y309999D01*
X73540Y310309D01*
X73501Y310619D01*
X73578Y310981D01*
X73846Y311239D01*
X74115Y311342D01*
X74460D01*
G01X74115D02*
X73885Y311497D01*
X73693Y311756D01*
X73616Y312066D01*
X73693Y312376D01*
X73885Y312634D01*
X74230Y312789D01*
X74575Y312737D01*
X74920Y312531D01*
G01X82840Y316587D02*
X83070Y316742D01*
X83338Y316845D01*
X83645D01*
X83990Y316690D01*
X84258Y316432D01*
X84450Y316122D01*
X84603Y315605D01*
X84641Y315140D01*
X84565Y314675D01*
X84450Y314365D01*
X84220Y314055D01*
X83951Y313848D01*
X83683Y313745D01*
X83415D01*
X83146Y313848D01*
X82916Y314003D01*
X82725Y314210D01*
G01X81311Y316328D02*
X81081Y316638D01*
X80813Y316793D01*
X80506Y316845D01*
X80123Y316742D01*
X79855Y316483D01*
X79778Y316173D01*
X79816Y315863D01*
X79970Y315605D01*
X80736Y315088D01*
X81081Y314727D01*
X81311Y314210D01*
X81388Y313745D01*
X79778D01*
G01X77560D02*
X77483Y314417D01*
X77368Y314985D01*
X77215Y315502D01*
X77023Y316070D01*
X76716Y316845D01*
X78250D01*
G01X75226Y314210D02*
X74996Y313952D01*
X74728Y313797D01*
X74383Y313745D01*
X74038Y313848D01*
X73770Y314055D01*
X73578Y314417D01*
X73540Y314830D01*
X73616Y315243D01*
X73808Y315502D01*
X74076Y315708D01*
X74345Y315760D01*
X74613Y315708D01*
X74958Y315502D01*
X74843Y316845D01*
X73808D01*
G01X79792Y304118D02*
X80022Y304273D01*
X80290Y304376D01*
X80597D01*
X80942Y304221D01*
X81210Y303963D01*
X81402Y303653D01*
X81555Y303136D01*
X81593Y302671D01*
X81517Y302206D01*
X81402Y301896D01*
X81172Y301586D01*
X80903Y301379D01*
X80635Y301276D01*
X80367D01*
X80098Y301379D01*
X79868Y301534D01*
X79677Y301741D01*
G01X78263Y303859D02*
X78033Y304169D01*
X77765Y304324D01*
X77458Y304376D01*
X77075Y304273D01*
X76807Y304014D01*
X76730Y303704D01*
X76768Y303394D01*
X76922Y303136D01*
X77688Y302619D01*
X78033Y302258D01*
X78263Y301741D01*
X78340Y301276D01*
X76730D01*
G01X74512D02*
X74435Y301948D01*
X74320Y302516D01*
X74167Y303033D01*
X73975Y303601D01*
X73668Y304376D01*
X75202D01*
G01X71335D02*
X71642Y304273D01*
X71872Y304014D01*
X72025Y303704D01*
X72140Y303291D01*
X72178Y302826D01*
X72140Y302361D01*
X72025Y301948D01*
X71872Y301638D01*
X71642Y301379D01*
X71335Y301276D01*
X71028Y301379D01*
X70798Y301638D01*
X70645Y301948D01*
X70530Y302361D01*
X70492Y302826D01*
X70530Y303291D01*
X70645Y303704D01*
X70798Y304014D01*
X71028Y304273D01*
X71335Y304376D01*
G01X79792Y308400D02*
X80022Y308555D01*
X80290Y308658D01*
X80597D01*
X80942Y308503D01*
X81210Y308245D01*
X81402Y307935D01*
X81555Y307418D01*
X81593Y306953D01*
X81517Y306488D01*
X81402Y306178D01*
X81172Y305868D01*
X80903Y305661D01*
X80635Y305558D01*
X80367D01*
X80098Y305661D01*
X79868Y305816D01*
X79677Y306023D01*
G01X78263Y308141D02*
X78033Y308451D01*
X77765Y308606D01*
X77458Y308658D01*
X77075Y308555D01*
X76807Y308296D01*
X76730Y307986D01*
X76768Y307676D01*
X76922Y307418D01*
X77688Y306901D01*
X78033Y306540D01*
X78263Y306023D01*
X78340Y305558D01*
X76730D01*
G01X75163Y306850D02*
X74895Y307211D01*
X74665Y307418D01*
X74358Y307521D01*
X74090Y307418D01*
X73898Y307211D01*
X73745Y306901D01*
X73707Y306540D01*
X73745Y306230D01*
X73898Y305920D01*
X74128Y305661D01*
X74397Y305558D01*
X74703Y305661D01*
X74972Y305971D01*
X75125Y306436D01*
X75163Y306953D01*
X75087Y307625D01*
X74972Y307986D01*
X74780Y308348D01*
X74512Y308606D01*
X74243Y308658D01*
X73975Y308555D01*
X73783Y308296D01*
G01X71335Y305558D02*
X71067Y305610D01*
X70760Y305765D01*
X70568Y306023D01*
X70492Y306385D01*
X70568Y306746D01*
X70798Y307056D01*
X71143Y307211D01*
X71527D01*
X71757Y307315D01*
X71948Y307573D01*
X72025Y307935D01*
X71910Y308296D01*
X71642Y308555D01*
X71335Y308658D01*
X71028Y308555D01*
X70760Y308296D01*
X70645Y307935D01*
X70722Y307573D01*
X70913Y307315D01*
X71143Y307211D01*
X71527D01*
X71872Y307056D01*
X72102Y306746D01*
X72178Y306385D01*
X72102Y306023D01*
X71910Y305765D01*
X71603Y305610D01*
X71335Y305558D01*
G01X82840Y328881D02*
X83070Y329036D01*
X83338Y329139D01*
X83645D01*
X83990Y328984D01*
X84258Y328726D01*
X84450Y328416D01*
X84603Y327899D01*
X84641Y327434D01*
X84565Y326969D01*
X84450Y326659D01*
X84220Y326349D01*
X83951Y326142D01*
X83683Y326039D01*
X83415D01*
X83146Y326142D01*
X82916Y326297D01*
X82725Y326504D01*
G01X81311Y328622D02*
X81081Y328932D01*
X80813Y329087D01*
X80506Y329139D01*
X80123Y329036D01*
X79855Y328777D01*
X79778Y328467D01*
X79816Y328157D01*
X79970Y327899D01*
X80736Y327382D01*
X81081Y327021D01*
X81311Y326504D01*
X81388Y326039D01*
X79778D01*
G01X77560D02*
X77483Y326711D01*
X77368Y327279D01*
X77215Y327796D01*
X77023Y328364D01*
X76716Y329139D01*
X78250D01*
G01X73923Y326039D02*
Y329139D01*
X75341Y326917D01*
X73425D01*
G01X82840Y320592D02*
X83070Y320747D01*
X83338Y320850D01*
X83645D01*
X83990Y320695D01*
X84258Y320437D01*
X84450Y320127D01*
X84603Y319610D01*
X84641Y319145D01*
X84565Y318680D01*
X84450Y318370D01*
X84220Y318060D01*
X83951Y317853D01*
X83683Y317750D01*
X83415D01*
X83146Y317853D01*
X82916Y318008D01*
X82725Y318215D01*
G01X81311Y320333D02*
X81081Y320643D01*
X80813Y320798D01*
X80506Y320850D01*
X80123Y320747D01*
X79855Y320488D01*
X79778Y320178D01*
X79816Y319868D01*
X79970Y319610D01*
X80736Y319093D01*
X81081Y318732D01*
X81311Y318215D01*
X81388Y317750D01*
X79778D01*
G01X77483D02*
X77215Y317802D01*
X76908Y317957D01*
X76716Y318215D01*
X76640Y318577D01*
X76716Y318938D01*
X76946Y319248D01*
X77291Y319403D01*
X77675D01*
X77905Y319507D01*
X78096Y319765D01*
X78173Y320127D01*
X78058Y320488D01*
X77790Y320747D01*
X77483Y320850D01*
X77176Y320747D01*
X76908Y320488D01*
X76793Y320127D01*
X76870Y319765D01*
X77061Y319507D01*
X77291Y319403D01*
X77675D01*
X78020Y319248D01*
X78250Y318938D01*
X78326Y318577D01*
X78250Y318215D01*
X78058Y317957D01*
X77751Y317802D01*
X77483Y317750D01*
G01X75035Y318112D02*
X74766Y317853D01*
X74460Y317750D01*
X74153Y317853D01*
X73885Y318163D01*
X73693Y318628D01*
X73616Y319093D01*
Y319662D01*
X73693Y320127D01*
X73885Y320540D01*
X74115Y320747D01*
X74383Y320850D01*
X74690Y320747D01*
X74920Y320540D01*
X75073Y320230D01*
X75150Y319817D01*
X75073Y319455D01*
X74881Y319093D01*
X74651Y318887D01*
X74383Y318835D01*
X74076Y318938D01*
X73846Y319197D01*
X73616Y319662D01*
G01X82840Y324829D02*
X83070Y324984D01*
X83338Y325087D01*
X83645D01*
X83990Y324932D01*
X84258Y324674D01*
X84450Y324364D01*
X84603Y323847D01*
X84641Y323382D01*
X84565Y322917D01*
X84450Y322607D01*
X84220Y322297D01*
X83951Y322090D01*
X83683Y321987D01*
X83415D01*
X83146Y322090D01*
X82916Y322245D01*
X82725Y322452D01*
G01X81311Y324570D02*
X81081Y324880D01*
X80813Y325035D01*
X80506Y325087D01*
X80123Y324984D01*
X79855Y324725D01*
X79778Y324415D01*
X79816Y324105D01*
X79970Y323847D01*
X80736Y323330D01*
X81081Y322969D01*
X81311Y322452D01*
X81388Y321987D01*
X79778D01*
G01X77560D02*
X77483Y322659D01*
X77368Y323227D01*
X77215Y323744D01*
X77023Y324312D01*
X76716Y325087D01*
X78250D01*
G01X75111Y324570D02*
X74881Y324880D01*
X74613Y325035D01*
X74306Y325087D01*
X73923Y324984D01*
X73655Y324725D01*
X73578Y324415D01*
X73616Y324105D01*
X73770Y323847D01*
X74536Y323330D01*
X74881Y322969D01*
X75111Y322452D01*
X75188Y321987D01*
X73578D01*
G01X88994Y326797D02*
X89149Y326567D01*
X89252Y326299D01*
Y325992D01*
X89097Y325647D01*
X88839Y325379D01*
X88529Y325187D01*
X88012Y325034D01*
X87547Y324996D01*
X87082Y325072D01*
X86772Y325187D01*
X86462Y325417D01*
X86255Y325686D01*
X86152Y325954D01*
Y326222D01*
X86255Y326491D01*
X86410Y326721D01*
X86617Y326912D01*
G01X88735Y328326D02*
X89045Y328556D01*
X89200Y328824D01*
X89252Y329131D01*
X89149Y329514D01*
X88890Y329782D01*
X88580Y329859D01*
X88270Y329821D01*
X88012Y329667D01*
X87495Y328901D01*
X87134Y328556D01*
X86617Y328326D01*
X86152Y328249D01*
Y329859D01*
G01Y332154D02*
X86204Y332422D01*
X86359Y332729D01*
X86617Y332921D01*
X86979Y332997D01*
X87340Y332921D01*
X87650Y332691D01*
X87805Y332346D01*
Y331962D01*
X87909Y331732D01*
X88167Y331541D01*
X88529Y331464D01*
X88890Y331579D01*
X89149Y331847D01*
X89252Y332154D01*
X89149Y332461D01*
X88890Y332729D01*
X88529Y332844D01*
X88167Y332767D01*
X87909Y332576D01*
X87805Y332346D01*
Y331962D01*
X87650Y331617D01*
X87340Y331387D01*
X86979Y331311D01*
X86617Y331387D01*
X86359Y331579D01*
X86204Y331886D01*
X86152Y332154D01*
G01Y335177D02*
X86824Y335254D01*
X87392Y335369D01*
X87909Y335522D01*
X88477Y335714D01*
X89252Y336021D01*
Y334487D01*
G01X76511Y343663D02*
X74928Y348663D01*
X73345Y343663D01*
G01X73915Y345413D02*
X75941D01*
G01X80080Y340310D02*
Y352790D01*
G01X82840Y337210D02*
X83070Y337365D01*
X83338Y337468D01*
X83645D01*
X83990Y337313D01*
X84258Y337055D01*
X84450Y336745D01*
X84603Y336228D01*
X84641Y335763D01*
X84565Y335298D01*
X84450Y334988D01*
X84220Y334678D01*
X83951Y334471D01*
X83683Y334368D01*
X83415D01*
X83146Y334471D01*
X82916Y334626D01*
X82725Y334833D01*
G01X81311Y336951D02*
X81081Y337261D01*
X80813Y337416D01*
X80506Y337468D01*
X80123Y337365D01*
X79855Y337106D01*
X79778Y336796D01*
X79816Y336486D01*
X79970Y336228D01*
X80736Y335711D01*
X81081Y335350D01*
X81311Y334833D01*
X81388Y334368D01*
X79778D01*
G01X77023D02*
Y337468D01*
X78441Y335246D01*
X76525D01*
G01X73923Y334368D02*
Y337468D01*
X75341Y335246D01*
X73425D01*
G01X82840Y332979D02*
X83070Y333134D01*
X83338Y333237D01*
X83645D01*
X83990Y333082D01*
X84258Y332824D01*
X84450Y332514D01*
X84603Y331997D01*
X84641Y331532D01*
X84565Y331067D01*
X84450Y330757D01*
X84220Y330447D01*
X83951Y330240D01*
X83683Y330137D01*
X83415D01*
X83146Y330240D01*
X82916Y330395D01*
X82725Y330602D01*
G01X81311Y332720D02*
X81081Y333030D01*
X80813Y333185D01*
X80506Y333237D01*
X80123Y333134D01*
X79855Y332875D01*
X79778Y332565D01*
X79816Y332255D01*
X79970Y331997D01*
X80736Y331480D01*
X81081Y331119D01*
X81311Y330602D01*
X81388Y330137D01*
X79778D01*
G01X77483D02*
X77215Y330189D01*
X76908Y330344D01*
X76716Y330602D01*
X76640Y330964D01*
X76716Y331325D01*
X76946Y331635D01*
X77291Y331790D01*
X77675D01*
X77905Y331894D01*
X78096Y332152D01*
X78173Y332514D01*
X78058Y332875D01*
X77790Y333134D01*
X77483Y333237D01*
X77176Y333134D01*
X76908Y332875D01*
X76793Y332514D01*
X76870Y332152D01*
X77061Y331894D01*
X77291Y331790D01*
X77675D01*
X78020Y331635D01*
X78250Y331325D01*
X78326Y330964D01*
X78250Y330602D01*
X78058Y330344D01*
X77751Y330189D01*
X77483Y330137D01*
G01X74383Y333237D02*
X74690Y333134D01*
X74920Y332875D01*
X75073Y332565D01*
X75188Y332152D01*
X75226Y331687D01*
X75188Y331222D01*
X75073Y330809D01*
X74920Y330499D01*
X74690Y330240D01*
X74383Y330137D01*
X74076Y330240D01*
X73846Y330499D01*
X73693Y330809D01*
X73578Y331222D01*
X73540Y331687D01*
X73578Y332152D01*
X73693Y332565D01*
X73846Y332875D01*
X74076Y333134D01*
X74383Y333237D01*
G01X84318Y340696D02*
X84473Y340466D01*
X84576Y340198D01*
Y339891D01*
X84421Y339546D01*
X84163Y339278D01*
X83853Y339086D01*
X83336Y338933D01*
X82871Y338895D01*
X82406Y338971D01*
X82096Y339086D01*
X81786Y339316D01*
X81579Y339585D01*
X81476Y339853D01*
Y340121D01*
X81579Y340390D01*
X81734Y340620D01*
X81941Y340811D01*
G01X84059Y342225D02*
X84369Y342455D01*
X84524Y342723D01*
X84576Y343030D01*
X84473Y343413D01*
X84214Y343681D01*
X83904Y343758D01*
X83594Y343720D01*
X83336Y343566D01*
X82819Y342800D01*
X82458Y342455D01*
X81941Y342225D01*
X81476Y342148D01*
Y343758D01*
G01X81838Y345401D02*
X81579Y345670D01*
X81476Y345976D01*
X81579Y346283D01*
X81889Y346551D01*
X82354Y346743D01*
X82819Y346820D01*
X83388D01*
X83853Y346743D01*
X84266Y346551D01*
X84473Y346321D01*
X84576Y346053D01*
X84473Y345746D01*
X84266Y345516D01*
X83956Y345363D01*
X83543Y345286D01*
X83181Y345363D01*
X82819Y345555D01*
X82613Y345785D01*
X82561Y346053D01*
X82664Y346360D01*
X82923Y346590D01*
X83388Y346820D01*
G01X81476Y349613D02*
X84576D01*
X82354Y348195D01*
Y350111D01*
G01X77930Y352990D02*
X92040D01*
G01X80020Y431423D02*
X80250Y431578D01*
X80518Y431681D01*
X80825D01*
X81170Y431526D01*
X81438Y431268D01*
X81630Y430958D01*
X81783Y430441D01*
X81821Y429976D01*
X81745Y429511D01*
X81630Y429201D01*
X81400Y428891D01*
X81131Y428684D01*
X80863Y428581D01*
X80595D01*
X80326Y428684D01*
X80096Y428839D01*
X79905Y429046D01*
G01X78606D02*
X78376Y428788D01*
X78108Y428633D01*
X77763Y428581D01*
X77418Y428684D01*
X77150Y428891D01*
X76958Y429253D01*
X76920Y429666D01*
X76996Y430079D01*
X77188Y430338D01*
X77456Y430544D01*
X77725Y430596D01*
X77993Y430544D01*
X78338Y430338D01*
X78223Y431681D01*
X77188D01*
G01X75506Y429046D02*
X75276Y428788D01*
X75008Y428633D01*
X74663Y428581D01*
X74318Y428684D01*
X74050Y428891D01*
X73858Y429253D01*
X73820Y429666D01*
X73896Y430079D01*
X74088Y430338D01*
X74356Y430544D01*
X74625Y430596D01*
X74893Y430544D01*
X75238Y430338D01*
X75123Y431681D01*
X74088D01*
G01X80396Y436689D02*
X80626Y436844D01*
X80894Y436947D01*
X81201D01*
X81546Y436792D01*
X81814Y436534D01*
X82006Y436224D01*
X82159Y435707D01*
X82197Y435242D01*
X82121Y434777D01*
X82006Y434467D01*
X81776Y434157D01*
X81507Y433950D01*
X81239Y433847D01*
X80971D01*
X80702Y433950D01*
X80472Y434105D01*
X80281Y434312D01*
G01X78982D02*
X78752Y434054D01*
X78484Y433899D01*
X78139Y433847D01*
X77794Y433950D01*
X77526Y434157D01*
X77334Y434519D01*
X77296Y434932D01*
X77372Y435345D01*
X77564Y435604D01*
X77832Y435810D01*
X78101Y435862D01*
X78369Y435810D01*
X78714Y435604D01*
X78599Y436947D01*
X77564D01*
G01X75882Y434467D02*
X75652Y434105D01*
X75346Y433899D01*
X75001Y433847D01*
X74694Y433899D01*
X74387Y434157D01*
X74196Y434467D01*
X74157Y434777D01*
X74234Y435139D01*
X74502Y435397D01*
X74771Y435500D01*
X75116D01*
G01X74771D02*
X74541Y435655D01*
X74349Y435914D01*
X74272Y436224D01*
X74349Y436534D01*
X74541Y436792D01*
X74886Y436947D01*
X75231Y436895D01*
X75576Y436689D01*
G01X83549Y448671D02*
X83779Y448826D01*
X84047Y448929D01*
X84354D01*
X84699Y448774D01*
X84967Y448516D01*
X85159Y448206D01*
X85312Y447689D01*
X85350Y447224D01*
X85274Y446759D01*
X85159Y446449D01*
X84929Y446139D01*
X84660Y445932D01*
X84392Y445829D01*
X84124D01*
X83855Y445932D01*
X83625Y446087D01*
X83434Y446294D01*
G01X82135D02*
X81905Y446036D01*
X81637Y445881D01*
X81292Y445829D01*
X80947Y445932D01*
X80679Y446139D01*
X80487Y446501D01*
X80449Y446914D01*
X80525Y447327D01*
X80717Y447586D01*
X80985Y447792D01*
X81254Y447844D01*
X81522Y447792D01*
X81867Y447586D01*
X81752Y448929D01*
X80717D01*
G01X77732Y445829D02*
Y448929D01*
X79150Y446707D01*
X77234D01*
G01X90381Y613890D02*
X90611Y614045D01*
X90879Y614148D01*
X91186D01*
X91531Y613993D01*
X91799Y613735D01*
X91991Y613425D01*
X92144Y612908D01*
X92182Y612443D01*
X92106Y611978D01*
X91991Y611668D01*
X91761Y611358D01*
X91492Y611151D01*
X91224Y611048D01*
X90956D01*
X90687Y611151D01*
X90457Y611306D01*
X90266Y611513D01*
G01X88967D02*
X88737Y611255D01*
X88469Y611100D01*
X88124Y611048D01*
X87779Y611151D01*
X87511Y611358D01*
X87319Y611720D01*
X87281Y612133D01*
X87357Y612546D01*
X87549Y612805D01*
X87817Y613011D01*
X88086Y613063D01*
X88354Y613011D01*
X88699Y612805D01*
X88584Y614148D01*
X87549D01*
G01X85024Y611048D02*
Y614148D01*
X85484Y613528D01*
G01Y611048D02*
X84564D01*
G01X81464D02*
Y614148D01*
X82882Y611926D01*
X80966D01*
G01X90381Y618390D02*
X90611Y618545D01*
X90879Y618648D01*
X91186D01*
X91531Y618493D01*
X91799Y618235D01*
X91991Y617925D01*
X92144Y617408D01*
X92182Y616943D01*
X92106Y616478D01*
X91991Y616168D01*
X91761Y615858D01*
X91492Y615651D01*
X91224Y615548D01*
X90956D01*
X90687Y615651D01*
X90457Y615806D01*
X90266Y616013D01*
G01X88967D02*
X88737Y615755D01*
X88469Y615600D01*
X88124Y615548D01*
X87779Y615651D01*
X87511Y615858D01*
X87319Y616220D01*
X87281Y616633D01*
X87357Y617046D01*
X87549Y617305D01*
X87817Y617511D01*
X88086Y617563D01*
X88354Y617511D01*
X88699Y617305D01*
X88584Y618648D01*
X87549D01*
G01X85024Y615548D02*
Y618648D01*
X85484Y618028D01*
G01Y615548D02*
X84564D01*
G01X82652Y618131D02*
X82422Y618441D01*
X82154Y618596D01*
X81847Y618648D01*
X81464Y618545D01*
X81196Y618286D01*
X81119Y617976D01*
X81157Y617666D01*
X81311Y617408D01*
X82077Y616891D01*
X82422Y616530D01*
X82652Y616013D01*
X82729Y615548D01*
X81119D01*
G01X90381Y622890D02*
X90611Y623045D01*
X90879Y623148D01*
X91186D01*
X91531Y622993D01*
X91799Y622735D01*
X91991Y622425D01*
X92144Y621908D01*
X92182Y621443D01*
X92106Y620978D01*
X91991Y620668D01*
X91761Y620358D01*
X91492Y620151D01*
X91224Y620048D01*
X90956D01*
X90687Y620151D01*
X90457Y620306D01*
X90266Y620513D01*
G01X88967D02*
X88737Y620255D01*
X88469Y620100D01*
X88124Y620048D01*
X87779Y620151D01*
X87511Y620358D01*
X87319Y620720D01*
X87281Y621133D01*
X87357Y621546D01*
X87549Y621805D01*
X87817Y622011D01*
X88086Y622063D01*
X88354Y622011D01*
X88699Y621805D01*
X88584Y623148D01*
X87549D01*
G01X85024Y620048D02*
Y623148D01*
X85484Y622528D01*
G01Y620048D02*
X84564D01*
G01X82767Y620668D02*
X82537Y620306D01*
X82231Y620100D01*
X81886Y620048D01*
X81579Y620100D01*
X81272Y620358D01*
X81081Y620668D01*
X81042Y620978D01*
X81119Y621340D01*
X81387Y621598D01*
X81656Y621701D01*
X82001D01*
G01X81656D02*
X81426Y621856D01*
X81234Y622115D01*
X81157Y622425D01*
X81234Y622735D01*
X81426Y622993D01*
X81771Y623148D01*
X82116Y623096D01*
X82461Y622890D01*
G01X91065Y20990D02*
X90835Y20628D01*
X90529Y20422D01*
X90184Y20370D01*
X89877Y20422D01*
X89570Y20680D01*
X89379Y20990D01*
X89340Y21300D01*
X89417Y21662D01*
X89685Y21920D01*
X89954Y22023D01*
X90299D01*
G01X89954D02*
X89724Y22178D01*
X89532Y22437D01*
X89455Y22747D01*
X89532Y23057D01*
X89724Y23315D01*
X90069Y23470D01*
X90414Y23418D01*
X90759Y23212D01*
G01X87738Y150333D02*
X87508Y150643D01*
X87240Y150798D01*
X86933Y150850D01*
X86550Y150747D01*
X86282Y150488D01*
X86205Y150178D01*
X86243Y149868D01*
X86397Y149610D01*
X87163Y149093D01*
X87508Y148732D01*
X87738Y148215D01*
X87815Y147750D01*
X86205D01*
G01X111462Y247244D02*
G02I-9100J0D01*
G01X95940Y287610D02*
Y271490D01*
G01X134410Y287610D02*
X95940D01*
G01X95222Y289594D02*
X98322D01*
Y290553D01*
X98167Y290859D01*
X97960Y291051D01*
X97547Y291128D01*
X97134Y291051D01*
X96875Y290821D01*
X96720Y290553D01*
Y289594D01*
G01Y290553D02*
X95222Y291128D01*
G01X95842Y292618D02*
X95480Y292848D01*
X95274Y293154D01*
X95222Y293499D01*
X95274Y293806D01*
X95532Y294113D01*
X95842Y294304D01*
X96152Y294343D01*
X96514Y294266D01*
X96772Y293998D01*
X96875Y293729D01*
Y293384D01*
G01Y293729D02*
X97030Y293959D01*
X97289Y294151D01*
X97599Y294228D01*
X97909Y294151D01*
X98167Y293959D01*
X98322Y293614D01*
X98270Y293269D01*
X98064Y292924D01*
G01X97805Y295833D02*
X98115Y296063D01*
X98270Y296331D01*
X98322Y296638D01*
X98219Y297021D01*
X97960Y297289D01*
X97650Y297366D01*
X97340Y297328D01*
X97082Y297174D01*
X96565Y296408D01*
X96204Y296063D01*
X95687Y295833D01*
X95222Y295756D01*
Y297366D01*
G01Y299661D02*
X95274Y299929D01*
X95429Y300236D01*
X95687Y300428D01*
X96049Y300504D01*
X96410Y300428D01*
X96720Y300198D01*
X96875Y299853D01*
Y299469D01*
X96979Y299239D01*
X97237Y299048D01*
X97599Y298971D01*
X97960Y299086D01*
X98219Y299354D01*
X98322Y299661D01*
X98219Y299968D01*
X97960Y300236D01*
X97599Y300351D01*
X97237Y300274D01*
X96979Y300083D01*
X96875Y299853D01*
Y299469D01*
X96720Y299124D01*
X96410Y298894D01*
X96049Y298818D01*
X95687Y298894D01*
X95429Y299086D01*
X95274Y299393D01*
X95222Y299661D01*
G01X93832Y303912D02*
X93987Y303682D01*
X94090Y303414D01*
Y303107D01*
X93935Y302762D01*
X93677Y302494D01*
X93367Y302302D01*
X92850Y302149D01*
X92385Y302111D01*
X91920Y302187D01*
X91610Y302302D01*
X91300Y302532D01*
X91093Y302801D01*
X90990Y303069D01*
Y303337D01*
X91093Y303606D01*
X91248Y303836D01*
X91455Y304027D01*
G01X93573Y305441D02*
X93883Y305671D01*
X94038Y305939D01*
X94090Y306246D01*
X93987Y306629D01*
X93728Y306897D01*
X93418Y306974D01*
X93108Y306936D01*
X92850Y306782D01*
X92333Y306016D01*
X91972Y305671D01*
X91455Y305441D01*
X90990Y305364D01*
Y306974D01*
G01X91455Y308426D02*
X91197Y308656D01*
X91042Y308924D01*
X90990Y309269D01*
X91093Y309614D01*
X91300Y309882D01*
X91662Y310074D01*
X92075Y310112D01*
X92488Y310036D01*
X92747Y309844D01*
X92953Y309576D01*
X93005Y309307D01*
X92953Y309039D01*
X92747Y308694D01*
X94090Y308809D01*
Y309844D01*
G01X91610Y311526D02*
X91248Y311756D01*
X91042Y312062D01*
X90990Y312407D01*
X91042Y312714D01*
X91300Y313021D01*
X91610Y313212D01*
X91920Y313251D01*
X92282Y313174D01*
X92540Y312906D01*
X92643Y312637D01*
Y312292D01*
G01Y312637D02*
X92798Y312867D01*
X93057Y313059D01*
X93367Y313136D01*
X93677Y313059D01*
X93935Y312867D01*
X94090Y312522D01*
X94038Y312177D01*
X93832Y311832D01*
G01X89641Y303912D02*
X89796Y303682D01*
X89899Y303414D01*
Y303107D01*
X89744Y302762D01*
X89486Y302494D01*
X89176Y302302D01*
X88659Y302149D01*
X88194Y302111D01*
X87729Y302187D01*
X87419Y302302D01*
X87109Y302532D01*
X86902Y302801D01*
X86799Y303069D01*
Y303337D01*
X86902Y303606D01*
X87057Y303836D01*
X87264Y304027D01*
G01X89382Y305441D02*
X89692Y305671D01*
X89847Y305939D01*
X89899Y306246D01*
X89796Y306629D01*
X89537Y306897D01*
X89227Y306974D01*
X88917Y306936D01*
X88659Y306782D01*
X88142Y306016D01*
X87781Y305671D01*
X87264Y305441D01*
X86799Y305364D01*
Y306974D01*
G01X87161Y308617D02*
X86902Y308886D01*
X86799Y309192D01*
X86902Y309499D01*
X87212Y309767D01*
X87677Y309959D01*
X88142Y310036D01*
X88711D01*
X89176Y309959D01*
X89589Y309767D01*
X89796Y309537D01*
X89899Y309269D01*
X89796Y308962D01*
X89589Y308732D01*
X89279Y308579D01*
X88866Y308502D01*
X88504Y308579D01*
X88142Y308771D01*
X87936Y309001D01*
X87884Y309269D01*
X87987Y309576D01*
X88246Y309806D01*
X88711Y310036D01*
G01X87419Y311526D02*
X87057Y311756D01*
X86851Y312062D01*
X86799Y312407D01*
X86851Y312714D01*
X87109Y313021D01*
X87419Y313212D01*
X87729Y313251D01*
X88091Y313174D01*
X88349Y312906D01*
X88452Y312637D01*
Y312292D01*
G01Y312637D02*
X88607Y312867D01*
X88866Y313059D01*
X89176Y313136D01*
X89486Y313059D01*
X89744Y312867D01*
X89899Y312522D01*
X89847Y312177D01*
X89641Y311832D01*
G01X98064Y303912D02*
X98219Y303682D01*
X98322Y303414D01*
Y303107D01*
X98167Y302762D01*
X97909Y302494D01*
X97599Y302302D01*
X97082Y302149D01*
X96617Y302111D01*
X96152Y302187D01*
X95842Y302302D01*
X95532Y302532D01*
X95325Y302801D01*
X95222Y303069D01*
Y303337D01*
X95325Y303606D01*
X95480Y303836D01*
X95687Y304027D01*
G01X97805Y305441D02*
X98115Y305671D01*
X98270Y305939D01*
X98322Y306246D01*
X98219Y306629D01*
X97960Y306897D01*
X97650Y306974D01*
X97340Y306936D01*
X97082Y306782D01*
X96565Y306016D01*
X96204Y305671D01*
X95687Y305441D01*
X95222Y305364D01*
Y306974D01*
G01X95687Y308426D02*
X95429Y308656D01*
X95274Y308924D01*
X95222Y309269D01*
X95325Y309614D01*
X95532Y309882D01*
X95894Y310074D01*
X96307Y310112D01*
X96720Y310036D01*
X96979Y309844D01*
X97185Y309576D01*
X97237Y309307D01*
X97185Y309039D01*
X96979Y308694D01*
X98322Y308809D01*
Y309844D01*
G01X95222Y312829D02*
X98322D01*
X96100Y311411D01*
Y313327D01*
G01X99466Y328269D02*
X99696Y328424D01*
X99964Y328527D01*
X100271D01*
X100616Y328372D01*
X100884Y328114D01*
X101076Y327804D01*
X101229Y327287D01*
X101267Y326822D01*
X101191Y326357D01*
X101076Y326047D01*
X100846Y325737D01*
X100577Y325530D01*
X100309Y325427D01*
X100041D01*
X99772Y325530D01*
X99542Y325685D01*
X99351Y325892D01*
G01X97937Y328010D02*
X97707Y328320D01*
X97439Y328475D01*
X97132Y328527D01*
X96749Y328424D01*
X96481Y328165D01*
X96404Y327855D01*
X96442Y327545D01*
X96596Y327287D01*
X97362Y326770D01*
X97707Y326409D01*
X97937Y325892D01*
X98014Y325427D01*
X96404D01*
G01X94952Y325892D02*
X94722Y325634D01*
X94454Y325479D01*
X94109Y325427D01*
X93764Y325530D01*
X93496Y325737D01*
X93304Y326099D01*
X93266Y326512D01*
X93342Y326925D01*
X93534Y327184D01*
X93802Y327390D01*
X94071Y327442D01*
X94339Y327390D01*
X94684Y327184D01*
X94569Y328527D01*
X93534D01*
G01X91009Y325427D02*
Y328527D01*
X91469Y327907D01*
G01Y325427D02*
X90549D01*
G01X92040Y339340D02*
X116090D01*
G01X92040Y352990D02*
Y339340D01*
G01X111462Y349606D02*
G02I-9100J0D01*
G01X89812Y341335D02*
X89967Y341105D01*
X90070Y340837D01*
Y340530D01*
X89915Y340185D01*
X89657Y339917D01*
X89347Y339725D01*
X88830Y339572D01*
X88365Y339534D01*
X87900Y339610D01*
X87590Y339725D01*
X87280Y339955D01*
X87073Y340224D01*
X86970Y340492D01*
Y340760D01*
X87073Y341029D01*
X87228Y341259D01*
X87435Y341450D01*
G01X89553Y342864D02*
X89863Y343094D01*
X90018Y343362D01*
X90070Y343669D01*
X89967Y344052D01*
X89708Y344320D01*
X89398Y344397D01*
X89088Y344359D01*
X88830Y344205D01*
X88313Y343439D01*
X87952Y343094D01*
X87435Y342864D01*
X86970Y342787D01*
Y344397D01*
G01Y347152D02*
X90070D01*
X87848Y345734D01*
Y347650D01*
G01X89553Y349064D02*
X89863Y349294D01*
X90018Y349562D01*
X90070Y349869D01*
X89967Y350252D01*
X89708Y350520D01*
X89398Y350597D01*
X89088Y350559D01*
X88830Y350405D01*
X88313Y349639D01*
X87952Y349294D01*
X87435Y349064D01*
X86970Y348987D01*
Y350597D01*
G01X99466Y332992D02*
X99696Y333147D01*
X99964Y333250D01*
X100271D01*
X100616Y333095D01*
X100884Y332837D01*
X101076Y332527D01*
X101229Y332010D01*
X101267Y331545D01*
X101191Y331080D01*
X101076Y330770D01*
X100846Y330460D01*
X100577Y330253D01*
X100309Y330150D01*
X100041D01*
X99772Y330253D01*
X99542Y330408D01*
X99351Y330615D01*
G01X97937Y332733D02*
X97707Y333043D01*
X97439Y333198D01*
X97132Y333250D01*
X96749Y333147D01*
X96481Y332888D01*
X96404Y332578D01*
X96442Y332268D01*
X96596Y332010D01*
X97362Y331493D01*
X97707Y331132D01*
X97937Y330615D01*
X98014Y330150D01*
X96404D01*
G01X94952Y330615D02*
X94722Y330357D01*
X94454Y330202D01*
X94109Y330150D01*
X93764Y330253D01*
X93496Y330460D01*
X93304Y330822D01*
X93266Y331235D01*
X93342Y331648D01*
X93534Y331907D01*
X93802Y332113D01*
X94071Y332165D01*
X94339Y332113D01*
X94684Y331907D01*
X94569Y333250D01*
X93534D01*
G01X91009D02*
X91316Y333147D01*
X91546Y332888D01*
X91699Y332578D01*
X91814Y332165D01*
X91852Y331700D01*
X91814Y331235D01*
X91699Y330822D01*
X91546Y330512D01*
X91316Y330253D01*
X91009Y330150D01*
X90702Y330253D01*
X90472Y330512D01*
X90319Y330822D01*
X90204Y331235D01*
X90166Y331700D01*
X90204Y332165D01*
X90319Y332578D01*
X90472Y332888D01*
X90702Y333147D01*
X91009Y333250D01*
G01X93887Y423643D02*
Y430243D01*
G01X86387Y423543D02*
X101387D01*
G01X86387Y430343D02*
Y423543D01*
G01X101387Y430343D02*
X86387D01*
G01X93887Y432643D02*
Y439243D01*
G01X86387Y432543D02*
X101387D01*
G01X86387Y439343D02*
Y432543D01*
G01X101387Y439343D02*
X86387D01*
G01X93887Y441643D02*
Y448243D01*
G01X86387Y441543D02*
X101387D01*
G01X86387Y448343D02*
Y441543D01*
G01X101387Y448343D02*
X86387D01*
G01X99448Y455594D02*
X99678Y455749D01*
X99946Y455852D01*
X100253D01*
X100598Y455697D01*
X100866Y455439D01*
X101058Y455129D01*
X101211Y454612D01*
X101249Y454147D01*
X101173Y453682D01*
X101058Y453372D01*
X100828Y453062D01*
X100559Y452855D01*
X100291Y452752D01*
X100023D01*
X99754Y452855D01*
X99524Y453010D01*
X99333Y453217D01*
G01X97843Y453114D02*
X97574Y452855D01*
X97268Y452752D01*
X96961Y452855D01*
X96693Y453165D01*
X96501Y453630D01*
X96424Y454095D01*
Y454664D01*
X96501Y455129D01*
X96693Y455542D01*
X96923Y455749D01*
X97191Y455852D01*
X97498Y455749D01*
X97728Y455542D01*
X97881Y455232D01*
X97958Y454819D01*
X97881Y454457D01*
X97689Y454095D01*
X97459Y453889D01*
X97191Y453837D01*
X96884Y453940D01*
X96654Y454199D01*
X96424Y454664D01*
G01X94168Y452752D02*
X94091Y453424D01*
X93976Y453992D01*
X93823Y454509D01*
X93631Y455077D01*
X93324Y455852D01*
X94858D01*
G01X99522Y463153D02*
X99752Y463308D01*
X100020Y463411D01*
X100327D01*
X100672Y463256D01*
X100940Y462998D01*
X101132Y462688D01*
X101285Y462171D01*
X101323Y461706D01*
X101247Y461241D01*
X101132Y460931D01*
X100902Y460621D01*
X100633Y460414D01*
X100365Y460311D01*
X100097D01*
X99828Y460414D01*
X99598Y460569D01*
X99407Y460776D01*
G01X97917Y460673D02*
X97648Y460414D01*
X97342Y460311D01*
X97035Y460414D01*
X96767Y460724D01*
X96575Y461189D01*
X96498Y461654D01*
Y462223D01*
X96575Y462688D01*
X96767Y463101D01*
X96997Y463308D01*
X97265Y463411D01*
X97572Y463308D01*
X97802Y463101D01*
X97955Y462791D01*
X98032Y462378D01*
X97955Y462016D01*
X97763Y461654D01*
X97533Y461448D01*
X97265Y461396D01*
X96958Y461499D01*
X96728Y461758D01*
X96498Y462223D01*
G01X94893Y461603D02*
X94625Y461964D01*
X94395Y462171D01*
X94088Y462274D01*
X93820Y462171D01*
X93628Y461964D01*
X93475Y461654D01*
X93437Y461293D01*
X93475Y460983D01*
X93628Y460673D01*
X93858Y460414D01*
X94127Y460311D01*
X94433Y460414D01*
X94702Y460724D01*
X94855Y461189D01*
X94893Y461706D01*
X94817Y462378D01*
X94702Y462739D01*
X94510Y463101D01*
X94242Y463359D01*
X93973Y463411D01*
X93705Y463308D01*
X93513Y463049D01*
G01X100964Y613518D02*
Y610318D01*
G01D02*
X107164D01*
G01Y618018D02*
X100964D01*
G01D02*
Y614818D01*
G01D02*
X107164D01*
G01Y622518D02*
X100964D01*
G01D02*
Y619318D01*
G01D02*
X107164D01*
G01Y613518D02*
X100964D01*
G01X103703Y637174D02*
X103933Y637329D01*
X104201Y637432D01*
X104508D01*
X104853Y637277D01*
X105121Y637019D01*
X105313Y636709D01*
X105466Y636192D01*
X105504Y635727D01*
X105428Y635262D01*
X105313Y634952D01*
X105083Y634642D01*
X104814Y634435D01*
X104546Y634332D01*
X104278D01*
X104009Y634435D01*
X103779Y634590D01*
X103588Y634797D01*
G01X102289D02*
X102059Y634539D01*
X101791Y634384D01*
X101446Y634332D01*
X101101Y634435D01*
X100833Y634642D01*
X100641Y635004D01*
X100603Y635417D01*
X100679Y635830D01*
X100871Y636089D01*
X101139Y636295D01*
X101408Y636347D01*
X101676Y636295D01*
X102021Y636089D01*
X101906Y637432D01*
X100871D01*
G01X98346Y634332D02*
Y637432D01*
X98806Y636812D01*
G01Y634332D02*
X97886D01*
G01X95246Y637432D02*
X95553Y637329D01*
X95783Y637070D01*
X95936Y636760D01*
X96051Y636347D01*
X96089Y635882D01*
X96051Y635417D01*
X95936Y635004D01*
X95783Y634694D01*
X95553Y634435D01*
X95246Y634332D01*
X94939Y634435D01*
X94709Y634694D01*
X94556Y635004D01*
X94441Y635417D01*
X94403Y635882D01*
X94441Y636347D01*
X94556Y636760D01*
X94709Y637070D01*
X94939Y637329D01*
X95246Y637432D01*
G01X100696Y645945D02*
Y642745D01*
G01D02*
X106896D01*
G01X103737Y641446D02*
X103967Y641601D01*
X104235Y641704D01*
X104542D01*
X104887Y641549D01*
X105155Y641291D01*
X105347Y640981D01*
X105500Y640464D01*
X105538Y639999D01*
X105462Y639534D01*
X105347Y639224D01*
X105117Y638914D01*
X104848Y638707D01*
X104580Y638604D01*
X104312D01*
X104043Y638707D01*
X103813Y638862D01*
X103622Y639069D01*
G01X102323D02*
X102093Y638811D01*
X101825Y638656D01*
X101480Y638604D01*
X101135Y638707D01*
X100867Y638914D01*
X100675Y639276D01*
X100637Y639689D01*
X100713Y640102D01*
X100905Y640361D01*
X101173Y640567D01*
X101442Y640619D01*
X101710Y640567D01*
X102055Y640361D01*
X101940Y641704D01*
X100905D01*
G01X98380Y638604D02*
Y641704D01*
X98840Y641084D01*
G01Y638604D02*
X97920D01*
G01X95280D02*
Y641704D01*
X95740Y641084D01*
G01Y638604D02*
X94820D01*
G01X106896Y645945D02*
X100696D01*
G01X106930Y650217D02*
X100730D01*
G01D02*
Y647017D01*
G01D02*
X106930D01*
G01X119803Y299037D02*
X119958Y298807D01*
X120061Y298539D01*
Y298232D01*
X119906Y297887D01*
X119648Y297619D01*
X119338Y297427D01*
X118821Y297274D01*
X118356Y297236D01*
X117891Y297312D01*
X117581Y297427D01*
X117271Y297657D01*
X117064Y297926D01*
X116961Y298194D01*
Y298462D01*
X117064Y298731D01*
X117219Y298961D01*
X117426Y299152D01*
G01X119544Y300566D02*
X119854Y300796D01*
X120009Y301064D01*
X120061Y301371D01*
X119958Y301754D01*
X119699Y302022D01*
X119389Y302099D01*
X119079Y302061D01*
X118821Y301907D01*
X118304Y301141D01*
X117943Y300796D01*
X117426Y300566D01*
X116961Y300489D01*
Y302099D01*
G01X117426Y303551D02*
X117168Y303781D01*
X117013Y304049D01*
X116961Y304394D01*
X117064Y304739D01*
X117271Y305007D01*
X117633Y305199D01*
X118046Y305237D01*
X118459Y305161D01*
X118718Y304969D01*
X118924Y304701D01*
X118976Y304432D01*
X118924Y304164D01*
X118718Y303819D01*
X120061Y303934D01*
Y304969D01*
G01X118253Y306766D02*
X118614Y307034D01*
X118821Y307264D01*
X118924Y307571D01*
X118821Y307839D01*
X118614Y308031D01*
X118304Y308184D01*
X117943Y308222D01*
X117633Y308184D01*
X117323Y308031D01*
X117064Y307801D01*
X116961Y307532D01*
X117064Y307226D01*
X117374Y306957D01*
X117839Y306804D01*
X118356Y306766D01*
X119028Y306842D01*
X119389Y306957D01*
X119751Y307149D01*
X120009Y307417D01*
X120061Y307686D01*
X119958Y307954D01*
X119699Y308146D01*
G01X112942Y332854D02*
X113172Y333009D01*
X113440Y333112D01*
X113747D01*
X114092Y332957D01*
X114360Y332699D01*
X114552Y332389D01*
X114705Y331872D01*
X114743Y331407D01*
X114667Y330942D01*
X114552Y330632D01*
X114322Y330322D01*
X114053Y330115D01*
X113785Y330012D01*
X113517D01*
X113248Y330115D01*
X113018Y330270D01*
X112827Y330477D01*
G01X111413Y332595D02*
X111183Y332905D01*
X110915Y333060D01*
X110608Y333112D01*
X110225Y333009D01*
X109957Y332750D01*
X109880Y332440D01*
X109918Y332130D01*
X110072Y331872D01*
X110838Y331355D01*
X111183Y330994D01*
X111413Y330477D01*
X111490Y330012D01*
X109880D01*
G01X108237Y330374D02*
X107968Y330115D01*
X107662Y330012D01*
X107355Y330115D01*
X107087Y330425D01*
X106895Y330890D01*
X106818Y331355D01*
Y331924D01*
X106895Y332389D01*
X107087Y332802D01*
X107317Y333009D01*
X107585Y333112D01*
X107892Y333009D01*
X108122Y332802D01*
X108275Y332492D01*
X108352Y332079D01*
X108275Y331717D01*
X108083Y331355D01*
X107853Y331149D01*
X107585Y331097D01*
X107278Y331200D01*
X107048Y331459D01*
X106818Y331924D01*
G01X104485Y330012D02*
Y333112D01*
X104945Y332492D01*
G01Y330012D02*
X104025D01*
G01X112942Y328131D02*
X113172Y328286D01*
X113440Y328389D01*
X113747D01*
X114092Y328234D01*
X114360Y327976D01*
X114552Y327666D01*
X114705Y327149D01*
X114743Y326684D01*
X114667Y326219D01*
X114552Y325909D01*
X114322Y325599D01*
X114053Y325392D01*
X113785Y325289D01*
X113517D01*
X113248Y325392D01*
X113018Y325547D01*
X112827Y325754D01*
G01X111413Y327872D02*
X111183Y328182D01*
X110915Y328337D01*
X110608Y328389D01*
X110225Y328286D01*
X109957Y328027D01*
X109880Y327717D01*
X109918Y327407D01*
X110072Y327149D01*
X110838Y326632D01*
X111183Y326271D01*
X111413Y325754D01*
X111490Y325289D01*
X109880D01*
G01X108237Y325651D02*
X107968Y325392D01*
X107662Y325289D01*
X107355Y325392D01*
X107087Y325702D01*
X106895Y326167D01*
X106818Y326632D01*
Y327201D01*
X106895Y327666D01*
X107087Y328079D01*
X107317Y328286D01*
X107585Y328389D01*
X107892Y328286D01*
X108122Y328079D01*
X108275Y327769D01*
X108352Y327356D01*
X108275Y326994D01*
X108083Y326632D01*
X107853Y326426D01*
X107585Y326374D01*
X107278Y326477D01*
X107048Y326736D01*
X106818Y327201D01*
G01X105213Y327872D02*
X104983Y328182D01*
X104715Y328337D01*
X104408Y328389D01*
X104025Y328286D01*
X103757Y328027D01*
X103680Y327717D01*
X103718Y327407D01*
X103872Y327149D01*
X104638Y326632D01*
X104983Y326271D01*
X105213Y325754D01*
X105290Y325289D01*
X103680D01*
G01X118416Y326659D02*
X118571Y326429D01*
X118674Y326161D01*
Y325854D01*
X118519Y325509D01*
X118261Y325241D01*
X117951Y325049D01*
X117434Y324896D01*
X116969Y324858D01*
X116504Y324934D01*
X116194Y325049D01*
X115884Y325279D01*
X115677Y325548D01*
X115574Y325816D01*
Y326084D01*
X115677Y326353D01*
X115832Y326583D01*
X116039Y326774D01*
G01X118157Y328188D02*
X118467Y328418D01*
X118622Y328686D01*
X118674Y328993D01*
X118571Y329376D01*
X118312Y329644D01*
X118002Y329721D01*
X117692Y329683D01*
X117434Y329529D01*
X116917Y328763D01*
X116556Y328418D01*
X116039Y328188D01*
X115574Y328111D01*
Y329721D01*
G01Y332476D02*
X118674D01*
X116452Y331058D01*
Y332974D01*
G01X116194Y334273D02*
X115832Y334503D01*
X115626Y334809D01*
X115574Y335154D01*
X115626Y335461D01*
X115884Y335768D01*
X116194Y335959D01*
X116504Y335998D01*
X116866Y335921D01*
X117124Y335653D01*
X117227Y335384D01*
Y335039D01*
G01Y335384D02*
X117382Y335614D01*
X117641Y335806D01*
X117951Y335883D01*
X118261Y335806D01*
X118519Y335614D01*
X118674Y335269D01*
X118622Y334924D01*
X118416Y334579D01*
G01X116090Y344020D02*
X134410D01*
G01X116090Y339340D02*
Y344020D01*
G01X115355Y420853D02*
Y405853D01*
G01D02*
X122155D01*
G01X107554Y415308D02*
X107709Y415078D01*
X107812Y414810D01*
Y414503D01*
X107657Y414158D01*
X107399Y413890D01*
X107089Y413698D01*
X106572Y413545D01*
X106107Y413507D01*
X105642Y413583D01*
X105332Y413698D01*
X105022Y413928D01*
X104815Y414197D01*
X104712Y414465D01*
Y414733D01*
X104815Y415002D01*
X104970Y415232D01*
X105177Y415423D01*
G01X104712Y417565D02*
X104764Y417833D01*
X104919Y418140D01*
X105177Y418332D01*
X105539Y418408D01*
X105900Y418332D01*
X106210Y418102D01*
X106365Y417757D01*
Y417373D01*
X106469Y417143D01*
X106727Y416952D01*
X107089Y416875D01*
X107450Y416990D01*
X107709Y417258D01*
X107812Y417565D01*
X107709Y417872D01*
X107450Y418140D01*
X107089Y418255D01*
X106727Y418178D01*
X106469Y417987D01*
X106365Y417757D01*
Y417373D01*
X106210Y417028D01*
X105900Y416798D01*
X105539Y416722D01*
X105177Y416798D01*
X104919Y416990D01*
X104764Y417297D01*
X104712Y417565D01*
G01Y420665D02*
X107812D01*
X107192Y420205D01*
G01X104712D02*
Y421125D01*
G01Y423765D02*
X104764Y424033D01*
X104919Y424340D01*
X105177Y424532D01*
X105539Y424608D01*
X105900Y424532D01*
X106210Y424302D01*
X106365Y423957D01*
Y423573D01*
X106469Y423343D01*
X106727Y423152D01*
X107089Y423075D01*
X107450Y423190D01*
X107709Y423458D01*
X107812Y423765D01*
X107709Y424072D01*
X107450Y424340D01*
X107089Y424455D01*
X106727Y424378D01*
X106469Y424187D01*
X106365Y423957D01*
Y423573D01*
X106210Y423228D01*
X105900Y422998D01*
X105539Y422922D01*
X105177Y422998D01*
X104919Y423190D01*
X104764Y423497D01*
X104712Y423765D01*
G01X122155Y420853D02*
X115355D01*
G01X122055Y413353D02*
X115455D01*
G01X111735Y415045D02*
X111890Y414815D01*
X111993Y414547D01*
Y414240D01*
X111838Y413895D01*
X111580Y413627D01*
X111270Y413435D01*
X110753Y413282D01*
X110288Y413244D01*
X109823Y413320D01*
X109513Y413435D01*
X109203Y413665D01*
X108996Y413934D01*
X108893Y414202D01*
Y414470D01*
X108996Y414739D01*
X109151Y414969D01*
X109358Y415160D01*
G01X108893Y417302D02*
X108945Y417570D01*
X109100Y417877D01*
X109358Y418069D01*
X109720Y418145D01*
X110081Y418069D01*
X110391Y417839D01*
X110546Y417494D01*
Y417110D01*
X110650Y416880D01*
X110908Y416689D01*
X111270Y416612D01*
X111631Y416727D01*
X111890Y416995D01*
X111993Y417302D01*
X111890Y417609D01*
X111631Y417877D01*
X111270Y417992D01*
X110908Y417915D01*
X110650Y417724D01*
X110546Y417494D01*
Y417110D01*
X110391Y416765D01*
X110081Y416535D01*
X109720Y416459D01*
X109358Y416535D01*
X109100Y416727D01*
X108945Y417034D01*
X108893Y417302D01*
G01X111476Y419674D02*
X111786Y419904D01*
X111941Y420172D01*
X111993Y420479D01*
X111890Y420862D01*
X111631Y421130D01*
X111321Y421207D01*
X111011Y421169D01*
X110753Y421015D01*
X110236Y420249D01*
X109875Y419904D01*
X109358Y419674D01*
X108893Y419597D01*
Y421207D01*
G01X111993Y423502D02*
X111890Y423195D01*
X111631Y422965D01*
X111321Y422812D01*
X110908Y422697D01*
X110443Y422659D01*
X109978Y422697D01*
X109565Y422812D01*
X109255Y422965D01*
X108996Y423195D01*
X108893Y423502D01*
X108996Y423809D01*
X109255Y424039D01*
X109565Y424192D01*
X109978Y424307D01*
X110443Y424345D01*
X110908Y424307D01*
X111321Y424192D01*
X111631Y424039D01*
X111890Y423809D01*
X111993Y423502D01*
G01X101387Y423543D02*
Y430343D01*
G01Y432543D02*
Y439343D01*
G01Y441543D02*
Y448343D01*
G01X110118Y450336D02*
Y456936D01*
G01X102618Y450236D02*
X117618D01*
G01X102618Y457036D02*
Y450236D01*
G01X117618Y457036D02*
X102618D01*
G01X111184Y465518D02*
Y458118D01*
G01X102484D02*
X119884D01*
G01X102484Y465518D02*
Y458118D01*
G01X119884Y465518D02*
X102484D01*
G01X160870Y631811D02*
X186259D01*
Y629867D01*
X196226D01*
Y592003D01*
X186259D01*
Y585672D01*
X144634D01*
Y609011D01*
X114983D01*
Y623348D01*
X102758D01*
Y629178D01*
X109341D01*
Y661148D01*
X134416D01*
Y667249D01*
X157548D01*
Y636073D01*
X157673D01*
G01X104064Y610418D02*
Y613418D01*
G01X107164Y610318D02*
Y613518D01*
G01X104064Y614918D02*
Y617918D01*
G01X107164Y614818D02*
Y618018D01*
G01X104064Y619418D02*
Y622418D01*
G01X107164Y619318D02*
Y622518D01*
G01X120427Y624869D02*
X120582Y624639D01*
X120685Y624371D01*
Y624064D01*
X120530Y623719D01*
X120272Y623451D01*
X119962Y623259D01*
X119445Y623106D01*
X118980Y623068D01*
X118515Y623144D01*
X118205Y623259D01*
X117895Y623489D01*
X117688Y623758D01*
X117585Y624026D01*
Y624294D01*
X117688Y624563D01*
X117843Y624793D01*
X118050Y624984D01*
G01X118205Y626283D02*
X117843Y626513D01*
X117637Y626819D01*
X117585Y627164D01*
X117637Y627471D01*
X117895Y627778D01*
X118205Y627969D01*
X118515Y628008D01*
X118877Y627931D01*
X119135Y627663D01*
X119238Y627394D01*
Y627049D01*
G01Y627394D02*
X119393Y627624D01*
X119652Y627816D01*
X119962Y627893D01*
X120272Y627816D01*
X120530Y627624D01*
X120685Y627279D01*
X120633Y626934D01*
X120427Y626589D01*
G01X117947Y629574D02*
X117688Y629843D01*
X117585Y630149D01*
X117688Y630456D01*
X117998Y630724D01*
X118463Y630916D01*
X118928Y630993D01*
X119497D01*
X119962Y630916D01*
X120375Y630724D01*
X120582Y630494D01*
X120685Y630226D01*
X120582Y629919D01*
X120375Y629689D01*
X120065Y629536D01*
X119652Y629459D01*
X119290Y629536D01*
X118928Y629728D01*
X118722Y629958D01*
X118670Y630226D01*
X118773Y630533D01*
X119032Y630763D01*
X119497Y630993D01*
G01X118050Y632483D02*
X117792Y632713D01*
X117637Y632981D01*
X117585Y633326D01*
X117688Y633671D01*
X117895Y633939D01*
X118257Y634131D01*
X118670Y634169D01*
X119083Y634093D01*
X119342Y633901D01*
X119548Y633633D01*
X119600Y633364D01*
X119548Y633096D01*
X119342Y632751D01*
X120685Y632866D01*
Y633901D01*
G01X113461Y627162D02*
X113691Y627317D01*
X113959Y627420D01*
X114266D01*
X114611Y627265D01*
X114879Y627007D01*
X115071Y626697D01*
X115224Y626180D01*
X115262Y625715D01*
X115186Y625250D01*
X115071Y624940D01*
X114841Y624630D01*
X114572Y624423D01*
X114304Y624320D01*
X114036D01*
X113767Y624423D01*
X113537Y624578D01*
X113346Y624785D01*
G01X112047Y624940D02*
X111817Y624578D01*
X111511Y624372D01*
X111166Y624320D01*
X110859Y624372D01*
X110552Y624630D01*
X110361Y624940D01*
X110322Y625250D01*
X110399Y625612D01*
X110667Y625870D01*
X110936Y625973D01*
X111281D01*
G01X110936D02*
X110706Y626128D01*
X110514Y626387D01*
X110437Y626697D01*
X110514Y627007D01*
X110706Y627265D01*
X111051Y627420D01*
X111396Y627368D01*
X111741Y627162D01*
G01X108756Y624682D02*
X108487Y624423D01*
X108181Y624320D01*
X107874Y624423D01*
X107606Y624733D01*
X107414Y625198D01*
X107337Y625663D01*
Y626232D01*
X107414Y626697D01*
X107606Y627110D01*
X107836Y627317D01*
X108104Y627420D01*
X108411Y627317D01*
X108641Y627110D01*
X108794Y626800D01*
X108871Y626387D01*
X108794Y626025D01*
X108602Y625663D01*
X108372Y625457D01*
X108104Y625405D01*
X107797Y625508D01*
X107567Y625767D01*
X107337Y626232D01*
G01X105081Y624320D02*
X105004Y624992D01*
X104889Y625560D01*
X104736Y626077D01*
X104544Y626645D01*
X104237Y627420D01*
X105771D01*
G01X106896Y642745D02*
Y645945D01*
G01X103796Y642845D02*
Y645845D01*
G01X120257Y647357D02*
X120487Y647512D01*
X120755Y647615D01*
X121062D01*
X121407Y647460D01*
X121675Y647202D01*
X121867Y646892D01*
X122020Y646375D01*
X122058Y645910D01*
X121982Y645445D01*
X121867Y645135D01*
X121637Y644825D01*
X121368Y644618D01*
X121100Y644515D01*
X120832D01*
X120563Y644618D01*
X120333Y644773D01*
X120142Y644980D01*
G01X117540Y644515D02*
Y647615D01*
X118958Y645393D01*
X117042D01*
G01X115628Y647098D02*
X115398Y647408D01*
X115130Y647563D01*
X114823Y647615D01*
X114440Y647512D01*
X114172Y647253D01*
X114095Y646943D01*
X114133Y646633D01*
X114287Y646375D01*
X115053Y645858D01*
X115398Y645497D01*
X115628Y644980D01*
X115705Y644515D01*
X114095D01*
G01X111877D02*
X111800Y645187D01*
X111685Y645755D01*
X111532Y646272D01*
X111340Y646840D01*
X111033Y647615D01*
X112567D01*
G01X119830Y641556D02*
X120060Y641711D01*
X120328Y641814D01*
X120635D01*
X120980Y641659D01*
X121248Y641401D01*
X121440Y641091D01*
X121593Y640574D01*
X121631Y640109D01*
X121555Y639644D01*
X121440Y639334D01*
X121210Y639024D01*
X120941Y638817D01*
X120673Y638714D01*
X120405D01*
X120136Y638817D01*
X119906Y638972D01*
X119715Y639179D01*
G01X117113Y638714D02*
Y641814D01*
X118531Y639592D01*
X116615D01*
G01X114473Y641814D02*
X114780Y641711D01*
X115010Y641452D01*
X115163Y641142D01*
X115278Y640729D01*
X115316Y640264D01*
X115278Y639799D01*
X115163Y639386D01*
X115010Y639076D01*
X114780Y638817D01*
X114473Y638714D01*
X114166Y638817D01*
X113936Y639076D01*
X113783Y639386D01*
X113668Y639799D01*
X113630Y640264D01*
X113668Y640729D01*
X113783Y641142D01*
X113936Y641452D01*
X114166Y641711D01*
X114473Y641814D01*
G01X112101Y640006D02*
X111833Y640367D01*
X111603Y640574D01*
X111296Y640677D01*
X111028Y640574D01*
X110836Y640367D01*
X110683Y640057D01*
X110645Y639696D01*
X110683Y639386D01*
X110836Y639076D01*
X111066Y638817D01*
X111335Y638714D01*
X111641Y638817D01*
X111910Y639127D01*
X112063Y639592D01*
X112101Y640109D01*
X112025Y640781D01*
X111910Y641142D01*
X111718Y641504D01*
X111450Y641762D01*
X111181Y641814D01*
X110913Y641711D01*
X110721Y641452D01*
G01X119863Y637558D02*
X120093Y637713D01*
X120361Y637816D01*
X120668D01*
X121013Y637661D01*
X121281Y637403D01*
X121473Y637093D01*
X121626Y636576D01*
X121664Y636111D01*
X121588Y635646D01*
X121473Y635336D01*
X121243Y635026D01*
X120974Y634819D01*
X120706Y634716D01*
X120438D01*
X120169Y634819D01*
X119939Y634974D01*
X119748Y635181D01*
G01X117146Y634716D02*
Y637816D01*
X118564Y635594D01*
X116648D01*
G01X115234Y637299D02*
X115004Y637609D01*
X114736Y637764D01*
X114429Y637816D01*
X114046Y637713D01*
X113778Y637454D01*
X113701Y637144D01*
X113739Y636834D01*
X113893Y636576D01*
X114659Y636059D01*
X115004Y635698D01*
X115234Y635181D01*
X115311Y634716D01*
X113701D01*
G01X112134Y636008D02*
X111866Y636369D01*
X111636Y636576D01*
X111329Y636679D01*
X111061Y636576D01*
X110869Y636369D01*
X110716Y636059D01*
X110678Y635698D01*
X110716Y635388D01*
X110869Y635078D01*
X111099Y634819D01*
X111368Y634716D01*
X111674Y634819D01*
X111943Y635129D01*
X112096Y635594D01*
X112134Y636111D01*
X112058Y636783D01*
X111943Y637144D01*
X111751Y637506D01*
X111483Y637764D01*
X111214Y637816D01*
X110946Y637713D01*
X110754Y637454D01*
G01X106930Y647017D02*
Y650217D01*
G01X103830Y647117D02*
Y650117D01*
G01X119931Y655930D02*
X120161Y656085D01*
X120429Y656188D01*
X120736D01*
X121081Y656033D01*
X121349Y655775D01*
X121541Y655465D01*
X121694Y654948D01*
X121732Y654483D01*
X121656Y654018D01*
X121541Y653708D01*
X121311Y653398D01*
X121042Y653191D01*
X120774Y653088D01*
X120506D01*
X120237Y653191D01*
X120007Y653346D01*
X119816Y653553D01*
G01X117214Y653088D02*
Y656188D01*
X118632Y653966D01*
X116716D01*
G01X114574Y656188D02*
X114881Y656085D01*
X115111Y655826D01*
X115264Y655516D01*
X115379Y655103D01*
X115417Y654638D01*
X115379Y654173D01*
X115264Y653760D01*
X115111Y653450D01*
X114881Y653191D01*
X114574Y653088D01*
X114267Y653191D01*
X114037Y653450D01*
X113884Y653760D01*
X113769Y654173D01*
X113731Y654638D01*
X113769Y655103D01*
X113884Y655516D01*
X114037Y655826D01*
X114267Y656085D01*
X114574Y656188D01*
G01X111551Y653088D02*
X111474Y653760D01*
X111359Y654328D01*
X111206Y654845D01*
X111014Y655413D01*
X110707Y656188D01*
X112241D01*
G01X119931Y651630D02*
X120161Y651785D01*
X120429Y651888D01*
X120736D01*
X121081Y651733D01*
X121349Y651475D01*
X121541Y651165D01*
X121694Y650648D01*
X121732Y650183D01*
X121656Y649718D01*
X121541Y649408D01*
X121311Y649098D01*
X121042Y648891D01*
X120774Y648788D01*
X120506D01*
X120237Y648891D01*
X120007Y649046D01*
X119816Y649253D01*
G01X117214Y648788D02*
Y651888D01*
X118632Y649666D01*
X116716D01*
G01X114574Y651888D02*
X114881Y651785D01*
X115111Y651526D01*
X115264Y651216D01*
X115379Y650803D01*
X115417Y650338D01*
X115379Y649873D01*
X115264Y649460D01*
X115111Y649150D01*
X114881Y648891D01*
X114574Y648788D01*
X114267Y648891D01*
X114037Y649150D01*
X113884Y649460D01*
X113769Y649873D01*
X113731Y650338D01*
X113769Y650803D01*
X113884Y651216D01*
X114037Y651526D01*
X114267Y651785D01*
X114574Y651888D01*
G01X111474Y648788D02*
Y651888D01*
X111934Y651268D01*
G01Y648788D02*
X111014D01*
G01X121010Y148320D02*
Y214250D01*
G01X147860Y148320D02*
X121010D01*
G01X130537Y188861D02*
X130767Y189016D01*
X131035Y189119D01*
X131342D01*
X131687Y188964D01*
X131955Y188706D01*
X132147Y188396D01*
X132300Y187879D01*
X132338Y187414D01*
X132262Y186949D01*
X132147Y186639D01*
X131917Y186329D01*
X131648Y186122D01*
X131380Y186019D01*
X131112D01*
X130843Y186122D01*
X130613Y186277D01*
X130422Y186484D01*
G01X129123D02*
X128893Y186226D01*
X128625Y186071D01*
X128280Y186019D01*
X127935Y186122D01*
X127667Y186329D01*
X127475Y186691D01*
X127437Y187104D01*
X127513Y187517D01*
X127705Y187776D01*
X127973Y187982D01*
X128242Y188034D01*
X128510Y187982D01*
X128855Y187776D01*
X128740Y189119D01*
X127705D01*
G01X125908Y187311D02*
X125640Y187672D01*
X125410Y187879D01*
X125103Y187982D01*
X124835Y187879D01*
X124643Y187672D01*
X124490Y187362D01*
X124452Y187001D01*
X124490Y186691D01*
X124643Y186381D01*
X124873Y186122D01*
X125142Y186019D01*
X125448Y186122D01*
X125717Y186432D01*
X125870Y186897D01*
X125908Y187414D01*
X125832Y188086D01*
X125717Y188447D01*
X125525Y188809D01*
X125257Y189067D01*
X124988Y189119D01*
X124720Y189016D01*
X124528Y188757D01*
G01X130797Y183143D02*
X131027Y183298D01*
X131295Y183401D01*
X131602D01*
X131947Y183246D01*
X132215Y182988D01*
X132407Y182678D01*
X132560Y182161D01*
X132598Y181696D01*
X132522Y181231D01*
X132407Y180921D01*
X132177Y180611D01*
X131908Y180404D01*
X131640Y180301D01*
X131372D01*
X131103Y180404D01*
X130873Y180559D01*
X130682Y180766D01*
G01X129383Y180921D02*
X129153Y180559D01*
X128847Y180353D01*
X128502Y180301D01*
X128195Y180353D01*
X127888Y180611D01*
X127697Y180921D01*
X127658Y181231D01*
X127735Y181593D01*
X128003Y181851D01*
X128272Y181954D01*
X128617D01*
G01X128272D02*
X128042Y182109D01*
X127850Y182368D01*
X127773Y182678D01*
X127850Y182988D01*
X128042Y183246D01*
X128387Y183401D01*
X128732Y183349D01*
X129077Y183143D01*
G01X126283Y180766D02*
X126053Y180508D01*
X125785Y180353D01*
X125440Y180301D01*
X125095Y180404D01*
X124827Y180611D01*
X124635Y180973D01*
X124597Y181386D01*
X124673Y181799D01*
X124865Y182058D01*
X125133Y182264D01*
X125402Y182316D01*
X125670Y182264D01*
X126015Y182058D01*
X125900Y183401D01*
X124865D01*
G01X121110Y201820D02*
Y202010D01*
G01X130980Y201820D02*
X121110D01*
G01X130980Y213660D02*
Y201820D01*
G01X126743Y204793D02*
Y209793D01*
X125477D01*
X124970Y209543D01*
X124590Y209210D01*
X124273Y208710D01*
X124020Y208126D01*
X123957Y207293D01*
X124020Y206460D01*
X124273Y205876D01*
X124590Y205376D01*
X124970Y205043D01*
X125477Y204793D01*
X126743D01*
G01X130880Y213660D02*
X130980D01*
G01X121010Y214250D02*
X125940D01*
G01X121010D02*
X191880D01*
G01X143047Y209239D02*
Y212339D01*
X142088D01*
X141782Y212184D01*
X141590Y211977D01*
X141513Y211564D01*
X141590Y211151D01*
X141820Y210892D01*
X142088Y210737D01*
X143047D01*
G01X142088D02*
X141513Y209239D01*
G01X139180D02*
Y212339D01*
X139640Y211719D01*
G01Y209239D02*
X138720D01*
G01X135620D02*
Y212339D01*
X137038Y210117D01*
X135122D01*
G01X132980Y209239D02*
X132712Y209291D01*
X132405Y209446D01*
X132213Y209704D01*
X132137Y210066D01*
X132213Y210427D01*
X132443Y210737D01*
X132788Y210892D01*
X133172D01*
X133402Y210996D01*
X133593Y211254D01*
X133670Y211616D01*
X133555Y211977D01*
X133287Y212236D01*
X132980Y212339D01*
X132673Y212236D01*
X132405Y211977D01*
X132290Y211616D01*
X132367Y211254D01*
X132558Y210996D01*
X132788Y210892D01*
X133172D01*
X133517Y210737D01*
X133747Y210427D01*
X133823Y210066D01*
X133747Y209704D01*
X133555Y209446D01*
X133248Y209291D01*
X132980Y209239D01*
G01X130438Y252588D02*
X130668Y252743D01*
X130936Y252846D01*
X131243D01*
X131588Y252691D01*
X131856Y252433D01*
X132048Y252123D01*
X132201Y251606D01*
X132239Y251141D01*
X132163Y250676D01*
X132048Y250366D01*
X131818Y250056D01*
X131549Y249849D01*
X131281Y249746D01*
X131013D01*
X130744Y249849D01*
X130514Y250004D01*
X130323Y250211D01*
G01X128909Y252329D02*
X128679Y252639D01*
X128411Y252794D01*
X128104Y252846D01*
X127721Y252743D01*
X127453Y252484D01*
X127376Y252174D01*
X127414Y251864D01*
X127568Y251606D01*
X128334Y251089D01*
X128679Y250728D01*
X128909Y250211D01*
X128986Y249746D01*
X127376D01*
G01X125081Y252846D02*
X125388Y252743D01*
X125618Y252484D01*
X125771Y252174D01*
X125886Y251761D01*
X125924Y251296D01*
X125886Y250831D01*
X125771Y250418D01*
X125618Y250108D01*
X125388Y249849D01*
X125081Y249746D01*
X124774Y249849D01*
X124544Y250108D01*
X124391Y250418D01*
X124276Y250831D01*
X124238Y251296D01*
X124276Y251761D01*
X124391Y252174D01*
X124544Y252484D01*
X124774Y252743D01*
X125081Y252846D01*
G01X131017Y267257D02*
X131247Y267412D01*
X131515Y267515D01*
X131822D01*
X132167Y267360D01*
X132435Y267102D01*
X132627Y266792D01*
X132780Y266275D01*
X132818Y265810D01*
X132742Y265345D01*
X132627Y265035D01*
X132397Y264725D01*
X132128Y264518D01*
X131860Y264415D01*
X131592D01*
X131323Y264518D01*
X131093Y264673D01*
X130902Y264880D01*
G01X128760Y264415D02*
Y267515D01*
X129220Y266895D01*
G01Y264415D02*
X128300D01*
G01X125737D02*
X125660Y265087D01*
X125545Y265655D01*
X125392Y266172D01*
X125200Y266740D01*
X124893Y267515D01*
X126427D01*
G01X131077Y263221D02*
X131307Y263376D01*
X131575Y263479D01*
X131882D01*
X132227Y263324D01*
X132495Y263066D01*
X132687Y262756D01*
X132840Y262239D01*
X132878Y261774D01*
X132802Y261309D01*
X132687Y260999D01*
X132457Y260689D01*
X132188Y260482D01*
X131920Y260379D01*
X131652D01*
X131383Y260482D01*
X131153Y260637D01*
X130962Y260844D01*
G01X128820Y260379D02*
Y263479D01*
X129280Y262859D01*
G01Y260379D02*
X128360D01*
G01X125720D02*
X125452Y260431D01*
X125145Y260586D01*
X124953Y260844D01*
X124877Y261206D01*
X124953Y261567D01*
X125183Y261877D01*
X125528Y262032D01*
X125912D01*
X126142Y262136D01*
X126333Y262394D01*
X126410Y262756D01*
X126295Y263117D01*
X126027Y263376D01*
X125720Y263479D01*
X125413Y263376D01*
X125145Y263117D01*
X125030Y262756D01*
X125107Y262394D01*
X125298Y262136D01*
X125528Y262032D01*
X125912D01*
X126257Y261877D01*
X126487Y261567D01*
X126563Y261206D01*
X126487Y260844D01*
X126295Y260586D01*
X125988Y260431D01*
X125720Y260379D01*
G01X130438Y256588D02*
X130668Y256743D01*
X130936Y256846D01*
X131243D01*
X131588Y256691D01*
X131856Y256433D01*
X132048Y256123D01*
X132201Y255606D01*
X132239Y255141D01*
X132163Y254676D01*
X132048Y254366D01*
X131818Y254056D01*
X131549Y253849D01*
X131281Y253746D01*
X131013D01*
X130744Y253849D01*
X130514Y254004D01*
X130323Y254211D01*
G01X128181Y253746D02*
Y256846D01*
X128641Y256226D01*
G01Y253746D02*
X127721D01*
G01X125733Y254108D02*
X125464Y253849D01*
X125158Y253746D01*
X124851Y253849D01*
X124583Y254159D01*
X124391Y254624D01*
X124314Y255089D01*
Y255658D01*
X124391Y256123D01*
X124583Y256536D01*
X124813Y256743D01*
X125081Y256846D01*
X125388Y256743D01*
X125618Y256536D01*
X125771Y256226D01*
X125848Y255813D01*
X125771Y255451D01*
X125579Y255089D01*
X125349Y254883D01*
X125081Y254831D01*
X124774Y254934D01*
X124544Y255193D01*
X124314Y255658D01*
G01X123946Y298899D02*
X124101Y298669D01*
X124204Y298401D01*
Y298094D01*
X124049Y297749D01*
X123791Y297481D01*
X123481Y297289D01*
X122964Y297136D01*
X122499Y297098D01*
X122034Y297174D01*
X121724Y297289D01*
X121414Y297519D01*
X121207Y297788D01*
X121104Y298056D01*
Y298324D01*
X121207Y298593D01*
X121362Y298823D01*
X121569Y299014D01*
G01X123687Y300428D02*
X123997Y300658D01*
X124152Y300926D01*
X124204Y301233D01*
X124101Y301616D01*
X123842Y301884D01*
X123532Y301961D01*
X123222Y301923D01*
X122964Y301769D01*
X122447Y301003D01*
X122086Y300658D01*
X121569Y300428D01*
X121104Y300351D01*
Y301961D01*
G01X121569Y303413D02*
X121311Y303643D01*
X121156Y303911D01*
X121104Y304256D01*
X121207Y304601D01*
X121414Y304869D01*
X121776Y305061D01*
X122189Y305099D01*
X122602Y305023D01*
X122861Y304831D01*
X123067Y304563D01*
X123119Y304294D01*
X123067Y304026D01*
X122861Y303681D01*
X124204Y303796D01*
Y304831D01*
G01X121569Y306513D02*
X121311Y306743D01*
X121156Y307011D01*
X121104Y307356D01*
X121207Y307701D01*
X121414Y307969D01*
X121776Y308161D01*
X122189Y308199D01*
X122602Y308123D01*
X122861Y307931D01*
X123067Y307663D01*
X123119Y307394D01*
X123067Y307126D01*
X122861Y306781D01*
X124204Y306896D01*
Y307931D01*
G01X128302Y298223D02*
X128457Y297993D01*
X128560Y297725D01*
Y297418D01*
X128405Y297073D01*
X128147Y296805D01*
X127837Y296613D01*
X127320Y296460D01*
X126855Y296422D01*
X126390Y296498D01*
X126080Y296613D01*
X125770Y296843D01*
X125563Y297112D01*
X125460Y297380D01*
Y297648D01*
X125563Y297917D01*
X125718Y298147D01*
X125925Y298338D01*
G01X128043Y299752D02*
X128353Y299982D01*
X128508Y300250D01*
X128560Y300557D01*
X128457Y300940D01*
X128198Y301208D01*
X127888Y301285D01*
X127578Y301247D01*
X127320Y301093D01*
X126803Y300327D01*
X126442Y299982D01*
X125925Y299752D01*
X125460Y299675D01*
Y301285D01*
G01Y303503D02*
X126132Y303580D01*
X126700Y303695D01*
X127217Y303848D01*
X127785Y304040D01*
X128560Y304347D01*
Y302813D01*
G01X125822Y306028D02*
X125563Y306297D01*
X125460Y306603D01*
X125563Y306910D01*
X125873Y307178D01*
X126338Y307370D01*
X126803Y307447D01*
X127372D01*
X127837Y307370D01*
X128250Y307178D01*
X128457Y306948D01*
X128560Y306680D01*
X128457Y306373D01*
X128250Y306143D01*
X127940Y305990D01*
X127527Y305913D01*
X127165Y305990D01*
X126803Y306182D01*
X126597Y306412D01*
X126545Y306680D01*
X126648Y306987D01*
X126907Y307217D01*
X127372Y307447D01*
G01X126800Y312451D02*
X127030Y312606D01*
X127298Y312709D01*
X127605D01*
X127950Y312554D01*
X128218Y312296D01*
X128410Y311986D01*
X128563Y311469D01*
X128601Y311004D01*
X128525Y310539D01*
X128410Y310229D01*
X128180Y309919D01*
X127911Y309712D01*
X127643Y309609D01*
X127375D01*
X127106Y309712D01*
X126876Y309867D01*
X126685Y310074D01*
G01X125271Y312192D02*
X125041Y312502D01*
X124773Y312657D01*
X124466Y312709D01*
X124083Y312606D01*
X123815Y312347D01*
X123738Y312037D01*
X123776Y311727D01*
X123930Y311469D01*
X124696Y310952D01*
X125041Y310591D01*
X125271Y310074D01*
X125348Y309609D01*
X123738D01*
G01X122095Y309971D02*
X121826Y309712D01*
X121520Y309609D01*
X121213Y309712D01*
X120945Y310022D01*
X120753Y310487D01*
X120676Y310952D01*
Y311521D01*
X120753Y311986D01*
X120945Y312399D01*
X121175Y312606D01*
X121443Y312709D01*
X121750Y312606D01*
X121980Y312399D01*
X122133Y312089D01*
X122210Y311676D01*
X122133Y311314D01*
X121941Y310952D01*
X121711Y310746D01*
X121443Y310694D01*
X121136Y310797D01*
X120906Y311056D01*
X120676Y311521D01*
G01X118343Y312709D02*
X118650Y312606D01*
X118880Y312347D01*
X119033Y312037D01*
X119148Y311624D01*
X119186Y311159D01*
X119148Y310694D01*
X119033Y310281D01*
X118880Y309971D01*
X118650Y309712D01*
X118343Y309609D01*
X118036Y309712D01*
X117806Y309971D01*
X117653Y310281D01*
X117538Y310694D01*
X117500Y311159D01*
X117538Y311624D01*
X117653Y312037D01*
X117806Y312347D01*
X118036Y312606D01*
X118343Y312709D01*
G01X129217Y331370D02*
X129447Y331525D01*
X129715Y331628D01*
X130022D01*
X130367Y331473D01*
X130635Y331215D01*
X130827Y330905D01*
X130980Y330388D01*
X131018Y329923D01*
X130942Y329458D01*
X130827Y329148D01*
X130597Y328838D01*
X130328Y328631D01*
X130060Y328528D01*
X129792D01*
X129523Y328631D01*
X129293Y328786D01*
X129102Y328993D01*
G01X127688Y331111D02*
X127458Y331421D01*
X127190Y331576D01*
X126883Y331628D01*
X126500Y331525D01*
X126232Y331266D01*
X126155Y330956D01*
X126193Y330646D01*
X126347Y330388D01*
X127113Y329871D01*
X127458Y329510D01*
X127688Y328993D01*
X127765Y328528D01*
X126155D01*
G01X123860D02*
X123592Y328580D01*
X123285Y328735D01*
X123093Y328993D01*
X123017Y329355D01*
X123093Y329716D01*
X123323Y330026D01*
X123668Y330181D01*
X124052D01*
X124282Y330285D01*
X124473Y330543D01*
X124550Y330905D01*
X124435Y331266D01*
X124167Y331525D01*
X123860Y331628D01*
X123553Y331525D01*
X123285Y331266D01*
X123170Y330905D01*
X123247Y330543D01*
X123438Y330285D01*
X123668Y330181D01*
X124052D01*
X124397Y330026D01*
X124627Y329716D01*
X124703Y329355D01*
X124627Y328993D01*
X124435Y328735D01*
X124128Y328580D01*
X123860Y328528D01*
G01X121488Y331111D02*
X121258Y331421D01*
X120990Y331576D01*
X120683Y331628D01*
X120300Y331525D01*
X120032Y331266D01*
X119955Y330956D01*
X119993Y330646D01*
X120147Y330388D01*
X120913Y329871D01*
X121258Y329510D01*
X121488Y328993D01*
X121565Y328528D01*
X119955D01*
G01X129217Y323450D02*
X129447Y323605D01*
X129715Y323708D01*
X130022D01*
X130367Y323553D01*
X130635Y323295D01*
X130827Y322985D01*
X130980Y322468D01*
X131018Y322003D01*
X130942Y321538D01*
X130827Y321228D01*
X130597Y320918D01*
X130328Y320711D01*
X130060Y320608D01*
X129792D01*
X129523Y320711D01*
X129293Y320866D01*
X129102Y321073D01*
G01X127688Y323191D02*
X127458Y323501D01*
X127190Y323656D01*
X126883Y323708D01*
X126500Y323605D01*
X126232Y323346D01*
X126155Y323036D01*
X126193Y322726D01*
X126347Y322468D01*
X127113Y321951D01*
X127458Y321590D01*
X127688Y321073D01*
X127765Y320608D01*
X126155D01*
G01X123400D02*
Y323708D01*
X124818Y321486D01*
X122902D01*
G01X121412Y320970D02*
X121143Y320711D01*
X120837Y320608D01*
X120530Y320711D01*
X120262Y321021D01*
X120070Y321486D01*
X119993Y321951D01*
Y322520D01*
X120070Y322985D01*
X120262Y323398D01*
X120492Y323605D01*
X120760Y323708D01*
X121067Y323605D01*
X121297Y323398D01*
X121450Y323088D01*
X121527Y322675D01*
X121450Y322313D01*
X121258Y321951D01*
X121028Y321745D01*
X120760Y321693D01*
X120453Y321796D01*
X120223Y322055D01*
X119993Y322520D01*
G01X129217Y327134D02*
X129447Y327289D01*
X129715Y327392D01*
X130022D01*
X130367Y327237D01*
X130635Y326979D01*
X130827Y326669D01*
X130980Y326152D01*
X131018Y325687D01*
X130942Y325222D01*
X130827Y324912D01*
X130597Y324602D01*
X130328Y324395D01*
X130060Y324292D01*
X129792D01*
X129523Y324395D01*
X129293Y324550D01*
X129102Y324757D01*
G01X127688Y326875D02*
X127458Y327185D01*
X127190Y327340D01*
X126883Y327392D01*
X126500Y327289D01*
X126232Y327030D01*
X126155Y326720D01*
X126193Y326410D01*
X126347Y326152D01*
X127113Y325635D01*
X127458Y325274D01*
X127688Y324757D01*
X127765Y324292D01*
X126155D01*
G01X123860D02*
X123592Y324344D01*
X123285Y324499D01*
X123093Y324757D01*
X123017Y325119D01*
X123093Y325480D01*
X123323Y325790D01*
X123668Y325945D01*
X124052D01*
X124282Y326049D01*
X124473Y326307D01*
X124550Y326669D01*
X124435Y327030D01*
X124167Y327289D01*
X123860Y327392D01*
X123553Y327289D01*
X123285Y327030D01*
X123170Y326669D01*
X123247Y326307D01*
X123438Y326049D01*
X123668Y325945D01*
X124052D01*
X124397Y325790D01*
X124627Y325480D01*
X124703Y325119D01*
X124627Y324757D01*
X124435Y324499D01*
X124128Y324344D01*
X123860Y324292D01*
G01X120760D02*
Y327392D01*
X121220Y326772D01*
G01Y324292D02*
X120300D01*
G01X129217Y335284D02*
X129447Y335439D01*
X129715Y335542D01*
X130022D01*
X130367Y335387D01*
X130635Y335129D01*
X130827Y334819D01*
X130980Y334302D01*
X131018Y333837D01*
X130942Y333372D01*
X130827Y333062D01*
X130597Y332752D01*
X130328Y332545D01*
X130060Y332442D01*
X129792D01*
X129523Y332545D01*
X129293Y332700D01*
X129102Y332907D01*
G01X127688Y335025D02*
X127458Y335335D01*
X127190Y335490D01*
X126883Y335542D01*
X126500Y335439D01*
X126232Y335180D01*
X126155Y334870D01*
X126193Y334560D01*
X126347Y334302D01*
X127113Y333785D01*
X127458Y333424D01*
X127688Y332907D01*
X127765Y332442D01*
X126155D01*
G01X124703Y332907D02*
X124473Y332649D01*
X124205Y332494D01*
X123860Y332442D01*
X123515Y332545D01*
X123247Y332752D01*
X123055Y333114D01*
X123017Y333527D01*
X123093Y333940D01*
X123285Y334199D01*
X123553Y334405D01*
X123822Y334457D01*
X124090Y334405D01*
X124435Y334199D01*
X124320Y335542D01*
X123285D01*
G01X121488Y335025D02*
X121258Y335335D01*
X120990Y335490D01*
X120683Y335542D01*
X120300Y335439D01*
X120032Y335180D01*
X119955Y334870D01*
X119993Y334560D01*
X120147Y334302D01*
X120913Y333785D01*
X121258Y333424D01*
X121488Y332907D01*
X121565Y332442D01*
X119955D01*
G01X129288Y340461D02*
X129518Y340616D01*
X129786Y340719D01*
X130093D01*
X130438Y340564D01*
X130706Y340306D01*
X130898Y339996D01*
X131051Y339479D01*
X131089Y339014D01*
X131013Y338549D01*
X130898Y338239D01*
X130668Y337929D01*
X130399Y337722D01*
X130131Y337619D01*
X129863D01*
X129594Y337722D01*
X129364Y337877D01*
X129173Y338084D01*
G01X127759Y340202D02*
X127529Y340512D01*
X127261Y340667D01*
X126954Y340719D01*
X126571Y340616D01*
X126303Y340357D01*
X126226Y340047D01*
X126264Y339737D01*
X126418Y339479D01*
X127184Y338962D01*
X127529Y338601D01*
X127759Y338084D01*
X127836Y337619D01*
X126226D01*
G01X123471D02*
Y340719D01*
X124889Y338497D01*
X122973D01*
G01X120831Y337619D02*
X120563Y337671D01*
X120256Y337826D01*
X120064Y338084D01*
X119988Y338446D01*
X120064Y338807D01*
X120294Y339117D01*
X120639Y339272D01*
X121023D01*
X121253Y339376D01*
X121444Y339634D01*
X121521Y339996D01*
X121406Y340357D01*
X121138Y340616D01*
X120831Y340719D01*
X120524Y340616D01*
X120256Y340357D01*
X120141Y339996D01*
X120218Y339634D01*
X120409Y339376D01*
X120639Y339272D01*
X121023D01*
X121368Y339117D01*
X121598Y338807D01*
X121674Y338446D01*
X121598Y338084D01*
X121406Y337826D01*
X121099Y337671D01*
X120831Y337619D01*
G01X127094Y355131D02*
X127249Y354901D01*
X127352Y354633D01*
Y354326D01*
X127197Y353981D01*
X126939Y353713D01*
X126629Y353521D01*
X126112Y353368D01*
X125647Y353330D01*
X125182Y353406D01*
X124872Y353521D01*
X124562Y353751D01*
X124355Y354020D01*
X124252Y354288D01*
Y354556D01*
X124355Y354825D01*
X124510Y355055D01*
X124717Y355246D01*
G01X126835Y356660D02*
X127145Y356890D01*
X127300Y357158D01*
X127352Y357465D01*
X127249Y357848D01*
X126990Y358116D01*
X126680Y358193D01*
X126370Y358155D01*
X126112Y358001D01*
X125595Y357235D01*
X125234Y356890D01*
X124717Y356660D01*
X124252Y356583D01*
Y358193D01*
G01Y360488D02*
X124304Y360756D01*
X124459Y361063D01*
X124717Y361255D01*
X125079Y361331D01*
X125440Y361255D01*
X125750Y361025D01*
X125905Y360680D01*
Y360296D01*
X126009Y360066D01*
X126267Y359875D01*
X126629Y359798D01*
X126990Y359913D01*
X127249Y360181D01*
X127352Y360488D01*
X127249Y360795D01*
X126990Y361063D01*
X126629Y361178D01*
X126267Y361101D01*
X126009Y360910D01*
X125905Y360680D01*
Y360296D01*
X125750Y359951D01*
X125440Y359721D01*
X125079Y359645D01*
X124717Y359721D01*
X124459Y359913D01*
X124304Y360220D01*
X124252Y360488D01*
G01X135152Y355131D02*
X135307Y354901D01*
X135410Y354633D01*
Y354326D01*
X135255Y353981D01*
X134997Y353713D01*
X134687Y353521D01*
X134170Y353368D01*
X133705Y353330D01*
X133240Y353406D01*
X132930Y353521D01*
X132620Y353751D01*
X132413Y354020D01*
X132310Y354288D01*
Y354556D01*
X132413Y354825D01*
X132568Y355055D01*
X132775Y355246D01*
G01X132930Y356545D02*
X132568Y356775D01*
X132362Y357081D01*
X132310Y357426D01*
X132362Y357733D01*
X132620Y358040D01*
X132930Y358231D01*
X133240Y358270D01*
X133602Y358193D01*
X133860Y357925D01*
X133963Y357656D01*
Y357311D01*
G01Y357656D02*
X134118Y357886D01*
X134377Y358078D01*
X134687Y358155D01*
X134997Y358078D01*
X135255Y357886D01*
X135410Y357541D01*
X135358Y357196D01*
X135152Y356851D01*
G01X135410Y360488D02*
X135307Y360181D01*
X135048Y359951D01*
X134738Y359798D01*
X134325Y359683D01*
X133860Y359645D01*
X133395Y359683D01*
X132982Y359798D01*
X132672Y359951D01*
X132413Y360181D01*
X132310Y360488D01*
X132413Y360795D01*
X132672Y361025D01*
X132982Y361178D01*
X133395Y361293D01*
X133860Y361331D01*
X134325Y361293D01*
X134738Y361178D01*
X135048Y361025D01*
X135307Y360795D01*
X135410Y360488D01*
G01X128350Y353521D02*
X131450D01*
Y354480D01*
X131295Y354786D01*
X131088Y354978D01*
X130675Y355055D01*
X130262Y354978D01*
X130003Y354748D01*
X129848Y354480D01*
Y353521D01*
G01Y354480D02*
X128350Y355055D01*
G01Y357388D02*
X131450D01*
X130830Y356928D01*
G01X128350D02*
Y357848D01*
G01X130933Y359760D02*
X131243Y359990D01*
X131398Y360258D01*
X131450Y360565D01*
X131347Y360948D01*
X131088Y361216D01*
X130778Y361293D01*
X130468Y361255D01*
X130210Y361101D01*
X129693Y360335D01*
X129332Y359990D01*
X128815Y359760D01*
X128350Y359683D01*
Y361293D01*
G01X128815Y362745D02*
X128557Y362975D01*
X128402Y363243D01*
X128350Y363588D01*
X128453Y363933D01*
X128660Y364201D01*
X129022Y364393D01*
X129435Y364431D01*
X129848Y364355D01*
X130107Y364163D01*
X130313Y363895D01*
X130365Y363626D01*
X130313Y363358D01*
X130107Y363013D01*
X131450Y363128D01*
Y364163D01*
G01X122155Y405853D02*
Y420853D01*
G01X129360Y420389D02*
Y405389D01*
G01D02*
X136160D01*
G01Y420389D02*
X129360D01*
G01X136060Y412889D02*
X129460D01*
G01X117618Y450236D02*
Y457036D01*
G01X119884Y458118D02*
Y465518D01*
G01X127447Y498050D02*
X127602Y497820D01*
X127705Y497552D01*
Y497245D01*
X127550Y496900D01*
X127292Y496632D01*
X126982Y496440D01*
X126465Y496287D01*
X126000Y496249D01*
X125535Y496325D01*
X125225Y496440D01*
X124915Y496670D01*
X124708Y496939D01*
X124605Y497207D01*
Y497475D01*
X124708Y497744D01*
X124863Y497974D01*
X125070Y498165D01*
G01X124605Y500307D02*
X124657Y500575D01*
X124812Y500882D01*
X125070Y501074D01*
X125432Y501150D01*
X125793Y501074D01*
X126103Y500844D01*
X126258Y500499D01*
Y500115D01*
X126362Y499885D01*
X126620Y499694D01*
X126982Y499617D01*
X127343Y499732D01*
X127602Y500000D01*
X127705Y500307D01*
X127602Y500614D01*
X127343Y500882D01*
X126982Y500997D01*
X126620Y500920D01*
X126362Y500729D01*
X126258Y500499D01*
Y500115D01*
X126103Y499770D01*
X125793Y499540D01*
X125432Y499464D01*
X125070Y499540D01*
X124812Y499732D01*
X124657Y500039D01*
X124605Y500307D01*
G01X125225Y502564D02*
X124863Y502794D01*
X124657Y503100D01*
X124605Y503445D01*
X124657Y503752D01*
X124915Y504059D01*
X125225Y504250D01*
X125535Y504289D01*
X125897Y504212D01*
X126155Y503944D01*
X126258Y503675D01*
Y503330D01*
G01Y503675D02*
X126413Y503905D01*
X126672Y504097D01*
X126982Y504174D01*
X127292Y504097D01*
X127550Y503905D01*
X127705Y503560D01*
X127653Y503215D01*
X127447Y502870D01*
G01X124605Y506507D02*
X127705D01*
X127085Y506047D01*
G01X124605D02*
Y506967D01*
G01X128835Y501422D02*
X135435D01*
G01X128735Y493922D02*
X135535D01*
G01X128735Y508922D02*
Y493922D01*
G01X135535Y508922D02*
X128735D01*
G01X137896Y542381D02*
X138126Y542536D01*
X138394Y542639D01*
X138701D01*
X139046Y542484D01*
X139314Y542226D01*
X139506Y541916D01*
X139659Y541399D01*
X139697Y540934D01*
X139621Y540469D01*
X139506Y540159D01*
X139276Y539849D01*
X139007Y539642D01*
X138739Y539539D01*
X138471D01*
X138202Y539642D01*
X137972Y539797D01*
X137781Y540004D01*
G01X136367Y542122D02*
X136137Y542432D01*
X135869Y542587D01*
X135562Y542639D01*
X135179Y542536D01*
X134911Y542277D01*
X134834Y541967D01*
X134872Y541657D01*
X135026Y541399D01*
X135792Y540882D01*
X136137Y540521D01*
X136367Y540004D01*
X136444Y539539D01*
X134834D01*
G01X133267Y542122D02*
X133037Y542432D01*
X132769Y542587D01*
X132462Y542639D01*
X132079Y542536D01*
X131811Y542277D01*
X131734Y541967D01*
X131772Y541657D01*
X131926Y541399D01*
X132692Y540882D01*
X133037Y540521D01*
X133267Y540004D01*
X133344Y539539D01*
X131734D01*
G01X129516D02*
X129439Y540211D01*
X129324Y540779D01*
X129171Y541296D01*
X128979Y541864D01*
X128672Y542639D01*
X130206D01*
G01X137896Y538145D02*
X138126Y538300D01*
X138394Y538403D01*
X138701D01*
X139046Y538248D01*
X139314Y537990D01*
X139506Y537680D01*
X139659Y537163D01*
X139697Y536698D01*
X139621Y536233D01*
X139506Y535923D01*
X139276Y535613D01*
X139007Y535406D01*
X138739Y535303D01*
X138471D01*
X138202Y535406D01*
X137972Y535561D01*
X137781Y535768D01*
G01X136367Y537886D02*
X136137Y538196D01*
X135869Y538351D01*
X135562Y538403D01*
X135179Y538300D01*
X134911Y538041D01*
X134834Y537731D01*
X134872Y537421D01*
X135026Y537163D01*
X135792Y536646D01*
X136137Y536285D01*
X136367Y535768D01*
X136444Y535303D01*
X134834D01*
G01X133267Y537886D02*
X133037Y538196D01*
X132769Y538351D01*
X132462Y538403D01*
X132079Y538300D01*
X131811Y538041D01*
X131734Y537731D01*
X131772Y537421D01*
X131926Y537163D01*
X132692Y536646D01*
X133037Y536285D01*
X133267Y535768D01*
X133344Y535303D01*
X131734D01*
G01X129439D02*
X129171Y535355D01*
X128864Y535510D01*
X128672Y535768D01*
X128596Y536130D01*
X128672Y536491D01*
X128902Y536801D01*
X129247Y536956D01*
X129631D01*
X129861Y537060D01*
X130052Y537318D01*
X130129Y537680D01*
X130014Y538041D01*
X129746Y538300D01*
X129439Y538403D01*
X129132Y538300D01*
X128864Y538041D01*
X128749Y537680D01*
X128826Y537318D01*
X129017Y537060D01*
X129247Y536956D01*
X129631D01*
X129976Y536801D01*
X130206Y536491D01*
X130282Y536130D01*
X130206Y535768D01*
X130014Y535510D01*
X129707Y535355D01*
X129439Y535303D01*
G01X137896Y550761D02*
X138126Y550916D01*
X138394Y551019D01*
X138701D01*
X139046Y550864D01*
X139314Y550606D01*
X139506Y550296D01*
X139659Y549779D01*
X139697Y549314D01*
X139621Y548849D01*
X139506Y548539D01*
X139276Y548229D01*
X139007Y548022D01*
X138739Y547919D01*
X138471D01*
X138202Y548022D01*
X137972Y548177D01*
X137781Y548384D01*
G01X136367Y550502D02*
X136137Y550812D01*
X135869Y550967D01*
X135562Y551019D01*
X135179Y550916D01*
X134911Y550657D01*
X134834Y550347D01*
X134872Y550037D01*
X135026Y549779D01*
X135792Y549262D01*
X136137Y548901D01*
X136367Y548384D01*
X136444Y547919D01*
X134834D01*
G01X133267Y550502D02*
X133037Y550812D01*
X132769Y550967D01*
X132462Y551019D01*
X132079Y550916D01*
X131811Y550657D01*
X131734Y550347D01*
X131772Y550037D01*
X131926Y549779D01*
X132692Y549262D01*
X133037Y548901D01*
X133267Y548384D01*
X133344Y547919D01*
X131734D01*
G01X128979D02*
Y551019D01*
X130397Y548797D01*
X128481D01*
G01X139506Y543591D02*
Y546691D01*
X138547D01*
X138241Y546536D01*
X138049Y546329D01*
X137972Y545916D01*
X138049Y545503D01*
X138279Y545244D01*
X138547Y545089D01*
X139506D01*
G01X138547D02*
X137972Y543591D01*
G01X136367Y546174D02*
X136137Y546484D01*
X135869Y546639D01*
X135562Y546691D01*
X135179Y546588D01*
X134911Y546329D01*
X134834Y546019D01*
X134872Y545709D01*
X135026Y545451D01*
X135792Y544934D01*
X136137Y544573D01*
X136367Y544056D01*
X136444Y543591D01*
X134834D01*
G01X133267Y544883D02*
X132999Y545244D01*
X132769Y545451D01*
X132462Y545554D01*
X132194Y545451D01*
X132002Y545244D01*
X131849Y544934D01*
X131811Y544573D01*
X131849Y544263D01*
X132002Y543953D01*
X132232Y543694D01*
X132501Y543591D01*
X132807Y543694D01*
X133076Y544004D01*
X133229Y544469D01*
X133267Y544986D01*
X133191Y545658D01*
X133076Y546019D01*
X132884Y546381D01*
X132616Y546639D01*
X132347Y546691D01*
X132079Y546588D01*
X131887Y546329D01*
G01X130167Y546174D02*
X129937Y546484D01*
X129669Y546639D01*
X129362Y546691D01*
X128979Y546588D01*
X128711Y546329D01*
X128634Y546019D01*
X128672Y545709D01*
X128826Y545451D01*
X129592Y544934D01*
X129937Y544573D01*
X130167Y544056D01*
X130244Y543591D01*
X128634D01*
G01X141858Y556701D02*
X142088Y556856D01*
X142356Y556959D01*
X142663D01*
X143008Y556804D01*
X143276Y556546D01*
X143468Y556236D01*
X143621Y555719D01*
X143659Y555254D01*
X143583Y554789D01*
X143468Y554479D01*
X143238Y554169D01*
X142969Y553962D01*
X142701Y553859D01*
X142433D01*
X142164Y553962D01*
X141934Y554117D01*
X141743Y554324D01*
G01X140329Y556442D02*
X140099Y556752D01*
X139831Y556907D01*
X139524Y556959D01*
X139141Y556856D01*
X138873Y556597D01*
X138796Y556287D01*
X138834Y555977D01*
X138988Y555719D01*
X139754Y555202D01*
X140099Y554841D01*
X140329Y554324D01*
X140406Y553859D01*
X138796D01*
G01X137344Y554479D02*
X137114Y554117D01*
X136808Y553911D01*
X136463Y553859D01*
X136156Y553911D01*
X135849Y554169D01*
X135658Y554479D01*
X135619Y554789D01*
X135696Y555151D01*
X135964Y555409D01*
X136233Y555512D01*
X136578D01*
G01X136233D02*
X136003Y555667D01*
X135811Y555926D01*
X135734Y556236D01*
X135811Y556546D01*
X136003Y556804D01*
X136348Y556959D01*
X136693Y556907D01*
X137038Y556701D01*
G01X132941Y553859D02*
Y556959D01*
X134359Y554737D01*
X132443D01*
G01X138889Y578280D02*
Y581380D01*
X137930D01*
X137624Y581225D01*
X137432Y581018D01*
X137355Y580605D01*
X137432Y580192D01*
X137662Y579933D01*
X137930Y579778D01*
X138889D01*
G01X137930D02*
X137355Y578280D01*
G01X135865Y578745D02*
X135635Y578487D01*
X135367Y578332D01*
X135022Y578280D01*
X134677Y578383D01*
X134409Y578590D01*
X134217Y578952D01*
X134179Y579365D01*
X134255Y579778D01*
X134447Y580037D01*
X134715Y580243D01*
X134984Y580295D01*
X135252Y580243D01*
X135597Y580037D01*
X135482Y581380D01*
X134447D01*
G01X132765Y578745D02*
X132535Y578487D01*
X132267Y578332D01*
X131922Y578280D01*
X131577Y578383D01*
X131309Y578590D01*
X131117Y578952D01*
X131079Y579365D01*
X131155Y579778D01*
X131347Y580037D01*
X131615Y580243D01*
X131884Y580295D01*
X132152Y580243D01*
X132497Y580037D01*
X132382Y581380D01*
X131347D01*
G01X128362Y578280D02*
Y581380D01*
X129780Y579158D01*
X127864D01*
G01X138889Y570372D02*
Y573472D01*
X137930D01*
X137624Y573317D01*
X137432Y573110D01*
X137355Y572697D01*
X137432Y572284D01*
X137662Y572025D01*
X137930Y571870D01*
X138889D01*
G01X137930D02*
X137355Y570372D01*
G01X135865Y570837D02*
X135635Y570579D01*
X135367Y570424D01*
X135022Y570372D01*
X134677Y570475D01*
X134409Y570682D01*
X134217Y571044D01*
X134179Y571457D01*
X134255Y571870D01*
X134447Y572129D01*
X134715Y572335D01*
X134984Y572387D01*
X135252Y572335D01*
X135597Y572129D01*
X135482Y573472D01*
X134447D01*
G01X132765Y570837D02*
X132535Y570579D01*
X132267Y570424D01*
X131922Y570372D01*
X131577Y570475D01*
X131309Y570682D01*
X131117Y571044D01*
X131079Y571457D01*
X131155Y571870D01*
X131347Y572129D01*
X131615Y572335D01*
X131884Y572387D01*
X132152Y572335D01*
X132497Y572129D01*
X132382Y573472D01*
X131347D01*
G01X128822Y570372D02*
Y573472D01*
X129282Y572852D01*
G01Y570372D02*
X128362D01*
G01X138889Y574372D02*
Y577472D01*
X137930D01*
X137624Y577317D01*
X137432Y577110D01*
X137355Y576697D01*
X137432Y576284D01*
X137662Y576025D01*
X137930Y575870D01*
X138889D01*
G01X137930D02*
X137355Y574372D01*
G01X135865Y574837D02*
X135635Y574579D01*
X135367Y574424D01*
X135022Y574372D01*
X134677Y574475D01*
X134409Y574682D01*
X134217Y575044D01*
X134179Y575457D01*
X134255Y575870D01*
X134447Y576129D01*
X134715Y576335D01*
X134984Y576387D01*
X135252Y576335D01*
X135597Y576129D01*
X135482Y577472D01*
X134447D01*
G01X132765Y574837D02*
X132535Y574579D01*
X132267Y574424D01*
X131922Y574372D01*
X131577Y574475D01*
X131309Y574682D01*
X131117Y575044D01*
X131079Y575457D01*
X131155Y575870D01*
X131347Y576129D01*
X131615Y576335D01*
X131884Y576387D01*
X132152Y576335D01*
X132497Y576129D01*
X132382Y577472D01*
X131347D01*
G01X129550Y576955D02*
X129320Y577265D01*
X129052Y577420D01*
X128745Y577472D01*
X128362Y577369D01*
X128094Y577110D01*
X128017Y576800D01*
X128055Y576490D01*
X128209Y576232D01*
X128975Y575715D01*
X129320Y575354D01*
X129550Y574837D01*
X129627Y574372D01*
X128017D01*
G01X124564Y624869D02*
X124719Y624639D01*
X124822Y624371D01*
Y624064D01*
X124667Y623719D01*
X124409Y623451D01*
X124099Y623259D01*
X123582Y623106D01*
X123117Y623068D01*
X122652Y623144D01*
X122342Y623259D01*
X122032Y623489D01*
X121825Y623758D01*
X121722Y624026D01*
Y624294D01*
X121825Y624563D01*
X121980Y624793D01*
X122187Y624984D01*
G01X121722Y627586D02*
X124822D01*
X122600Y626168D01*
Y628084D01*
G01X121722Y630226D02*
X124822D01*
X124202Y629766D01*
G01X121722D02*
Y630686D01*
G01X122084Y632674D02*
X121825Y632943D01*
X121722Y633249D01*
X121825Y633556D01*
X122135Y633824D01*
X122600Y634016D01*
X123065Y634093D01*
X123634D01*
X124099Y634016D01*
X124512Y633824D01*
X124719Y633594D01*
X124822Y633326D01*
X124719Y633019D01*
X124512Y632789D01*
X124202Y632636D01*
X123789Y632559D01*
X123427Y632636D01*
X123065Y632828D01*
X122859Y633058D01*
X122807Y633326D01*
X122910Y633633D01*
X123169Y633863D01*
X123634Y634093D01*
G01X128701Y624869D02*
X128856Y624639D01*
X128959Y624371D01*
Y624064D01*
X128804Y623719D01*
X128546Y623451D01*
X128236Y623259D01*
X127719Y623106D01*
X127254Y623068D01*
X126789Y623144D01*
X126479Y623259D01*
X126169Y623489D01*
X125962Y623758D01*
X125859Y624026D01*
Y624294D01*
X125962Y624563D01*
X126117Y624793D01*
X126324Y624984D01*
G01X126479Y626283D02*
X126117Y626513D01*
X125911Y626819D01*
X125859Y627164D01*
X125911Y627471D01*
X126169Y627778D01*
X126479Y627969D01*
X126789Y628008D01*
X127151Y627931D01*
X127409Y627663D01*
X127512Y627394D01*
Y627049D01*
G01Y627394D02*
X127667Y627624D01*
X127926Y627816D01*
X128236Y627893D01*
X128546Y627816D01*
X128804Y627624D01*
X128959Y627279D01*
X128907Y626934D01*
X128701Y626589D01*
G01X126221Y629574D02*
X125962Y629843D01*
X125859Y630149D01*
X125962Y630456D01*
X126272Y630724D01*
X126737Y630916D01*
X127202Y630993D01*
X127771D01*
X128236Y630916D01*
X128649Y630724D01*
X128856Y630494D01*
X128959Y630226D01*
X128856Y629919D01*
X128649Y629689D01*
X128339Y629536D01*
X127926Y629459D01*
X127564Y629536D01*
X127202Y629728D01*
X126996Y629958D01*
X126944Y630226D01*
X127047Y630533D01*
X127306Y630763D01*
X127771Y630993D01*
G01X127151Y632598D02*
X127512Y632866D01*
X127719Y633096D01*
X127822Y633403D01*
X127719Y633671D01*
X127512Y633863D01*
X127202Y634016D01*
X126841Y634054D01*
X126531Y634016D01*
X126221Y633863D01*
X125962Y633633D01*
X125859Y633364D01*
X125962Y633058D01*
X126272Y632789D01*
X126737Y632636D01*
X127254Y632598D01*
X127926Y632674D01*
X128287Y632789D01*
X128649Y632981D01*
X128907Y633249D01*
X128959Y633518D01*
X128856Y633786D01*
X128597Y633978D01*
G01X132684Y624869D02*
X132839Y624639D01*
X132942Y624371D01*
Y624064D01*
X132787Y623719D01*
X132529Y623451D01*
X132219Y623259D01*
X131702Y623106D01*
X131237Y623068D01*
X130772Y623144D01*
X130462Y623259D01*
X130152Y623489D01*
X129945Y623758D01*
X129842Y624026D01*
Y624294D01*
X129945Y624563D01*
X130100Y624793D01*
X130307Y624984D01*
G01X129842Y627586D02*
X132942D01*
X130720Y626168D01*
Y628084D01*
G01X132425Y629498D02*
X132735Y629728D01*
X132890Y629996D01*
X132942Y630303D01*
X132839Y630686D01*
X132580Y630954D01*
X132270Y631031D01*
X131960Y630993D01*
X131702Y630839D01*
X131185Y630073D01*
X130824Y629728D01*
X130307Y629498D01*
X129842Y629421D01*
Y631031D01*
G01X132425Y632598D02*
X132735Y632828D01*
X132890Y633096D01*
X132942Y633403D01*
X132839Y633786D01*
X132580Y634054D01*
X132270Y634131D01*
X131960Y634093D01*
X131702Y633939D01*
X131185Y633173D01*
X130824Y632828D01*
X130307Y632598D01*
X129842Y632521D01*
Y634131D01*
G01X131932Y646723D02*
X132162Y646878D01*
X132430Y646981D01*
X132737D01*
X133082Y646826D01*
X133350Y646568D01*
X133542Y646258D01*
X133695Y645741D01*
X133733Y645276D01*
X133657Y644811D01*
X133542Y644501D01*
X133312Y644191D01*
X133043Y643984D01*
X132775Y643881D01*
X132507D01*
X132238Y643984D01*
X132008Y644139D01*
X131817Y644346D01*
G01X129215Y643881D02*
Y646981D01*
X130633Y644759D01*
X128717D01*
G01X126575Y643881D02*
Y646981D01*
X127035Y646361D01*
G01Y643881D02*
X126115D01*
G01X123552D02*
X123475Y644553D01*
X123360Y645121D01*
X123207Y645638D01*
X123015Y646206D01*
X122708Y646981D01*
X124242D01*
G01X131932Y642521D02*
X132162Y642676D01*
X132430Y642779D01*
X132737D01*
X133082Y642624D01*
X133350Y642366D01*
X133542Y642056D01*
X133695Y641539D01*
X133733Y641074D01*
X133657Y640609D01*
X133542Y640299D01*
X133312Y639989D01*
X133043Y639782D01*
X132775Y639679D01*
X132507D01*
X132238Y639782D01*
X132008Y639937D01*
X131817Y640144D01*
G01X129215Y639679D02*
Y642779D01*
X130633Y640557D01*
X128717D01*
G01X126575Y642779D02*
X126882Y642676D01*
X127112Y642417D01*
X127265Y642107D01*
X127380Y641694D01*
X127418Y641229D01*
X127380Y640764D01*
X127265Y640351D01*
X127112Y640041D01*
X126882Y639782D01*
X126575Y639679D01*
X126268Y639782D01*
X126038Y640041D01*
X125885Y640351D01*
X125770Y640764D01*
X125732Y641229D01*
X125770Y641694D01*
X125885Y642107D01*
X126038Y642417D01*
X126268Y642676D01*
X126575Y642779D01*
G01X124203Y642262D02*
X123973Y642572D01*
X123705Y642727D01*
X123398Y642779D01*
X123015Y642676D01*
X122747Y642417D01*
X122670Y642107D01*
X122708Y641797D01*
X122862Y641539D01*
X123628Y641022D01*
X123973Y640661D01*
X124203Y640144D01*
X124280Y639679D01*
X122670D01*
G01X131932Y638338D02*
X132162Y638493D01*
X132430Y638596D01*
X132737D01*
X133082Y638441D01*
X133350Y638183D01*
X133542Y637873D01*
X133695Y637356D01*
X133733Y636891D01*
X133657Y636426D01*
X133542Y636116D01*
X133312Y635806D01*
X133043Y635599D01*
X132775Y635496D01*
X132507D01*
X132238Y635599D01*
X132008Y635754D01*
X131817Y635961D01*
G01X129215Y635496D02*
Y638596D01*
X130633Y636374D01*
X128717D01*
G01X127303Y638079D02*
X127073Y638389D01*
X126805Y638544D01*
X126498Y638596D01*
X126115Y638493D01*
X125847Y638234D01*
X125770Y637924D01*
X125808Y637614D01*
X125962Y637356D01*
X126728Y636839D01*
X127073Y636478D01*
X127303Y635961D01*
X127380Y635496D01*
X125770D01*
G01X123475D02*
X123207Y635548D01*
X122900Y635703D01*
X122708Y635961D01*
X122632Y636323D01*
X122708Y636684D01*
X122938Y636994D01*
X123283Y637149D01*
X123667D01*
X123897Y637253D01*
X124088Y637511D01*
X124165Y637873D01*
X124050Y638234D01*
X123782Y638493D01*
X123475Y638596D01*
X123168Y638493D01*
X122900Y638234D01*
X122785Y637873D01*
X122862Y637511D01*
X123053Y637253D01*
X123283Y637149D01*
X123667D01*
X124012Y636994D01*
X124242Y636684D01*
X124318Y636323D01*
X124242Y635961D01*
X124050Y635703D01*
X123743Y635548D01*
X123475Y635496D01*
G01X131363Y659598D02*
X131593Y659753D01*
X131861Y659856D01*
X132168D01*
X132513Y659701D01*
X132781Y659443D01*
X132973Y659133D01*
X133126Y658616D01*
X133164Y658151D01*
X133088Y657686D01*
X132973Y657376D01*
X132743Y657066D01*
X132474Y656859D01*
X132206Y656756D01*
X131938D01*
X131669Y656859D01*
X131439Y657014D01*
X131248Y657221D01*
G01X128646Y656756D02*
Y659856D01*
X130064Y657634D01*
X128148D01*
G01X126006Y659856D02*
X126313Y659753D01*
X126543Y659494D01*
X126696Y659184D01*
X126811Y658771D01*
X126849Y658306D01*
X126811Y657841D01*
X126696Y657428D01*
X126543Y657118D01*
X126313Y656859D01*
X126006Y656756D01*
X125699Y656859D01*
X125469Y657118D01*
X125316Y657428D01*
X125201Y657841D01*
X125163Y658306D01*
X125201Y658771D01*
X125316Y659184D01*
X125469Y659494D01*
X125699Y659753D01*
X126006Y659856D01*
G01X122446Y656756D02*
Y659856D01*
X123864Y657634D01*
X121948D01*
G01X131430Y655400D02*
X131660Y655555D01*
X131928Y655658D01*
X132235D01*
X132580Y655503D01*
X132848Y655245D01*
X133040Y654935D01*
X133193Y654418D01*
X133231Y653953D01*
X133155Y653488D01*
X133040Y653178D01*
X132810Y652868D01*
X132541Y652661D01*
X132273Y652558D01*
X132005D01*
X131736Y652661D01*
X131506Y652816D01*
X131315Y653023D01*
G01X128713Y652558D02*
Y655658D01*
X130131Y653436D01*
X128215D01*
G01X126073Y652558D02*
Y655658D01*
X126533Y655038D01*
G01Y652558D02*
X125613D01*
G01X122973D02*
Y655658D01*
X123433Y655038D01*
G01Y652558D02*
X122513D01*
G01X131787Y650876D02*
X132017Y651031D01*
X132285Y651134D01*
X132592D01*
X132937Y650979D01*
X133205Y650721D01*
X133397Y650411D01*
X133550Y649894D01*
X133588Y649429D01*
X133512Y648964D01*
X133397Y648654D01*
X133167Y648344D01*
X132898Y648137D01*
X132630Y648034D01*
X132362D01*
X132093Y648137D01*
X131863Y648292D01*
X131672Y648499D01*
G01X129070Y648034D02*
Y651134D01*
X130488Y648912D01*
X128572D01*
G01X126430Y651134D02*
X126737Y651031D01*
X126967Y650772D01*
X127120Y650462D01*
X127235Y650049D01*
X127273Y649584D01*
X127235Y649119D01*
X127120Y648706D01*
X126967Y648396D01*
X126737Y648137D01*
X126430Y648034D01*
X126123Y648137D01*
X125893Y648396D01*
X125740Y648706D01*
X125625Y649119D01*
X125587Y649584D01*
X125625Y650049D01*
X125740Y650462D01*
X125893Y650772D01*
X126123Y651031D01*
X126430Y651134D01*
G01X124173Y648654D02*
X123943Y648292D01*
X123637Y648086D01*
X123292Y648034D01*
X122985Y648086D01*
X122678Y648344D01*
X122487Y648654D01*
X122448Y648964D01*
X122525Y649326D01*
X122793Y649584D01*
X123062Y649687D01*
X123407D01*
G01X123062D02*
X122832Y649842D01*
X122640Y650101D01*
X122563Y650411D01*
X122640Y650721D01*
X122832Y650979D01*
X123177Y651134D01*
X123522Y651082D01*
X123867Y650876D01*
G01X133417Y733700D02*
Y736800D01*
X132458D01*
X132152Y736645D01*
X131960Y736438D01*
X131883Y736025D01*
X131960Y735612D01*
X132190Y735353D01*
X132458Y735198D01*
X133417D01*
G01X132458D02*
X131883Y733700D01*
G01X129550D02*
Y736800D01*
X130010Y736180D01*
G01Y733700D02*
X129090D01*
G01X127293Y734320D02*
X127063Y733958D01*
X126757Y733752D01*
X126412Y733700D01*
X126105Y733752D01*
X125798Y734010D01*
X125607Y734320D01*
X125568Y734630D01*
X125645Y734992D01*
X125913Y735250D01*
X126182Y735353D01*
X126527D01*
G01X126182D02*
X125952Y735508D01*
X125760Y735767D01*
X125683Y736077D01*
X125760Y736387D01*
X125952Y736645D01*
X126297Y736800D01*
X126642Y736748D01*
X126987Y736542D01*
G01X124193Y734320D02*
X123963Y733958D01*
X123657Y733752D01*
X123312Y733700D01*
X123005Y733752D01*
X122698Y734010D01*
X122507Y734320D01*
X122468Y734630D01*
X122545Y734992D01*
X122813Y735250D01*
X123082Y735353D01*
X123427D01*
G01X123082D02*
X122852Y735508D01*
X122660Y735767D01*
X122583Y736077D01*
X122660Y736387D01*
X122852Y736645D01*
X123197Y736800D01*
X123542Y736748D01*
X123887Y736542D01*
G01X120250Y733700D02*
Y736800D01*
X120710Y736180D01*
G01Y733700D02*
X119790D01*
G01X125400Y737500D02*
X131600D01*
Y740700D01*
X125400D01*
Y737500D01*
G01X134817Y745700D02*
Y748800D01*
X133858D01*
X133552Y748645D01*
X133360Y748438D01*
X133283Y748025D01*
X133360Y747612D01*
X133590Y747353D01*
X133858Y747198D01*
X134817D01*
G01X133858D02*
X133283Y745700D01*
G01X130950D02*
Y748800D01*
X131410Y748180D01*
G01Y745700D02*
X130490D01*
G01X128693Y746320D02*
X128463Y745958D01*
X128157Y745752D01*
X127812Y745700D01*
X127505Y745752D01*
X127198Y746010D01*
X127007Y746320D01*
X126968Y746630D01*
X127045Y746992D01*
X127313Y747250D01*
X127582Y747353D01*
X127927D01*
G01X127582D02*
X127352Y747508D01*
X127160Y747767D01*
X127083Y748077D01*
X127160Y748387D01*
X127352Y748645D01*
X127697Y748800D01*
X128042Y748748D01*
X128387Y748542D01*
G01X125593Y746320D02*
X125363Y745958D01*
X125057Y745752D01*
X124712Y745700D01*
X124405Y745752D01*
X124098Y746010D01*
X123907Y746320D01*
X123868Y746630D01*
X123945Y746992D01*
X124213Y747250D01*
X124482Y747353D01*
X124827D01*
G01X124482D02*
X124252Y747508D01*
X124060Y747767D01*
X123983Y748077D01*
X124060Y748387D01*
X124252Y748645D01*
X124597Y748800D01*
X124942Y748748D01*
X125287Y748542D01*
G01X122378Y748283D02*
X122148Y748593D01*
X121880Y748748D01*
X121573Y748800D01*
X121190Y748697D01*
X120922Y748438D01*
X120845Y748128D01*
X120883Y747818D01*
X121037Y747560D01*
X121803Y747043D01*
X122148Y746682D01*
X122378Y746165D01*
X122455Y745700D01*
X120845D01*
G01X131600Y744800D02*
X125400D01*
Y741600D01*
X131600D01*
Y744800D01*
G01X147860Y118710D02*
Y148320D01*
G01X198790Y118710D02*
X147860D01*
G01X150447Y152458D02*
Y155558D01*
X149488D01*
X149182Y155403D01*
X148990Y155196D01*
X148913Y154783D01*
X148990Y154370D01*
X149220Y154111D01*
X149488Y153956D01*
X150447D01*
G01X149488D02*
X148913Y152458D01*
G01X147423Y153078D02*
X147193Y152716D01*
X146887Y152510D01*
X146542Y152458D01*
X146235Y152510D01*
X145928Y152768D01*
X145737Y153078D01*
X145698Y153388D01*
X145775Y153750D01*
X146043Y154008D01*
X146312Y154111D01*
X146657D01*
G01X146312D02*
X146082Y154266D01*
X145890Y154525D01*
X145813Y154835D01*
X145890Y155145D01*
X146082Y155403D01*
X146427Y155558D01*
X146772Y155506D01*
X147117Y155300D01*
G01X144208Y153750D02*
X143940Y154111D01*
X143710Y154318D01*
X143403Y154421D01*
X143135Y154318D01*
X142943Y154111D01*
X142790Y153801D01*
X142752Y153440D01*
X142790Y153130D01*
X142943Y152820D01*
X143173Y152561D01*
X143442Y152458D01*
X143748Y152561D01*
X144017Y152871D01*
X144170Y153336D01*
X144208Y153853D01*
X144132Y154525D01*
X144017Y154886D01*
X143825Y155248D01*
X143557Y155506D01*
X143288Y155558D01*
X143020Y155455D01*
X142828Y155196D01*
G01X151047Y162317D02*
X151277Y162472D01*
X151545Y162575D01*
X151852D01*
X152197Y162420D01*
X152465Y162162D01*
X152657Y161852D01*
X152810Y161335D01*
X152848Y160870D01*
X152772Y160405D01*
X152657Y160095D01*
X152427Y159785D01*
X152158Y159578D01*
X151890Y159475D01*
X151622D01*
X151353Y159578D01*
X151123Y159733D01*
X150932Y159940D01*
G01X148790Y159475D02*
Y162575D01*
X149250Y161955D01*
G01Y159475D02*
X148330D01*
G01X146418Y162058D02*
X146188Y162368D01*
X145920Y162523D01*
X145613Y162575D01*
X145230Y162472D01*
X144962Y162213D01*
X144885Y161903D01*
X144923Y161593D01*
X145077Y161335D01*
X145843Y160818D01*
X146188Y160457D01*
X146418Y159940D01*
X146495Y159475D01*
X144885D01*
G01X143318Y160767D02*
X143050Y161128D01*
X142820Y161335D01*
X142513Y161438D01*
X142245Y161335D01*
X142053Y161128D01*
X141900Y160818D01*
X141862Y160457D01*
X141900Y160147D01*
X142053Y159837D01*
X142283Y159578D01*
X142552Y159475D01*
X142858Y159578D01*
X143127Y159888D01*
X143280Y160353D01*
X143318Y160870D01*
X143242Y161542D01*
X143127Y161903D01*
X142935Y162265D01*
X142667Y162523D01*
X142398Y162575D01*
X142130Y162472D01*
X141938Y162213D01*
G01X135760Y171052D02*
X138860D01*
Y172011D01*
X138705Y172317D01*
X138498Y172509D01*
X138085Y172586D01*
X137672Y172509D01*
X137413Y172279D01*
X137258Y172011D01*
Y171052D01*
G01Y172011D02*
X135760Y172586D01*
G01X136380Y174076D02*
X136018Y174306D01*
X135812Y174612D01*
X135760Y174957D01*
X135812Y175264D01*
X136070Y175571D01*
X136380Y175762D01*
X136690Y175801D01*
X137052Y175724D01*
X137310Y175456D01*
X137413Y175187D01*
Y174842D01*
G01Y175187D02*
X137568Y175417D01*
X137827Y175609D01*
X138137Y175686D01*
X138447Y175609D01*
X138705Y175417D01*
X138860Y175072D01*
X138808Y174727D01*
X138602Y174382D01*
G01X136122Y177367D02*
X135863Y177636D01*
X135760Y177942D01*
X135863Y178249D01*
X136173Y178517D01*
X136638Y178709D01*
X137103Y178786D01*
X137672D01*
X138137Y178709D01*
X138550Y178517D01*
X138757Y178287D01*
X138860Y178019D01*
X138757Y177712D01*
X138550Y177482D01*
X138240Y177329D01*
X137827Y177252D01*
X137465Y177329D01*
X137103Y177521D01*
X136897Y177751D01*
X136845Y178019D01*
X136948Y178326D01*
X137207Y178556D01*
X137672Y178786D01*
G01X136610Y157093D02*
X139710D01*
Y158052D01*
X139555Y158358D01*
X139348Y158550D01*
X138935Y158627D01*
X138522Y158550D01*
X138263Y158320D01*
X138108Y158052D01*
Y157093D01*
G01Y158052D02*
X136610Y158627D01*
G01Y160960D02*
X139710D01*
X139090Y160500D01*
G01X136610D02*
Y161420D01*
G01Y164520D02*
X139710D01*
X137488Y163102D01*
Y165018D01*
G01X136972Y166508D02*
X136713Y166777D01*
X136610Y167083D01*
X136713Y167390D01*
X137023Y167658D01*
X137488Y167850D01*
X137953Y167927D01*
X138522D01*
X138987Y167850D01*
X139400Y167658D01*
X139607Y167428D01*
X139710Y167160D01*
X139607Y166853D01*
X139400Y166623D01*
X139090Y166470D01*
X138677Y166393D01*
X138315Y166470D01*
X137953Y166662D01*
X137747Y166892D01*
X137695Y167160D01*
X137798Y167467D01*
X138057Y167697D01*
X138522Y167927D01*
G01X144242Y181374D02*
X144397Y181144D01*
X144500Y180876D01*
Y180569D01*
X144345Y180224D01*
X144087Y179956D01*
X143777Y179764D01*
X143260Y179611D01*
X142795Y179573D01*
X142330Y179649D01*
X142020Y179764D01*
X141710Y179994D01*
X141503Y180263D01*
X141400Y180531D01*
Y180799D01*
X141503Y181068D01*
X141658Y181298D01*
X141865Y181489D01*
G01Y182788D02*
X141607Y183018D01*
X141452Y183286D01*
X141400Y183631D01*
X141503Y183976D01*
X141710Y184244D01*
X142072Y184436D01*
X142485Y184474D01*
X142898Y184398D01*
X143157Y184206D01*
X143363Y183938D01*
X143415Y183669D01*
X143363Y183401D01*
X143157Y183056D01*
X144500Y183171D01*
Y184206D01*
G01X141762Y186079D02*
X141503Y186348D01*
X141400Y186654D01*
X141503Y186961D01*
X141813Y187229D01*
X142278Y187421D01*
X142743Y187498D01*
X143312D01*
X143777Y187421D01*
X144190Y187229D01*
X144397Y186999D01*
X144500Y186731D01*
X144397Y186424D01*
X144190Y186194D01*
X143880Y186041D01*
X143467Y185964D01*
X143105Y186041D01*
X142743Y186233D01*
X142537Y186463D01*
X142485Y186731D01*
X142588Y187038D01*
X142847Y187268D01*
X143312Y187498D01*
G01X140112Y181260D02*
X140267Y181030D01*
X140370Y180762D01*
Y180455D01*
X140215Y180110D01*
X139957Y179842D01*
X139647Y179650D01*
X139130Y179497D01*
X138665Y179459D01*
X138200Y179535D01*
X137890Y179650D01*
X137580Y179880D01*
X137373Y180149D01*
X137270Y180417D01*
Y180685D01*
X137373Y180954D01*
X137528Y181184D01*
X137735Y181375D01*
G01Y182674D02*
X137477Y182904D01*
X137322Y183172D01*
X137270Y183517D01*
X137373Y183862D01*
X137580Y184130D01*
X137942Y184322D01*
X138355Y184360D01*
X138768Y184284D01*
X139027Y184092D01*
X139233Y183824D01*
X139285Y183555D01*
X139233Y183287D01*
X139027Y182942D01*
X140370Y183057D01*
Y184092D01*
G01X137270Y186617D02*
X140370D01*
X139750Y186157D01*
G01X137270D02*
Y187077D01*
G01X150237Y175538D02*
Y178638D01*
X149278D01*
X148972Y178483D01*
X148780Y178276D01*
X148703Y177863D01*
X148780Y177450D01*
X149010Y177191D01*
X149278Y177036D01*
X150237D01*
G01X149278D02*
X148703Y175538D01*
G01X145910D02*
Y178638D01*
X147328Y176416D01*
X145412D01*
G01X143998Y178121D02*
X143768Y178431D01*
X143500Y178586D01*
X143193Y178638D01*
X142810Y178535D01*
X142542Y178276D01*
X142465Y177966D01*
X142503Y177656D01*
X142657Y177398D01*
X143423Y176881D01*
X143768Y176520D01*
X143998Y176003D01*
X144075Y175538D01*
X142465D01*
G01X139207Y191693D02*
X139437Y191848D01*
X139705Y191951D01*
X140012D01*
X140357Y191796D01*
X140625Y191538D01*
X140817Y191228D01*
X140970Y190711D01*
X141008Y190246D01*
X140932Y189781D01*
X140817Y189471D01*
X140587Y189161D01*
X140318Y188954D01*
X140050Y188851D01*
X139782D01*
X139513Y188954D01*
X139283Y189109D01*
X139092Y189316D01*
G01X137602Y189213D02*
X137333Y188954D01*
X137027Y188851D01*
X136720Y188954D01*
X136452Y189264D01*
X136260Y189729D01*
X136183Y190194D01*
Y190763D01*
X136260Y191228D01*
X136452Y191641D01*
X136682Y191848D01*
X136950Y191951D01*
X137257Y191848D01*
X137487Y191641D01*
X137640Y191331D01*
X137717Y190918D01*
X137640Y190556D01*
X137448Y190194D01*
X137218Y189988D01*
X136950Y189936D01*
X136643Y190039D01*
X136413Y190298D01*
X136183Y190763D01*
G01X134502Y189213D02*
X134233Y188954D01*
X133927Y188851D01*
X133620Y188954D01*
X133352Y189264D01*
X133160Y189729D01*
X133083Y190194D01*
Y190763D01*
X133160Y191228D01*
X133352Y191641D01*
X133582Y191848D01*
X133850Y191951D01*
X134157Y191848D01*
X134387Y191641D01*
X134540Y191331D01*
X134617Y190918D01*
X134540Y190556D01*
X134348Y190194D01*
X134118Y189988D01*
X133850Y189936D01*
X133543Y190039D01*
X133313Y190298D01*
X133083Y190763D01*
G01X142780Y197667D02*
X145880D01*
Y198626D01*
X145725Y198932D01*
X145518Y199124D01*
X145105Y199201D01*
X144692Y199124D01*
X144433Y198894D01*
X144278Y198626D01*
Y197667D01*
G01Y198626D02*
X142780Y199201D01*
G01Y201534D02*
X145880D01*
X145260Y201074D01*
G01X142780D02*
Y201994D01*
G01X145363Y203906D02*
X145673Y204136D01*
X145828Y204404D01*
X145880Y204711D01*
X145777Y205094D01*
X145518Y205362D01*
X145208Y205439D01*
X144898Y205401D01*
X144640Y205247D01*
X144123Y204481D01*
X143762Y204136D01*
X143245Y203906D01*
X142780Y203829D01*
Y205439D01*
G01X145880Y207734D02*
X145777Y207427D01*
X145518Y207197D01*
X145208Y207044D01*
X144795Y206929D01*
X144330Y206891D01*
X143865Y206929D01*
X143452Y207044D01*
X143142Y207197D01*
X142883Y207427D01*
X142780Y207734D01*
X142883Y208041D01*
X143142Y208271D01*
X143452Y208424D01*
X143865Y208539D01*
X144330Y208577D01*
X144795Y208539D01*
X145208Y208424D01*
X145518Y208271D01*
X145777Y208041D01*
X145880Y207734D01*
G01X137520Y197537D02*
X140620D01*
Y198496D01*
X140465Y198802D01*
X140258Y198994D01*
X139845Y199071D01*
X139432Y198994D01*
X139173Y198764D01*
X139018Y198496D01*
Y197537D01*
G01Y198496D02*
X137520Y199071D01*
G01Y201404D02*
X140620D01*
X140000Y200944D01*
G01X137520D02*
Y201864D01*
G01X140620Y204504D02*
X140517Y204197D01*
X140258Y203967D01*
X139948Y203814D01*
X139535Y203699D01*
X139070Y203661D01*
X138605Y203699D01*
X138192Y203814D01*
X137882Y203967D01*
X137623Y204197D01*
X137520Y204504D01*
X137623Y204811D01*
X137882Y205041D01*
X138192Y205194D01*
X138605Y205309D01*
X139070Y205347D01*
X139535Y205309D01*
X139948Y205194D01*
X140258Y205041D01*
X140517Y204811D01*
X140620Y204504D01*
G01X140103Y206876D02*
X140413Y207106D01*
X140568Y207374D01*
X140620Y207681D01*
X140517Y208064D01*
X140258Y208332D01*
X139948Y208409D01*
X139638Y208371D01*
X139380Y208217D01*
X138863Y207451D01*
X138502Y207106D01*
X137985Y206876D01*
X137520Y206799D01*
Y208409D01*
G01X153517Y193000D02*
Y196100D01*
X152558D01*
X152252Y195945D01*
X152060Y195738D01*
X151983Y195325D01*
X152060Y194912D01*
X152290Y194653D01*
X152558Y194498D01*
X153517D01*
G01X152558D02*
X151983Y193000D01*
G01X150378Y195583D02*
X150148Y195893D01*
X149880Y196048D01*
X149573Y196100D01*
X149190Y195997D01*
X148922Y195738D01*
X148845Y195428D01*
X148883Y195118D01*
X149037Y194860D01*
X149803Y194343D01*
X150148Y193982D01*
X150378Y193465D01*
X150455Y193000D01*
X148845D01*
G01X146550Y196100D02*
X146857Y195997D01*
X147087Y195738D01*
X147240Y195428D01*
X147355Y195015D01*
X147393Y194550D01*
X147355Y194085D01*
X147240Y193672D01*
X147087Y193362D01*
X146857Y193103D01*
X146550Y193000D01*
X146243Y193103D01*
X146013Y193362D01*
X145860Y193672D01*
X145745Y194085D01*
X145707Y194550D01*
X145745Y195015D01*
X145860Y195428D01*
X146013Y195738D01*
X146243Y195997D01*
X146550Y196100D01*
G01X143450D02*
X143757Y195997D01*
X143987Y195738D01*
X144140Y195428D01*
X144255Y195015D01*
X144293Y194550D01*
X144255Y194085D01*
X144140Y193672D01*
X143987Y193362D01*
X143757Y193103D01*
X143450Y193000D01*
X143143Y193103D01*
X142913Y193362D01*
X142760Y193672D01*
X142645Y194085D01*
X142607Y194550D01*
X142645Y195015D01*
X142760Y195428D01*
X142913Y195738D01*
X143143Y195997D01*
X143450Y196100D01*
G01X143420Y214230D02*
X144450D01*
G01X144320Y249314D02*
Y252514D01*
G01X141220Y252414D02*
Y249414D01*
G01X138120Y249314D02*
X144320D01*
G01X138120Y252514D02*
Y249314D01*
G01X144231Y264448D02*
Y267648D01*
G01X138031Y264448D02*
X144231D01*
G01X138031Y267648D02*
Y264448D01*
G01X141131Y267548D02*
Y264548D01*
G01X144231Y259948D02*
Y263148D01*
G01X138031Y259948D02*
X144231D01*
G01Y263148D02*
X138031D01*
G01D02*
Y259948D01*
G01X141131Y263048D02*
Y260048D01*
G01X144320Y252514D02*
X138120D01*
G01X144320Y253314D02*
Y256514D01*
G01X141220Y256414D02*
Y253414D01*
G01X138120Y253314D02*
X144320D01*
G01Y256514D02*
X138120D01*
G01D02*
Y253314D01*
G01X144231Y267648D02*
X138031D01*
G01X134410Y317110D02*
Y287610D01*
G01Y322020D02*
Y320590D01*
G01Y344020D02*
Y325980D01*
G01X143395Y355131D02*
X143550Y354901D01*
X143653Y354633D01*
Y354326D01*
X143498Y353981D01*
X143240Y353713D01*
X142930Y353521D01*
X142413Y353368D01*
X141948Y353330D01*
X141483Y353406D01*
X141173Y353521D01*
X140863Y353751D01*
X140656Y354020D01*
X140553Y354288D01*
Y354556D01*
X140656Y354825D01*
X140811Y355055D01*
X141018Y355246D01*
G01X143136Y356660D02*
X143446Y356890D01*
X143601Y357158D01*
X143653Y357465D01*
X143550Y357848D01*
X143291Y358116D01*
X142981Y358193D01*
X142671Y358155D01*
X142413Y358001D01*
X141896Y357235D01*
X141535Y356890D01*
X141018Y356660D01*
X140553Y356583D01*
Y358193D01*
G01X141845Y359760D02*
X142206Y360028D01*
X142413Y360258D01*
X142516Y360565D01*
X142413Y360833D01*
X142206Y361025D01*
X141896Y361178D01*
X141535Y361216D01*
X141225Y361178D01*
X140915Y361025D01*
X140656Y360795D01*
X140553Y360526D01*
X140656Y360220D01*
X140966Y359951D01*
X141431Y359798D01*
X141948Y359760D01*
X142620Y359836D01*
X142981Y359951D01*
X143343Y360143D01*
X143601Y360411D01*
X143653Y360680D01*
X143550Y360948D01*
X143291Y361140D01*
G01X151638Y355131D02*
X151793Y354901D01*
X151896Y354633D01*
Y354326D01*
X151741Y353981D01*
X151483Y353713D01*
X151173Y353521D01*
X150656Y353368D01*
X150191Y353330D01*
X149726Y353406D01*
X149416Y353521D01*
X149106Y353751D01*
X148899Y354020D01*
X148796Y354288D01*
Y354556D01*
X148899Y354825D01*
X149054Y355055D01*
X149261Y355246D01*
G01X151379Y356660D02*
X151689Y356890D01*
X151844Y357158D01*
X151896Y357465D01*
X151793Y357848D01*
X151534Y358116D01*
X151224Y358193D01*
X150914Y358155D01*
X150656Y358001D01*
X150139Y357235D01*
X149778Y356890D01*
X149261Y356660D01*
X148796Y356583D01*
Y358193D01*
G01X149158Y359836D02*
X148899Y360105D01*
X148796Y360411D01*
X148899Y360718D01*
X149209Y360986D01*
X149674Y361178D01*
X150139Y361255D01*
X150708D01*
X151173Y361178D01*
X151586Y360986D01*
X151793Y360756D01*
X151896Y360488D01*
X151793Y360181D01*
X151586Y359951D01*
X151276Y359798D01*
X150863Y359721D01*
X150501Y359798D01*
X150139Y359990D01*
X149933Y360220D01*
X149881Y360488D01*
X149984Y360795D01*
X150243Y361025D01*
X150708Y361255D01*
G01X136362Y353521D02*
X139462D01*
Y354480D01*
X139307Y354786D01*
X139100Y354978D01*
X138687Y355055D01*
X138274Y354978D01*
X138015Y354748D01*
X137860Y354480D01*
Y353521D01*
G01Y354480D02*
X136362Y355055D01*
G01Y357388D02*
X139462D01*
X138842Y356928D01*
G01X136362D02*
Y357848D01*
G01X136982Y359645D02*
X136620Y359875D01*
X136414Y360181D01*
X136362Y360526D01*
X136414Y360833D01*
X136672Y361140D01*
X136982Y361331D01*
X137292Y361370D01*
X137654Y361293D01*
X137912Y361025D01*
X138015Y360756D01*
Y360411D01*
G01Y360756D02*
X138170Y360986D01*
X138429Y361178D01*
X138739Y361255D01*
X139049Y361178D01*
X139307Y360986D01*
X139462Y360641D01*
X139410Y360296D01*
X139204Y359951D01*
G01X139462Y363588D02*
X139359Y363281D01*
X139100Y363051D01*
X138790Y362898D01*
X138377Y362783D01*
X137912Y362745D01*
X137447Y362783D01*
X137034Y362898D01*
X136724Y363051D01*
X136465Y363281D01*
X136362Y363588D01*
X136465Y363895D01*
X136724Y364125D01*
X137034Y364278D01*
X137447Y364393D01*
X137912Y364431D01*
X138377Y364393D01*
X138790Y364278D01*
X139100Y364125D01*
X139359Y363895D01*
X139462Y363588D01*
G01X144698Y353521D02*
X147798D01*
Y354480D01*
X147643Y354786D01*
X147436Y354978D01*
X147023Y355055D01*
X146610Y354978D01*
X146351Y354748D01*
X146196Y354480D01*
Y353521D01*
G01Y354480D02*
X144698Y355055D01*
G01Y357388D02*
X147798D01*
X147178Y356928D01*
G01X144698D02*
Y357848D01*
G01X147281Y359760D02*
X147591Y359990D01*
X147746Y360258D01*
X147798Y360565D01*
X147695Y360948D01*
X147436Y361216D01*
X147126Y361293D01*
X146816Y361255D01*
X146558Y361101D01*
X146041Y360335D01*
X145680Y359990D01*
X145163Y359760D01*
X144698Y359683D01*
Y361293D01*
G01Y363588D02*
X147798D01*
X147178Y363128D01*
G01X144698D02*
Y364048D01*
G01X145658Y368555D02*
Y374755D01*
G01X142558Y371655D02*
X145558D01*
G01X145658Y374755D02*
X142458D01*
G01D02*
Y368555D01*
G01D02*
X145658D01*
G01X149658Y374755D02*
X146458D01*
G01D02*
Y368555D01*
G01D02*
X149658D01*
G01X146518Y386365D02*
X149618D01*
Y387324D01*
X149463Y387630D01*
X149256Y387822D01*
X148843Y387899D01*
X148430Y387822D01*
X148171Y387592D01*
X148016Y387324D01*
Y386365D01*
G01Y387324D02*
X146518Y387899D01*
G01Y390232D02*
X149618D01*
X148998Y389772D01*
G01X146518D02*
Y390692D01*
G01X149101Y392604D02*
X149411Y392834D01*
X149566Y393102D01*
X149618Y393409D01*
X149515Y393792D01*
X149256Y394060D01*
X148946Y394137D01*
X148636Y394099D01*
X148378Y393945D01*
X147861Y393179D01*
X147500Y392834D01*
X146983Y392604D01*
X146518Y392527D01*
Y394137D01*
G01X147810Y395704D02*
X148171Y395972D01*
X148378Y396202D01*
X148481Y396509D01*
X148378Y396777D01*
X148171Y396969D01*
X147861Y397122D01*
X147500Y397160D01*
X147190Y397122D01*
X146880Y396969D01*
X146621Y396739D01*
X146518Y396470D01*
X146621Y396164D01*
X146931Y395895D01*
X147396Y395742D01*
X147913Y395704D01*
X148585Y395780D01*
X148946Y395895D01*
X149308Y396087D01*
X149566Y396355D01*
X149618Y396624D01*
X149515Y396892D01*
X149256Y397084D01*
G01X149599Y385257D02*
X146399D01*
G01D02*
Y379057D01*
G01D02*
X149599D01*
G01X137203Y420205D02*
Y405205D01*
G01X144003D02*
Y420205D01*
G01X137203Y405205D02*
X144003D01*
G01X136160Y405389D02*
Y420389D01*
G01X149478Y418382D02*
X149633Y418152D01*
X149736Y417884D01*
Y417577D01*
X149581Y417232D01*
X149323Y416964D01*
X149013Y416772D01*
X148496Y416619D01*
X148031Y416581D01*
X147566Y416657D01*
X147256Y416772D01*
X146946Y417002D01*
X146739Y417271D01*
X146636Y417539D01*
Y417807D01*
X146739Y418076D01*
X146894Y418306D01*
X147101Y418497D01*
G01X146636Y420639D02*
X146688Y420907D01*
X146843Y421214D01*
X147101Y421406D01*
X147463Y421482D01*
X147824Y421406D01*
X148134Y421176D01*
X148289Y420831D01*
Y420447D01*
X148393Y420217D01*
X148651Y420026D01*
X149013Y419949D01*
X149374Y420064D01*
X149633Y420332D01*
X149736Y420639D01*
X149633Y420946D01*
X149374Y421214D01*
X149013Y421329D01*
X148651Y421252D01*
X148393Y421061D01*
X148289Y420831D01*
Y420447D01*
X148134Y420102D01*
X147824Y419872D01*
X147463Y419796D01*
X147101Y419872D01*
X146843Y420064D01*
X146688Y420371D01*
X146636Y420639D01*
G01X149219Y423011D02*
X149529Y423241D01*
X149684Y423509D01*
X149736Y423816D01*
X149633Y424199D01*
X149374Y424467D01*
X149064Y424544D01*
X148754Y424506D01*
X148496Y424352D01*
X147979Y423586D01*
X147618Y423241D01*
X147101Y423011D01*
X146636Y422934D01*
Y424544D01*
G01Y426839D02*
X149736D01*
X149116Y426379D01*
G01X146636D02*
Y427299D01*
G01X144003Y420205D02*
X137203D01*
G01X143903Y412705D02*
X137303D01*
G01X148275Y415124D02*
X145075D01*
G01X148275Y408924D02*
Y415124D01*
G01X145075Y408924D02*
X148275D01*
G01X145075Y415124D02*
Y408924D01*
G01X148175Y412024D02*
X145175D01*
G01X135535Y493922D02*
Y508922D01*
G01X142195Y519761D02*
X142350Y519531D01*
X142453Y519263D01*
Y518956D01*
X142298Y518611D01*
X142040Y518343D01*
X141730Y518151D01*
X141213Y517998D01*
X140748Y517960D01*
X140283Y518036D01*
X139973Y518151D01*
X139663Y518381D01*
X139456Y518650D01*
X139353Y518918D01*
Y519186D01*
X139456Y519455D01*
X139611Y519685D01*
X139818Y519876D01*
G01X141936Y521290D02*
X142246Y521520D01*
X142401Y521788D01*
X142453Y522095D01*
X142350Y522478D01*
X142091Y522746D01*
X141781Y522823D01*
X141471Y522785D01*
X141213Y522631D01*
X140696Y521865D01*
X140335Y521520D01*
X139818Y521290D01*
X139353Y521213D01*
Y522823D01*
G01X141936Y524390D02*
X142246Y524620D01*
X142401Y524888D01*
X142453Y525195D01*
X142350Y525578D01*
X142091Y525846D01*
X141781Y525923D01*
X141471Y525885D01*
X141213Y525731D01*
X140696Y524965D01*
X140335Y524620D01*
X139818Y524390D01*
X139353Y524313D01*
Y525923D01*
G01X140645Y527490D02*
X141006Y527758D01*
X141213Y527988D01*
X141316Y528295D01*
X141213Y528563D01*
X141006Y528755D01*
X140696Y528908D01*
X140335Y528946D01*
X140025Y528908D01*
X139715Y528755D01*
X139456Y528525D01*
X139353Y528256D01*
X139456Y527950D01*
X139766Y527681D01*
X140231Y527528D01*
X140748Y527490D01*
X141420Y527566D01*
X141781Y527681D01*
X142143Y527873D01*
X142401Y528141D01*
X142453Y528410D01*
X142350Y528678D01*
X142091Y528870D01*
G01X147674Y505419D02*
X147829Y505189D01*
X147932Y504921D01*
Y504614D01*
X147777Y504269D01*
X147519Y504001D01*
X147209Y503809D01*
X146692Y503656D01*
X146227Y503618D01*
X145762Y503694D01*
X145452Y503809D01*
X145142Y504039D01*
X144935Y504308D01*
X144832Y504576D01*
Y504844D01*
X144935Y505113D01*
X145090Y505343D01*
X145297Y505534D01*
G01X147415Y506948D02*
X147725Y507178D01*
X147880Y507446D01*
X147932Y507753D01*
X147829Y508136D01*
X147570Y508404D01*
X147260Y508481D01*
X146950Y508443D01*
X146692Y508289D01*
X146175Y507523D01*
X145814Y507178D01*
X145297Y506948D01*
X144832Y506871D01*
Y508481D01*
G01X145452Y509933D02*
X145090Y510163D01*
X144884Y510469D01*
X144832Y510814D01*
X144884Y511121D01*
X145142Y511428D01*
X145452Y511619D01*
X145762Y511658D01*
X146124Y511581D01*
X146382Y511313D01*
X146485Y511044D01*
Y510699D01*
G01Y511044D02*
X146640Y511274D01*
X146899Y511466D01*
X147209Y511543D01*
X147519Y511466D01*
X147777Y511274D01*
X147932Y510929D01*
X147880Y510584D01*
X147674Y510239D01*
G01X147932Y513876D02*
X147829Y513569D01*
X147570Y513339D01*
X147260Y513186D01*
X146847Y513071D01*
X146382Y513033D01*
X145917Y513071D01*
X145504Y513186D01*
X145194Y513339D01*
X144935Y513569D01*
X144832Y513876D01*
X144935Y514183D01*
X145194Y514413D01*
X145504Y514566D01*
X145917Y514681D01*
X146382Y514719D01*
X146847Y514681D01*
X147260Y514566D01*
X147570Y514413D01*
X147829Y514183D01*
X147932Y513876D01*
G01X135402Y518203D02*
X138502D01*
Y519162D01*
X138347Y519468D01*
X138140Y519660D01*
X137727Y519737D01*
X137314Y519660D01*
X137055Y519430D01*
X136900Y519162D01*
Y518203D01*
G01Y519162D02*
X135402Y519737D01*
G01X137985Y521342D02*
X138295Y521572D01*
X138450Y521840D01*
X138502Y522147D01*
X138399Y522530D01*
X138140Y522798D01*
X137830Y522875D01*
X137520Y522837D01*
X137262Y522683D01*
X136745Y521917D01*
X136384Y521572D01*
X135867Y521342D01*
X135402Y521265D01*
Y522875D01*
G01X136694Y524442D02*
X137055Y524710D01*
X137262Y524940D01*
X137365Y525247D01*
X137262Y525515D01*
X137055Y525707D01*
X136745Y525860D01*
X136384Y525898D01*
X136074Y525860D01*
X135764Y525707D01*
X135505Y525477D01*
X135402Y525208D01*
X135505Y524902D01*
X135815Y524633D01*
X136280Y524480D01*
X136797Y524442D01*
X137469Y524518D01*
X137830Y524633D01*
X138192Y524825D01*
X138450Y525093D01*
X138502Y525362D01*
X138399Y525630D01*
X138140Y525822D01*
G01X135402Y528270D02*
X138502D01*
X137882Y527810D01*
G01X135402D02*
Y528730D01*
G01X150982Y525353D02*
X147982D01*
G01X151082Y528453D02*
X147882D01*
G01Y522253D02*
X151082D01*
G01X147882Y528453D02*
Y522253D01*
G01X147131Y528505D02*
X143931D01*
G01X147131Y522305D02*
Y528505D01*
G01X143931Y522305D02*
X147131D01*
G01X143931Y528505D02*
Y522305D01*
G01X148117Y542450D02*
Y539450D01*
G01X145017Y542550D02*
Y539350D01*
G01X151217Y542550D02*
X145017D01*
G01Y539350D02*
X151217D01*
G01X148217Y535508D02*
Y538508D01*
G01X145117Y535408D02*
X151317D01*
G01X145117Y538608D02*
Y535408D01*
G01X151317Y538608D02*
X145117D01*
G01X148209Y548853D02*
Y551853D01*
G01X145109Y548753D02*
X151309D01*
G01X145109Y551953D02*
Y548753D01*
G01Y543253D02*
X151309D01*
G01X145109Y546453D02*
Y543253D01*
G01X151309Y546453D02*
X145109D01*
G01X151309Y551953D02*
X145109D01*
G01X149725Y566637D02*
X149955Y566792D01*
X150223Y566895D01*
X150530D01*
X150875Y566740D01*
X151143Y566482D01*
X151335Y566172D01*
X151488Y565655D01*
X151526Y565190D01*
X151450Y564725D01*
X151335Y564415D01*
X151105Y564105D01*
X150836Y563898D01*
X150568Y563795D01*
X150300D01*
X150031Y563898D01*
X149801Y564053D01*
X149610Y564260D01*
G01X148196Y566378D02*
X147966Y566688D01*
X147698Y566843D01*
X147391Y566895D01*
X147008Y566792D01*
X146740Y566533D01*
X146663Y566223D01*
X146701Y565913D01*
X146855Y565655D01*
X147621Y565138D01*
X147966Y564777D01*
X148196Y564260D01*
X148273Y563795D01*
X146663D01*
G01X145096Y566378D02*
X144866Y566688D01*
X144598Y566843D01*
X144291Y566895D01*
X143908Y566792D01*
X143640Y566533D01*
X143563Y566223D01*
X143601Y565913D01*
X143755Y565655D01*
X144521Y565138D01*
X144866Y564777D01*
X145096Y564260D01*
X145173Y563795D01*
X143563D01*
G01X141920Y564157D02*
X141651Y563898D01*
X141345Y563795D01*
X141038Y563898D01*
X140770Y564208D01*
X140578Y564673D01*
X140501Y565138D01*
Y565707D01*
X140578Y566172D01*
X140770Y566585D01*
X141000Y566792D01*
X141268Y566895D01*
X141575Y566792D01*
X141805Y566585D01*
X141958Y566275D01*
X142035Y565862D01*
X141958Y565500D01*
X141766Y565138D01*
X141536Y564932D01*
X141268Y564880D01*
X140961Y564983D01*
X140731Y565242D01*
X140501Y565707D01*
G01X146210Y582613D02*
Y579413D01*
G01D02*
X152410D01*
G01Y574705D02*
X146210D01*
G01D02*
Y571505D01*
G01D02*
X152410D01*
G01X146210Y575505D02*
X152410D01*
G01Y578705D02*
X146210D01*
G01D02*
Y575505D01*
G01X146130Y599735D02*
Y596535D01*
G01D02*
X152330D01*
G01X152363Y595737D02*
X146163D01*
G01D02*
Y592537D01*
G01D02*
X152363D01*
G01X152410Y582613D02*
X146210D01*
G01X152428Y612302D02*
X146228D01*
G01D02*
Y609102D01*
G01D02*
X152428D01*
G01X152330Y599735D02*
X146130D01*
G01X146228Y620635D02*
Y617435D01*
G01D02*
X152428D01*
G01Y620635D02*
X146228D01*
G01Y616335D02*
Y613135D01*
G01D02*
X152428D01*
G01Y616335D02*
X146228D01*
G01X143427Y626212D02*
X143657Y626367D01*
X143925Y626470D01*
X144232D01*
X144577Y626315D01*
X144845Y626057D01*
X145037Y625747D01*
X145190Y625230D01*
X145228Y624765D01*
X145152Y624300D01*
X145037Y623990D01*
X144807Y623680D01*
X144538Y623473D01*
X144270Y623370D01*
X144002D01*
X143733Y623473D01*
X143503Y623628D01*
X143312Y623835D01*
G01X140710Y623370D02*
Y626470D01*
X142128Y624248D01*
X140212D01*
G01X138070Y623370D02*
Y626470D01*
X138530Y625850D01*
G01Y623370D02*
X137610D01*
G01X135698Y625953D02*
X135468Y626263D01*
X135200Y626418D01*
X134893Y626470D01*
X134510Y626367D01*
X134242Y626108D01*
X134165Y625798D01*
X134203Y625488D01*
X134357Y625230D01*
X135123Y624713D01*
X135468Y624352D01*
X135698Y623835D01*
X135775Y623370D01*
X134165D01*
G01X143427Y630171D02*
X143657Y630326D01*
X143925Y630429D01*
X144232D01*
X144577Y630274D01*
X144845Y630016D01*
X145037Y629706D01*
X145190Y629189D01*
X145228Y628724D01*
X145152Y628259D01*
X145037Y627949D01*
X144807Y627639D01*
X144538Y627432D01*
X144270Y627329D01*
X144002D01*
X143733Y627432D01*
X143503Y627587D01*
X143312Y627794D01*
G01X140710Y627329D02*
Y630429D01*
X142128Y628207D01*
X140212D01*
G01X138070Y627329D02*
Y630429D01*
X138530Y629809D01*
G01Y627329D02*
X137610D01*
G01X134970Y630429D02*
X135277Y630326D01*
X135507Y630067D01*
X135660Y629757D01*
X135775Y629344D01*
X135813Y628879D01*
X135775Y628414D01*
X135660Y628001D01*
X135507Y627691D01*
X135277Y627432D01*
X134970Y627329D01*
X134663Y627432D01*
X134433Y627691D01*
X134280Y628001D01*
X134165Y628414D01*
X134127Y628879D01*
X134165Y629344D01*
X134280Y629757D01*
X134433Y630067D01*
X134663Y630326D01*
X134970Y630429D01*
G01X143427Y622247D02*
X143657Y622402D01*
X143925Y622505D01*
X144232D01*
X144577Y622350D01*
X144845Y622092D01*
X145037Y621782D01*
X145190Y621265D01*
X145228Y620800D01*
X145152Y620335D01*
X145037Y620025D01*
X144807Y619715D01*
X144538Y619508D01*
X144270Y619405D01*
X144002D01*
X143733Y619508D01*
X143503Y619663D01*
X143312Y619870D01*
G01X140710Y619405D02*
Y622505D01*
X142128Y620283D01*
X140212D01*
G01X138070Y622505D02*
X138377Y622402D01*
X138607Y622143D01*
X138760Y621833D01*
X138875Y621420D01*
X138913Y620955D01*
X138875Y620490D01*
X138760Y620077D01*
X138607Y619767D01*
X138377Y619508D01*
X138070Y619405D01*
X137763Y619508D01*
X137533Y619767D01*
X137380Y620077D01*
X137265Y620490D01*
X137227Y620955D01*
X137265Y621420D01*
X137380Y621833D01*
X137533Y622143D01*
X137763Y622402D01*
X138070Y622505D01*
G01X135813Y619870D02*
X135583Y619612D01*
X135315Y619457D01*
X134970Y619405D01*
X134625Y619508D01*
X134357Y619715D01*
X134165Y620077D01*
X134127Y620490D01*
X134203Y620903D01*
X134395Y621162D01*
X134663Y621368D01*
X134932Y621420D01*
X135200Y621368D01*
X135545Y621162D01*
X135430Y622505D01*
X134395D01*
G01X143427Y618282D02*
X143657Y618437D01*
X143925Y618540D01*
X144232D01*
X144577Y618385D01*
X144845Y618127D01*
X145037Y617817D01*
X145190Y617300D01*
X145228Y616835D01*
X145152Y616370D01*
X145037Y616060D01*
X144807Y615750D01*
X144538Y615543D01*
X144270Y615440D01*
X144002D01*
X143733Y615543D01*
X143503Y615698D01*
X143312Y615905D01*
G01X140710Y615440D02*
Y618540D01*
X142128Y616318D01*
X140212D01*
G01X138798Y618023D02*
X138568Y618333D01*
X138300Y618488D01*
X137993Y618540D01*
X137610Y618437D01*
X137342Y618178D01*
X137265Y617868D01*
X137303Y617558D01*
X137457Y617300D01*
X138223Y616783D01*
X138568Y616422D01*
X138798Y615905D01*
X138875Y615440D01*
X137265D01*
G01X134970Y618540D02*
X135277Y618437D01*
X135507Y618178D01*
X135660Y617868D01*
X135775Y617455D01*
X135813Y616990D01*
X135775Y616525D01*
X135660Y616112D01*
X135507Y615802D01*
X135277Y615543D01*
X134970Y615440D01*
X134663Y615543D01*
X134433Y615802D01*
X134280Y616112D01*
X134165Y616525D01*
X134127Y616990D01*
X134165Y617455D01*
X134280Y617868D01*
X134433Y618178D01*
X134663Y618437D01*
X134970Y618540D01*
G01X143427Y633978D02*
X143657Y634133D01*
X143925Y634236D01*
X144232D01*
X144577Y634081D01*
X144845Y633823D01*
X145037Y633513D01*
X145190Y632996D01*
X145228Y632531D01*
X145152Y632066D01*
X145037Y631756D01*
X144807Y631446D01*
X144538Y631239D01*
X144270Y631136D01*
X144002D01*
X143733Y631239D01*
X143503Y631394D01*
X143312Y631601D01*
G01X140710Y631136D02*
Y634236D01*
X142128Y632014D01*
X140212D01*
G01X138798Y633719D02*
X138568Y634029D01*
X138300Y634184D01*
X137993Y634236D01*
X137610Y634133D01*
X137342Y633874D01*
X137265Y633564D01*
X137303Y633254D01*
X137457Y632996D01*
X138223Y632479D01*
X138568Y632118D01*
X138798Y631601D01*
X138875Y631136D01*
X137265D01*
G01X135813Y631756D02*
X135583Y631394D01*
X135277Y631188D01*
X134932Y631136D01*
X134625Y631188D01*
X134318Y631446D01*
X134127Y631756D01*
X134088Y632066D01*
X134165Y632428D01*
X134433Y632686D01*
X134702Y632789D01*
X135047D01*
G01X134702D02*
X134472Y632944D01*
X134280Y633203D01*
X134203Y633513D01*
X134280Y633823D01*
X134472Y634081D01*
X134817Y634236D01*
X135162Y634184D01*
X135507Y633978D01*
G01X143427Y638178D02*
X143657Y638333D01*
X143925Y638436D01*
X144232D01*
X144577Y638281D01*
X144845Y638023D01*
X145037Y637713D01*
X145190Y637196D01*
X145228Y636731D01*
X145152Y636266D01*
X145037Y635956D01*
X144807Y635646D01*
X144538Y635439D01*
X144270Y635336D01*
X144002D01*
X143733Y635439D01*
X143503Y635594D01*
X143312Y635801D01*
G01X142013Y635956D02*
X141783Y635594D01*
X141477Y635388D01*
X141132Y635336D01*
X140825Y635388D01*
X140518Y635646D01*
X140327Y635956D01*
X140288Y636266D01*
X140365Y636628D01*
X140633Y636886D01*
X140902Y636989D01*
X141247D01*
G01X140902D02*
X140672Y637144D01*
X140480Y637403D01*
X140403Y637713D01*
X140480Y638023D01*
X140672Y638281D01*
X141017Y638436D01*
X141362Y638384D01*
X141707Y638178D01*
G01X138722Y635698D02*
X138453Y635439D01*
X138147Y635336D01*
X137840Y635439D01*
X137572Y635749D01*
X137380Y636214D01*
X137303Y636679D01*
Y637248D01*
X137380Y637713D01*
X137572Y638126D01*
X137802Y638333D01*
X138070Y638436D01*
X138377Y638333D01*
X138607Y638126D01*
X138760Y637816D01*
X138837Y637403D01*
X138760Y637041D01*
X138568Y636679D01*
X138338Y636473D01*
X138070Y636421D01*
X137763Y636524D01*
X137533Y636783D01*
X137303Y637248D01*
G01X134970Y635336D02*
X134702Y635388D01*
X134395Y635543D01*
X134203Y635801D01*
X134127Y636163D01*
X134203Y636524D01*
X134433Y636834D01*
X134778Y636989D01*
X135162D01*
X135392Y637093D01*
X135583Y637351D01*
X135660Y637713D01*
X135545Y638074D01*
X135277Y638333D01*
X134970Y638436D01*
X134663Y638333D01*
X134395Y638074D01*
X134280Y637713D01*
X134357Y637351D01*
X134548Y637093D01*
X134778Y636989D01*
X135162D01*
X135507Y636834D01*
X135737Y636524D01*
X135813Y636163D01*
X135737Y635801D01*
X135545Y635543D01*
X135238Y635388D01*
X134970Y635336D01*
G01X143427Y642193D02*
X143657Y642348D01*
X143925Y642451D01*
X144232D01*
X144577Y642296D01*
X144845Y642038D01*
X145037Y641728D01*
X145190Y641211D01*
X145228Y640746D01*
X145152Y640281D01*
X145037Y639971D01*
X144807Y639661D01*
X144538Y639454D01*
X144270Y639351D01*
X144002D01*
X143733Y639454D01*
X143503Y639609D01*
X143312Y639816D01*
G01X142013Y639971D02*
X141783Y639609D01*
X141477Y639403D01*
X141132Y639351D01*
X140825Y639403D01*
X140518Y639661D01*
X140327Y639971D01*
X140288Y640281D01*
X140365Y640643D01*
X140633Y640901D01*
X140902Y641004D01*
X141247D01*
G01X140902D02*
X140672Y641159D01*
X140480Y641418D01*
X140403Y641728D01*
X140480Y642038D01*
X140672Y642296D01*
X141017Y642451D01*
X141362Y642399D01*
X141707Y642193D01*
G01X138722Y639713D02*
X138453Y639454D01*
X138147Y639351D01*
X137840Y639454D01*
X137572Y639764D01*
X137380Y640229D01*
X137303Y640694D01*
Y641263D01*
X137380Y641728D01*
X137572Y642141D01*
X137802Y642348D01*
X138070Y642451D01*
X138377Y642348D01*
X138607Y642141D01*
X138760Y641831D01*
X138837Y641418D01*
X138760Y641056D01*
X138568Y640694D01*
X138338Y640488D01*
X138070Y640436D01*
X137763Y640539D01*
X137533Y640798D01*
X137303Y641263D01*
G01X134510Y639351D02*
Y642451D01*
X135928Y640229D01*
X134012D01*
G01X138670Y656533D02*
X138825Y656303D01*
X138928Y656035D01*
Y655728D01*
X138773Y655383D01*
X138515Y655115D01*
X138205Y654923D01*
X137688Y654770D01*
X137223Y654732D01*
X136758Y654808D01*
X136448Y654923D01*
X136138Y655153D01*
X135931Y655422D01*
X135828Y655690D01*
Y655958D01*
X135931Y656227D01*
X136086Y656457D01*
X136293Y656648D01*
G01X135828Y659250D02*
X138928D01*
X136706Y657832D01*
Y659748D01*
G01X138928Y661890D02*
X138825Y661583D01*
X138566Y661353D01*
X138256Y661200D01*
X137843Y661085D01*
X137378Y661047D01*
X136913Y661085D01*
X136500Y661200D01*
X136190Y661353D01*
X135931Y661583D01*
X135828Y661890D01*
X135931Y662197D01*
X136190Y662427D01*
X136500Y662580D01*
X136913Y662695D01*
X137378Y662733D01*
X137843Y662695D01*
X138256Y662580D01*
X138566Y662427D01*
X138825Y662197D01*
X138928Y661890D01*
G01X135828Y664990D02*
X135880Y665258D01*
X136035Y665565D01*
X136293Y665757D01*
X136655Y665833D01*
X137016Y665757D01*
X137326Y665527D01*
X137481Y665182D01*
Y664798D01*
X137585Y664568D01*
X137843Y664377D01*
X138205Y664300D01*
X138566Y664415D01*
X138825Y664683D01*
X138928Y664990D01*
X138825Y665297D01*
X138566Y665565D01*
X138205Y665680D01*
X137843Y665603D01*
X137585Y665412D01*
X137481Y665182D01*
Y664798D01*
X137326Y664453D01*
X137016Y664223D01*
X136655Y664147D01*
X136293Y664223D01*
X136035Y664415D01*
X135880Y664722D01*
X135828Y664990D01*
G01X151337Y656403D02*
X151492Y656173D01*
X151595Y655905D01*
Y655598D01*
X151440Y655253D01*
X151182Y654985D01*
X150872Y654793D01*
X150355Y654640D01*
X149890Y654602D01*
X149425Y654678D01*
X149115Y654793D01*
X148805Y655023D01*
X148598Y655292D01*
X148495Y655560D01*
Y655828D01*
X148598Y656097D01*
X148753Y656327D01*
X148960Y656518D01*
G01X148495Y659120D02*
X151595D01*
X149373Y657702D01*
Y659618D01*
G01X148495Y661760D02*
X151595D01*
X150975Y661300D01*
G01X148495D02*
Y662220D01*
G01Y664860D02*
X148547Y665128D01*
X148702Y665435D01*
X148960Y665627D01*
X149322Y665703D01*
X149683Y665627D01*
X149993Y665397D01*
X150148Y665052D01*
Y664668D01*
X150252Y664438D01*
X150510Y664247D01*
X150872Y664170D01*
X151233Y664285D01*
X151492Y664553D01*
X151595Y664860D01*
X151492Y665167D01*
X151233Y665435D01*
X150872Y665550D01*
X150510Y665473D01*
X150252Y665282D01*
X150148Y665052D01*
Y664668D01*
X149993Y664323D01*
X149683Y664093D01*
X149322Y664017D01*
X148960Y664093D01*
X148702Y664285D01*
X148547Y664592D01*
X148495Y664860D01*
G01X147037Y656533D02*
X147192Y656303D01*
X147295Y656035D01*
Y655728D01*
X147140Y655383D01*
X146882Y655115D01*
X146572Y654923D01*
X146055Y654770D01*
X145590Y654732D01*
X145125Y654808D01*
X144815Y654923D01*
X144505Y655153D01*
X144298Y655422D01*
X144195Y655690D01*
Y655958D01*
X144298Y656227D01*
X144453Y656457D01*
X144660Y656648D01*
G01X144195Y659250D02*
X147295D01*
X145073Y657832D01*
Y659748D01*
G01X146778Y661162D02*
X147088Y661392D01*
X147243Y661660D01*
X147295Y661967D01*
X147192Y662350D01*
X146933Y662618D01*
X146623Y662695D01*
X146313Y662657D01*
X146055Y662503D01*
X145538Y661737D01*
X145177Y661392D01*
X144660Y661162D01*
X144195Y661085D01*
Y662695D01*
G01X144660Y664147D02*
X144402Y664377D01*
X144247Y664645D01*
X144195Y664990D01*
X144298Y665335D01*
X144505Y665603D01*
X144867Y665795D01*
X145280Y665833D01*
X145693Y665757D01*
X145952Y665565D01*
X146158Y665297D01*
X146210Y665028D01*
X146158Y664760D01*
X145952Y664415D01*
X147295Y664530D01*
Y665565D01*
G01X142937Y656533D02*
X143092Y656303D01*
X143195Y656035D01*
Y655728D01*
X143040Y655383D01*
X142782Y655115D01*
X142472Y654923D01*
X141955Y654770D01*
X141490Y654732D01*
X141025Y654808D01*
X140715Y654923D01*
X140405Y655153D01*
X140198Y655422D01*
X140095Y655690D01*
Y655958D01*
X140198Y656227D01*
X140353Y656457D01*
X140560Y656648D01*
G01X140095Y659250D02*
X143195D01*
X140973Y657832D01*
Y659748D01*
G01X143195Y661890D02*
X143092Y661583D01*
X142833Y661353D01*
X142523Y661200D01*
X142110Y661085D01*
X141645Y661047D01*
X141180Y661085D01*
X140767Y661200D01*
X140457Y661353D01*
X140198Y661583D01*
X140095Y661890D01*
X140198Y662197D01*
X140457Y662427D01*
X140767Y662580D01*
X141180Y662695D01*
X141645Y662733D01*
X142110Y662695D01*
X142523Y662580D01*
X142833Y662427D01*
X143092Y662197D01*
X143195Y661890D01*
G01X140457Y664338D02*
X140198Y664607D01*
X140095Y664913D01*
X140198Y665220D01*
X140508Y665488D01*
X140973Y665680D01*
X141438Y665757D01*
X142007D01*
X142472Y665680D01*
X142885Y665488D01*
X143092Y665258D01*
X143195Y664990D01*
X143092Y664683D01*
X142885Y664453D01*
X142575Y664300D01*
X142162Y664223D01*
X141800Y664300D01*
X141438Y664492D01*
X141232Y664722D01*
X141180Y664990D01*
X141283Y665297D01*
X141542Y665527D01*
X142007Y665757D01*
G01X150569Y704252D02*
X150724Y704022D01*
X150827Y703754D01*
Y703447D01*
X150672Y703102D01*
X150414Y702834D01*
X150104Y702642D01*
X149587Y702489D01*
X149122Y702451D01*
X148657Y702527D01*
X148347Y702642D01*
X148037Y702872D01*
X147830Y703141D01*
X147727Y703409D01*
Y703677D01*
X147830Y703946D01*
X147985Y704176D01*
X148192Y704367D01*
G01X149019Y705781D02*
X149380Y706049D01*
X149587Y706279D01*
X149690Y706586D01*
X149587Y706854D01*
X149380Y707046D01*
X149070Y707199D01*
X148709Y707237D01*
X148399Y707199D01*
X148089Y707046D01*
X147830Y706816D01*
X147727Y706547D01*
X147830Y706241D01*
X148140Y705972D01*
X148605Y705819D01*
X149122Y705781D01*
X149794Y705857D01*
X150155Y705972D01*
X150517Y706164D01*
X150775Y706432D01*
X150827Y706701D01*
X150724Y706969D01*
X150465Y707161D01*
G01X147727Y709609D02*
X150827D01*
X150207Y709149D01*
G01X147727D02*
Y710069D01*
G01X150310Y711981D02*
X150620Y712211D01*
X150775Y712479D01*
X150827Y712786D01*
X150724Y713169D01*
X150465Y713437D01*
X150155Y713514D01*
X149845Y713476D01*
X149587Y713322D01*
X149070Y712556D01*
X148709Y712211D01*
X148192Y711981D01*
X147727Y711904D01*
Y713514D01*
G01X146576Y704252D02*
X146731Y704022D01*
X146834Y703754D01*
Y703447D01*
X146679Y703102D01*
X146421Y702834D01*
X146111Y702642D01*
X145594Y702489D01*
X145129Y702451D01*
X144664Y702527D01*
X144354Y702642D01*
X144044Y702872D01*
X143837Y703141D01*
X143734Y703409D01*
Y703677D01*
X143837Y703946D01*
X143992Y704176D01*
X144199Y704367D01*
G01X145026Y705781D02*
X145387Y706049D01*
X145594Y706279D01*
X145697Y706586D01*
X145594Y706854D01*
X145387Y707046D01*
X145077Y707199D01*
X144716Y707237D01*
X144406Y707199D01*
X144096Y707046D01*
X143837Y706816D01*
X143734Y706547D01*
X143837Y706241D01*
X144147Y705972D01*
X144612Y705819D01*
X145129Y705781D01*
X145801Y705857D01*
X146162Y705972D01*
X146524Y706164D01*
X146782Y706432D01*
X146834Y706701D01*
X146731Y706969D01*
X146472Y707161D01*
G01X143734Y709609D02*
X146834D01*
X146214Y709149D01*
G01X143734D02*
Y710069D01*
G01X144199Y711866D02*
X143941Y712096D01*
X143786Y712364D01*
X143734Y712709D01*
X143837Y713054D01*
X144044Y713322D01*
X144406Y713514D01*
X144819Y713552D01*
X145232Y713476D01*
X145491Y713284D01*
X145697Y713016D01*
X145749Y712747D01*
X145697Y712479D01*
X145491Y712134D01*
X146834Y712249D01*
Y713284D01*
G01X163597Y124851D02*
X163827Y125006D01*
X164095Y125109D01*
X164402D01*
X164747Y124954D01*
X165015Y124696D01*
X165207Y124386D01*
X165360Y123869D01*
X165398Y123404D01*
X165322Y122939D01*
X165207Y122629D01*
X164977Y122319D01*
X164708Y122112D01*
X164440Y122009D01*
X164172D01*
X163903Y122112D01*
X163673Y122267D01*
X163482Y122474D01*
G01X161340Y122009D02*
Y125109D01*
X161800Y124489D01*
G01Y122009D02*
X160880D01*
G01X158240D02*
Y125109D01*
X158700Y124489D01*
G01Y122009D02*
X157780D01*
G01X155140D02*
X154872Y122061D01*
X154565Y122216D01*
X154373Y122474D01*
X154297Y122836D01*
X154373Y123197D01*
X154603Y123507D01*
X154948Y123662D01*
X155332D01*
X155562Y123766D01*
X155753Y124024D01*
X155830Y124386D01*
X155715Y124747D01*
X155447Y125006D01*
X155140Y125109D01*
X154833Y125006D01*
X154565Y124747D01*
X154450Y124386D01*
X154527Y124024D01*
X154718Y123766D01*
X154948Y123662D01*
X155332D01*
X155677Y123507D01*
X155907Y123197D01*
X155983Y122836D01*
X155907Y122474D01*
X155715Y122216D01*
X155408Y122061D01*
X155140Y122009D01*
G01X166002Y140237D02*
X166157Y140007D01*
X166260Y139739D01*
Y139432D01*
X166105Y139087D01*
X165847Y138819D01*
X165537Y138627D01*
X165020Y138474D01*
X164555Y138436D01*
X164090Y138512D01*
X163780Y138627D01*
X163470Y138857D01*
X163263Y139126D01*
X163160Y139394D01*
Y139662D01*
X163263Y139931D01*
X163418Y140161D01*
X163625Y140352D01*
G01X163522Y141842D02*
X163263Y142111D01*
X163160Y142417D01*
X163263Y142724D01*
X163573Y142992D01*
X164038Y143184D01*
X164503Y143261D01*
X165072D01*
X165537Y143184D01*
X165950Y142992D01*
X166157Y142762D01*
X166260Y142494D01*
X166157Y142187D01*
X165950Y141957D01*
X165640Y141804D01*
X165227Y141727D01*
X164865Y141804D01*
X164503Y141996D01*
X164297Y142226D01*
X164245Y142494D01*
X164348Y142801D01*
X164607Y143031D01*
X165072Y143261D01*
G01X163780Y144751D02*
X163418Y144981D01*
X163212Y145287D01*
X163160Y145632D01*
X163212Y145939D01*
X163470Y146246D01*
X163780Y146437D01*
X164090Y146476D01*
X164452Y146399D01*
X164710Y146131D01*
X164813Y145862D01*
Y145517D01*
G01Y145862D02*
X164968Y146092D01*
X165227Y146284D01*
X165537Y146361D01*
X165847Y146284D01*
X166105Y146092D01*
X166260Y145747D01*
X166208Y145402D01*
X166002Y145057D01*
G01X165417Y133800D02*
Y136900D01*
X164458D01*
X164152Y136745D01*
X163960Y136538D01*
X163883Y136125D01*
X163960Y135712D01*
X164190Y135453D01*
X164458Y135298D01*
X165417D01*
G01X164458D02*
X163883Y133800D01*
G01X162278Y136383D02*
X162048Y136693D01*
X161780Y136848D01*
X161473Y136900D01*
X161090Y136797D01*
X160822Y136538D01*
X160745Y136228D01*
X160783Y135918D01*
X160937Y135660D01*
X161703Y135143D01*
X162048Y134782D01*
X162278Y134265D01*
X162355Y133800D01*
X160745D01*
G01X159102Y134162D02*
X158833Y133903D01*
X158527Y133800D01*
X158220Y133903D01*
X157952Y134213D01*
X157760Y134678D01*
X157683Y135143D01*
Y135712D01*
X157760Y136177D01*
X157952Y136590D01*
X158182Y136797D01*
X158450Y136900D01*
X158757Y136797D01*
X158987Y136590D01*
X159140Y136280D01*
X159217Y135867D01*
X159140Y135505D01*
X158948Y135143D01*
X158718Y134937D01*
X158450Y134885D01*
X158143Y134988D01*
X157913Y135247D01*
X157683Y135712D01*
G01X165517Y129900D02*
Y133000D01*
X164558D01*
X164252Y132845D01*
X164060Y132638D01*
X163983Y132225D01*
X164060Y131812D01*
X164290Y131553D01*
X164558Y131398D01*
X165517D01*
G01X164558D02*
X163983Y129900D01*
G01X162378Y132483D02*
X162148Y132793D01*
X161880Y132948D01*
X161573Y133000D01*
X161190Y132897D01*
X160922Y132638D01*
X160845Y132328D01*
X160883Y132018D01*
X161037Y131760D01*
X161803Y131243D01*
X162148Y130882D01*
X162378Y130365D01*
X162455Y129900D01*
X160845D01*
G01X158550D02*
X158282Y129952D01*
X157975Y130107D01*
X157783Y130365D01*
X157707Y130727D01*
X157783Y131088D01*
X158013Y131398D01*
X158358Y131553D01*
X158742D01*
X158972Y131657D01*
X159163Y131915D01*
X159240Y132277D01*
X159125Y132638D01*
X158857Y132897D01*
X158550Y133000D01*
X158243Y132897D01*
X157975Y132638D01*
X157860Y132277D01*
X157937Y131915D01*
X158128Y131657D01*
X158358Y131553D01*
X158742D01*
X159087Y131398D01*
X159317Y131088D01*
X159393Y130727D01*
X159317Y130365D01*
X159125Y130107D01*
X158818Y129952D01*
X158550Y129900D01*
G01X153700Y125901D02*
X156800D01*
Y126860D01*
X156645Y127166D01*
X156438Y127358D01*
X156025Y127435D01*
X155612Y127358D01*
X155353Y127128D01*
X155198Y126860D01*
Y125901D01*
G01Y126860D02*
X153700Y127435D01*
G01X154320Y128925D02*
X153958Y129155D01*
X153752Y129461D01*
X153700Y129806D01*
X153752Y130113D01*
X154010Y130420D01*
X154320Y130611D01*
X154630Y130650D01*
X154992Y130573D01*
X155250Y130305D01*
X155353Y130036D01*
Y129691D01*
G01Y130036D02*
X155508Y130266D01*
X155767Y130458D01*
X156077Y130535D01*
X156387Y130458D01*
X156645Y130266D01*
X156800Y129921D01*
X156748Y129576D01*
X156542Y129231D01*
G01X156800Y132868D02*
X156697Y132561D01*
X156438Y132331D01*
X156128Y132178D01*
X155715Y132063D01*
X155250Y132025D01*
X154785Y132063D01*
X154372Y132178D01*
X154062Y132331D01*
X153803Y132561D01*
X153700Y132868D01*
X153803Y133175D01*
X154062Y133405D01*
X154372Y133558D01*
X154785Y133673D01*
X155250Y133711D01*
X155715Y133673D01*
X156128Y133558D01*
X156438Y133405D01*
X156697Y133175D01*
X156800Y132868D01*
G01X166907Y154650D02*
X167137Y154805D01*
X167405Y154908D01*
X167712D01*
X168057Y154753D01*
X168325Y154495D01*
X168517Y154185D01*
X168670Y153668D01*
X168708Y153203D01*
X168632Y152738D01*
X168517Y152428D01*
X168287Y152118D01*
X168018Y151911D01*
X167750Y151808D01*
X167482D01*
X167213Y151911D01*
X166983Y152066D01*
X166792Y152273D01*
G01X164650Y151808D02*
X164382Y151860D01*
X164075Y152015D01*
X163883Y152273D01*
X163807Y152635D01*
X163883Y152996D01*
X164113Y153306D01*
X164458Y153461D01*
X164842D01*
X165072Y153565D01*
X165263Y153823D01*
X165340Y154185D01*
X165225Y154546D01*
X164957Y154805D01*
X164650Y154908D01*
X164343Y154805D01*
X164075Y154546D01*
X163960Y154185D01*
X164037Y153823D01*
X164228Y153565D01*
X164458Y153461D01*
X164842D01*
X165187Y153306D01*
X165417Y152996D01*
X165493Y152635D01*
X165417Y152273D01*
X165225Y152015D01*
X164918Y151860D01*
X164650Y151808D01*
G01X161550Y154908D02*
X161857Y154805D01*
X162087Y154546D01*
X162240Y154236D01*
X162355Y153823D01*
X162393Y153358D01*
X162355Y152893D01*
X162240Y152480D01*
X162087Y152170D01*
X161857Y151911D01*
X161550Y151808D01*
X161243Y151911D01*
X161013Y152170D01*
X160860Y152480D01*
X160745Y152893D01*
X160707Y153358D01*
X160745Y153823D01*
X160860Y154236D01*
X161013Y154546D01*
X161243Y154805D01*
X161550Y154908D01*
G01X157832Y144964D02*
X157987Y144734D01*
X158090Y144466D01*
Y144159D01*
X157935Y143814D01*
X157677Y143546D01*
X157367Y143354D01*
X156850Y143201D01*
X156385Y143163D01*
X155920Y143239D01*
X155610Y143354D01*
X155300Y143584D01*
X155093Y143853D01*
X154990Y144121D01*
Y144389D01*
X155093Y144658D01*
X155248Y144888D01*
X155455Y145079D01*
G01X155352Y146569D02*
X155093Y146838D01*
X154990Y147144D01*
X155093Y147451D01*
X155403Y147719D01*
X155868Y147911D01*
X156333Y147988D01*
X156902D01*
X157367Y147911D01*
X157780Y147719D01*
X157987Y147489D01*
X158090Y147221D01*
X157987Y146914D01*
X157780Y146684D01*
X157470Y146531D01*
X157057Y146454D01*
X156695Y146531D01*
X156333Y146723D01*
X156127Y146953D01*
X156075Y147221D01*
X156178Y147528D01*
X156437Y147758D01*
X156902Y147988D01*
G01X155455Y149478D02*
X155197Y149708D01*
X155042Y149976D01*
X154990Y150321D01*
X155093Y150666D01*
X155300Y150934D01*
X155662Y151126D01*
X156075Y151164D01*
X156488Y151088D01*
X156747Y150896D01*
X156953Y150628D01*
X157005Y150359D01*
X156953Y150091D01*
X156747Y149746D01*
X158090Y149861D01*
Y150896D01*
G01X159807Y155364D02*
Y152264D01*
X158273D01*
G01X155940D02*
X155672Y152316D01*
X155365Y152471D01*
X155173Y152729D01*
X155097Y153091D01*
X155173Y153452D01*
X155403Y153762D01*
X155748Y153917D01*
X156132D01*
X156362Y154021D01*
X156553Y154279D01*
X156630Y154641D01*
X156515Y155002D01*
X156247Y155261D01*
X155940Y155364D01*
X155633Y155261D01*
X155365Y155002D01*
X155250Y154641D01*
X155327Y154279D01*
X155518Y154021D01*
X155748Y153917D01*
X156132D01*
X156477Y153762D01*
X156707Y153452D01*
X156783Y153091D01*
X156707Y152729D01*
X156515Y152471D01*
X156208Y152316D01*
X155940Y152264D01*
G01X154472Y169928D02*
X154627Y169698D01*
X154730Y169430D01*
Y169123D01*
X154575Y168778D01*
X154317Y168510D01*
X154007Y168318D01*
X153490Y168165D01*
X153025Y168127D01*
X152560Y168203D01*
X152250Y168318D01*
X151940Y168548D01*
X151733Y168817D01*
X151630Y169085D01*
Y169353D01*
X151733Y169622D01*
X151888Y169852D01*
X152095Y170043D01*
G01Y171342D02*
X151837Y171572D01*
X151682Y171840D01*
X151630Y172185D01*
X151733Y172530D01*
X151940Y172798D01*
X152302Y172990D01*
X152715Y173028D01*
X153128Y172952D01*
X153387Y172760D01*
X153593Y172492D01*
X153645Y172223D01*
X153593Y171955D01*
X153387Y171610D01*
X154730Y171725D01*
Y172760D01*
G01Y175285D02*
X154627Y174978D01*
X154368Y174748D01*
X154058Y174595D01*
X153645Y174480D01*
X153180Y174442D01*
X152715Y174480D01*
X152302Y174595D01*
X151992Y174748D01*
X151733Y174978D01*
X151630Y175285D01*
X151733Y175592D01*
X151992Y175822D01*
X152302Y175975D01*
X152715Y176090D01*
X153180Y176128D01*
X153645Y176090D01*
X154058Y175975D01*
X154368Y175822D01*
X154627Y175592D01*
X154730Y175285D01*
G01X162617Y162187D02*
X162847Y162342D01*
X163115Y162445D01*
X163422D01*
X163767Y162290D01*
X164035Y162032D01*
X164227Y161722D01*
X164380Y161205D01*
X164418Y160740D01*
X164342Y160275D01*
X164227Y159965D01*
X163997Y159655D01*
X163728Y159448D01*
X163460Y159345D01*
X163192D01*
X162923Y159448D01*
X162693Y159603D01*
X162502Y159810D01*
G01X160360Y159345D02*
Y162445D01*
X160820Y161825D01*
G01Y159345D02*
X159900D01*
G01X157988Y161928D02*
X157758Y162238D01*
X157490Y162393D01*
X157183Y162445D01*
X156800Y162342D01*
X156532Y162083D01*
X156455Y161773D01*
X156493Y161463D01*
X156647Y161205D01*
X157413Y160688D01*
X157758Y160327D01*
X157988Y159810D01*
X158065Y159345D01*
X156455D01*
G01X155003Y159810D02*
X154773Y159552D01*
X154505Y159397D01*
X154160Y159345D01*
X153815Y159448D01*
X153547Y159655D01*
X153355Y160017D01*
X153317Y160430D01*
X153393Y160843D01*
X153585Y161102D01*
X153853Y161308D01*
X154122Y161360D01*
X154390Y161308D01*
X154735Y161102D01*
X154620Y162445D01*
X153585D01*
G01X165083Y174512D02*
X165313Y174667D01*
X165581Y174770D01*
X165888D01*
X166233Y174615D01*
X166501Y174357D01*
X166693Y174047D01*
X166846Y173530D01*
X166884Y173065D01*
X166808Y172600D01*
X166693Y172290D01*
X166463Y171980D01*
X166194Y171773D01*
X165926Y171670D01*
X165658D01*
X165389Y171773D01*
X165159Y171928D01*
X164968Y172135D01*
G01X162826Y171670D02*
Y174770D01*
X163286Y174150D01*
G01Y171670D02*
X162366D01*
G01X160454Y174253D02*
X160224Y174563D01*
X159956Y174718D01*
X159649Y174770D01*
X159266Y174667D01*
X158998Y174408D01*
X158921Y174098D01*
X158959Y173788D01*
X159113Y173530D01*
X159879Y173013D01*
X160224Y172652D01*
X160454Y172135D01*
X160531Y171670D01*
X158921D01*
G01X157278Y172032D02*
X157009Y171773D01*
X156703Y171670D01*
X156396Y171773D01*
X156128Y172083D01*
X155936Y172548D01*
X155859Y173013D01*
Y173582D01*
X155936Y174047D01*
X156128Y174460D01*
X156358Y174667D01*
X156626Y174770D01*
X156933Y174667D01*
X157163Y174460D01*
X157316Y174150D01*
X157393Y173737D01*
X157316Y173375D01*
X157124Y173013D01*
X156894Y172807D01*
X156626Y172755D01*
X156319Y172858D01*
X156089Y173117D01*
X155859Y173582D01*
G01X164940Y170271D02*
X165170Y170426D01*
X165438Y170529D01*
X165745D01*
X166090Y170374D01*
X166358Y170116D01*
X166550Y169806D01*
X166703Y169289D01*
X166741Y168824D01*
X166665Y168359D01*
X166550Y168049D01*
X166320Y167739D01*
X166051Y167532D01*
X165783Y167429D01*
X165515D01*
X165246Y167532D01*
X165016Y167687D01*
X164825Y167894D01*
G01X162683Y167429D02*
Y170529D01*
X163143Y169909D01*
G01Y167429D02*
X162223D01*
G01X160311Y170012D02*
X160081Y170322D01*
X159813Y170477D01*
X159506Y170529D01*
X159123Y170426D01*
X158855Y170167D01*
X158778Y169857D01*
X158816Y169547D01*
X158970Y169289D01*
X159736Y168772D01*
X160081Y168411D01*
X160311Y167894D01*
X160388Y167429D01*
X158778D01*
G01X156483D02*
Y170529D01*
X156943Y169909D01*
G01Y167429D02*
X156023D01*
G01X153572Y181330D02*
X153727Y181100D01*
X153830Y180832D01*
Y180525D01*
X153675Y180180D01*
X153417Y179912D01*
X153107Y179720D01*
X152590Y179567D01*
X152125Y179529D01*
X151660Y179605D01*
X151350Y179720D01*
X151040Y179950D01*
X150833Y180219D01*
X150730Y180487D01*
Y180755D01*
X150833Y181024D01*
X150988Y181254D01*
X151195Y181445D01*
G01X150730Y183587D02*
X153830D01*
X153210Y183127D01*
G01X150730D02*
Y184047D01*
G01X153830Y186687D02*
X153727Y186380D01*
X153468Y186150D01*
X153158Y185997D01*
X152745Y185882D01*
X152280Y185844D01*
X151815Y185882D01*
X151402Y185997D01*
X151092Y186150D01*
X150833Y186380D01*
X150730Y186687D01*
X150833Y186994D01*
X151092Y187224D01*
X151402Y187377D01*
X151815Y187492D01*
X152280Y187530D01*
X152745Y187492D01*
X153158Y187377D01*
X153468Y187224D01*
X153727Y186994D01*
X153830Y186687D01*
G01X151350Y188944D02*
X150988Y189174D01*
X150782Y189480D01*
X150730Y189825D01*
X150782Y190132D01*
X151040Y190439D01*
X151350Y190630D01*
X151660Y190669D01*
X152022Y190592D01*
X152280Y190324D01*
X152383Y190055D01*
Y189710D01*
G01Y190055D02*
X152538Y190285D01*
X152797Y190477D01*
X153107Y190554D01*
X153417Y190477D01*
X153675Y190285D01*
X153830Y189940D01*
X153778Y189595D01*
X153572Y189250D01*
G01X163867Y188088D02*
X164097Y188243D01*
X164365Y188346D01*
X164672D01*
X165017Y188191D01*
X165285Y187933D01*
X165477Y187623D01*
X165630Y187106D01*
X165668Y186641D01*
X165592Y186176D01*
X165477Y185866D01*
X165247Y185556D01*
X164978Y185349D01*
X164710Y185246D01*
X164442D01*
X164173Y185349D01*
X163943Y185504D01*
X163752Y185711D01*
G01X161610Y185246D02*
Y188346D01*
X162070Y187726D01*
G01Y185246D02*
X161150D01*
G01X158510Y188346D02*
X158817Y188243D01*
X159047Y187984D01*
X159200Y187674D01*
X159315Y187261D01*
X159353Y186796D01*
X159315Y186331D01*
X159200Y185918D01*
X159047Y185608D01*
X158817Y185349D01*
X158510Y185246D01*
X158203Y185349D01*
X157973Y185608D01*
X157820Y185918D01*
X157705Y186331D01*
X157667Y186796D01*
X157705Y187261D01*
X157820Y187674D01*
X157973Y187984D01*
X158203Y188243D01*
X158510Y188346D01*
G01X154950Y185246D02*
Y188346D01*
X156368Y186124D01*
X154452D01*
G01X160232Y178321D02*
X160387Y178091D01*
X160490Y177823D01*
Y177516D01*
X160335Y177171D01*
X160077Y176903D01*
X159767Y176711D01*
X159250Y176558D01*
X158785Y176520D01*
X158320Y176596D01*
X158010Y176711D01*
X157700Y176941D01*
X157493Y177210D01*
X157390Y177478D01*
Y177746D01*
X157493Y178015D01*
X157648Y178245D01*
X157855Y178436D01*
G01Y179735D02*
X157597Y179965D01*
X157442Y180233D01*
X157390Y180578D01*
X157493Y180923D01*
X157700Y181191D01*
X158062Y181383D01*
X158475Y181421D01*
X158888Y181345D01*
X159147Y181153D01*
X159353Y180885D01*
X159405Y180616D01*
X159353Y180348D01*
X159147Y180003D01*
X160490Y180118D01*
Y181153D01*
G01X157390Y183678D02*
X157442Y183946D01*
X157597Y184253D01*
X157855Y184445D01*
X158217Y184521D01*
X158578Y184445D01*
X158888Y184215D01*
X159043Y183870D01*
Y183486D01*
X159147Y183256D01*
X159405Y183065D01*
X159767Y182988D01*
X160128Y183103D01*
X160387Y183371D01*
X160490Y183678D01*
X160387Y183985D01*
X160128Y184253D01*
X159767Y184368D01*
X159405Y184291D01*
X159147Y184100D01*
X159043Y183870D01*
Y183486D01*
X158888Y183141D01*
X158578Y182911D01*
X158217Y182835D01*
X157855Y182911D01*
X157597Y183103D01*
X157442Y183410D01*
X157390Y183678D01*
G01X165540Y202896D02*
X165770Y203051D01*
X166038Y203154D01*
X166345D01*
X166690Y202999D01*
X166958Y202741D01*
X167150Y202431D01*
X167303Y201914D01*
X167341Y201449D01*
X167265Y200984D01*
X167150Y200674D01*
X166920Y200364D01*
X166651Y200157D01*
X166383Y200054D01*
X166115D01*
X165846Y200157D01*
X165616Y200312D01*
X165425Y200519D01*
G01X164126D02*
X163896Y200261D01*
X163628Y200106D01*
X163283Y200054D01*
X162938Y200157D01*
X162670Y200364D01*
X162478Y200726D01*
X162440Y201139D01*
X162516Y201552D01*
X162708Y201811D01*
X162976Y202017D01*
X163245Y202069D01*
X163513Y202017D01*
X163858Y201811D01*
X163743Y203154D01*
X162708D01*
G01X160260Y200054D02*
X160183Y200726D01*
X160068Y201294D01*
X159915Y201811D01*
X159723Y202379D01*
X159416Y203154D01*
X160950D01*
G01X165497Y198572D02*
X165727Y198727D01*
X165995Y198830D01*
X166302D01*
X166647Y198675D01*
X166915Y198417D01*
X167107Y198107D01*
X167260Y197590D01*
X167298Y197125D01*
X167222Y196660D01*
X167107Y196350D01*
X166877Y196040D01*
X166608Y195833D01*
X166340Y195730D01*
X166072D01*
X165803Y195833D01*
X165573Y195988D01*
X165382Y196195D01*
G01X162780Y195730D02*
Y198830D01*
X164198Y196608D01*
X162282D01*
G01X160140Y195730D02*
X159872Y195782D01*
X159565Y195937D01*
X159373Y196195D01*
X159297Y196557D01*
X159373Y196918D01*
X159603Y197228D01*
X159948Y197383D01*
X160332D01*
X160562Y197487D01*
X160753Y197745D01*
X160830Y198107D01*
X160715Y198468D01*
X160447Y198727D01*
X160140Y198830D01*
X159833Y198727D01*
X159565Y198468D01*
X159450Y198107D01*
X159527Y197745D01*
X159718Y197487D01*
X159948Y197383D01*
X160332D01*
X160677Y197228D01*
X160907Y196918D01*
X160983Y196557D01*
X160907Y196195D01*
X160715Y195937D01*
X160408Y195782D01*
X160140Y195730D01*
G01X163617Y192829D02*
X163847Y192984D01*
X164115Y193087D01*
X164422D01*
X164767Y192932D01*
X165035Y192674D01*
X165227Y192364D01*
X165380Y191847D01*
X165418Y191382D01*
X165342Y190917D01*
X165227Y190607D01*
X164997Y190297D01*
X164728Y190090D01*
X164460Y189987D01*
X164192D01*
X163923Y190090D01*
X163693Y190245D01*
X163502Y190452D01*
G01X160900Y189987D02*
Y193087D01*
X162318Y190865D01*
X160402D01*
G01X158912Y190349D02*
X158643Y190090D01*
X158337Y189987D01*
X158030Y190090D01*
X157762Y190400D01*
X157570Y190865D01*
X157493Y191330D01*
Y191899D01*
X157570Y192364D01*
X157762Y192777D01*
X157992Y192984D01*
X158260Y193087D01*
X158567Y192984D01*
X158797Y192777D01*
X158950Y192467D01*
X159027Y192054D01*
X158950Y191692D01*
X158758Y191330D01*
X158528Y191124D01*
X158260Y191072D01*
X157953Y191175D01*
X157723Y191434D01*
X157493Y191899D01*
G01X164341Y267780D02*
X164571Y267935D01*
X164839Y268038D01*
X165146D01*
X165491Y267883D01*
X165759Y267625D01*
X165951Y267315D01*
X166104Y266798D01*
X166142Y266333D01*
X166066Y265868D01*
X165951Y265558D01*
X165721Y265248D01*
X165452Y265041D01*
X165184Y264938D01*
X164916D01*
X164647Y265041D01*
X164417Y265196D01*
X164226Y265403D01*
G01X162084Y264938D02*
Y268038D01*
X162544Y267418D01*
G01Y264938D02*
X161624D01*
G01X159827Y265403D02*
X159597Y265145D01*
X159329Y264990D01*
X158984Y264938D01*
X158639Y265041D01*
X158371Y265248D01*
X158179Y265610D01*
X158141Y266023D01*
X158217Y266436D01*
X158409Y266695D01*
X158677Y266901D01*
X158946Y266953D01*
X159214Y266901D01*
X159559Y266695D01*
X159444Y268038D01*
X158409D01*
G01X154018Y268987D02*
Y265987D01*
G01X150918Y265887D02*
X157118D01*
G01D02*
Y269087D01*
G01X150918D02*
Y265887D01*
G01X164387Y273352D02*
X164617Y273507D01*
X164885Y273610D01*
X165192D01*
X165537Y273455D01*
X165805Y273197D01*
X165997Y272887D01*
X166150Y272370D01*
X166188Y271905D01*
X166112Y271440D01*
X165997Y271130D01*
X165767Y270820D01*
X165498Y270613D01*
X165230Y270510D01*
X164962D01*
X164693Y270613D01*
X164463Y270768D01*
X164272Y270975D01*
G01X162130Y270510D02*
Y273610D01*
X162590Y272990D01*
G01Y270510D02*
X161670D01*
G01X159758Y271802D02*
X159490Y272163D01*
X159260Y272370D01*
X158953Y272473D01*
X158685Y272370D01*
X158493Y272163D01*
X158340Y271853D01*
X158302Y271492D01*
X158340Y271182D01*
X158493Y270872D01*
X158723Y270613D01*
X158992Y270510D01*
X159298Y270613D01*
X159567Y270923D01*
X159720Y271388D01*
X159758Y271905D01*
X159682Y272577D01*
X159567Y272938D01*
X159375Y273300D01*
X159107Y273558D01*
X158838Y273610D01*
X158570Y273507D01*
X158378Y273248D01*
G01X154018Y272987D02*
Y269987D01*
G01X150918Y269887D02*
X157118D01*
G01D02*
Y273087D01*
G01D02*
X150918D01*
G01D02*
Y269887D01*
G01X157118Y269087D02*
X150918D01*
G01X163510Y277740D02*
Y280840D01*
X162551D01*
X162245Y280685D01*
X162053Y280478D01*
X161976Y280065D01*
X162053Y279652D01*
X162283Y279393D01*
X162551Y279238D01*
X163510D01*
G01X162551D02*
X161976Y277740D01*
G01X160486Y278360D02*
X160256Y277998D01*
X159950Y277792D01*
X159605Y277740D01*
X159298Y277792D01*
X158991Y278050D01*
X158800Y278360D01*
X158761Y278670D01*
X158838Y279032D01*
X159106Y279290D01*
X159375Y279393D01*
X159720D01*
G01X159375D02*
X159145Y279548D01*
X158953Y279807D01*
X158876Y280117D01*
X158953Y280427D01*
X159145Y280685D01*
X159490Y280840D01*
X159835Y280788D01*
X160180Y280582D01*
G01X156620Y277740D02*
X156543Y278412D01*
X156428Y278980D01*
X156275Y279497D01*
X156083Y280065D01*
X155776Y280840D01*
X157310D01*
G01X163375Y281576D02*
Y284676D01*
X162416D01*
X162110Y284521D01*
X161918Y284314D01*
X161841Y283901D01*
X161918Y283488D01*
X162148Y283229D01*
X162416Y283074D01*
X163375D01*
G01X162416D02*
X161841Y281576D01*
G01X160351Y282196D02*
X160121Y281834D01*
X159815Y281628D01*
X159470Y281576D01*
X159163Y281628D01*
X158856Y281886D01*
X158665Y282196D01*
X158626Y282506D01*
X158703Y282868D01*
X158971Y283126D01*
X159240Y283229D01*
X159585D01*
G01X159240D02*
X159010Y283384D01*
X158818Y283643D01*
X158741Y283953D01*
X158818Y284263D01*
X159010Y284521D01*
X159355Y284676D01*
X159700Y284624D01*
X160045Y284418D01*
G01X156408Y281576D02*
X156140Y281628D01*
X155833Y281783D01*
X155641Y282041D01*
X155565Y282403D01*
X155641Y282764D01*
X155871Y283074D01*
X156216Y283229D01*
X156600D01*
X156830Y283333D01*
X157021Y283591D01*
X157098Y283953D01*
X156983Y284314D01*
X156715Y284573D01*
X156408Y284676D01*
X156101Y284573D01*
X155833Y284314D01*
X155718Y283953D01*
X155795Y283591D01*
X155986Y283333D01*
X156216Y283229D01*
X156600D01*
X156945Y283074D01*
X157175Y282764D01*
X157251Y282403D01*
X157175Y282041D01*
X156983Y281783D01*
X156676Y281628D01*
X156408Y281576D01*
G01X152831Y297262D02*
X152986Y297032D01*
X153089Y296764D01*
Y296457D01*
X152934Y296112D01*
X152676Y295844D01*
X152366Y295652D01*
X151849Y295499D01*
X151384Y295461D01*
X150919Y295537D01*
X150609Y295652D01*
X150299Y295882D01*
X150092Y296151D01*
X149989Y296419D01*
Y296687D01*
X150092Y296956D01*
X150247Y297186D01*
X150454Y297377D01*
G01X150609Y298676D02*
X150247Y298906D01*
X150041Y299212D01*
X149989Y299557D01*
X150041Y299864D01*
X150299Y300171D01*
X150609Y300362D01*
X150919Y300401D01*
X151281Y300324D01*
X151539Y300056D01*
X151642Y299787D01*
Y299442D01*
G01Y299787D02*
X151797Y300017D01*
X152056Y300209D01*
X152366Y300286D01*
X152676Y300209D01*
X152934Y300017D01*
X153089Y299672D01*
X153037Y299327D01*
X152831Y298982D01*
G01X151281Y301891D02*
X151642Y302159D01*
X151849Y302389D01*
X151952Y302696D01*
X151849Y302964D01*
X151642Y303156D01*
X151332Y303309D01*
X150971Y303347D01*
X150661Y303309D01*
X150351Y303156D01*
X150092Y302926D01*
X149989Y302657D01*
X150092Y302351D01*
X150402Y302082D01*
X150867Y301929D01*
X151384Y301891D01*
X152056Y301967D01*
X152417Y302082D01*
X152779Y302274D01*
X153037Y302542D01*
X153089Y302811D01*
X152986Y303079D01*
X152727Y303271D01*
G01X158551Y295010D02*
Y305210D01*
G01X153951D02*
Y295010D01*
G01D02*
X158551D01*
G01X163997Y305499D02*
Y295299D01*
G01D02*
X168597D01*
G01X158551Y305210D02*
X153951D01*
G01X158551Y300110D02*
X153951D01*
G01X168597Y305499D02*
X163997D01*
G01X168597Y300399D02*
X163997D01*
G01X159834Y355131D02*
X159989Y354901D01*
X160092Y354633D01*
Y354326D01*
X159937Y353981D01*
X159679Y353713D01*
X159369Y353521D01*
X158852Y353368D01*
X158387Y353330D01*
X157922Y353406D01*
X157612Y353521D01*
X157302Y353751D01*
X157095Y354020D01*
X156992Y354288D01*
Y354556D01*
X157095Y354825D01*
X157250Y355055D01*
X157457Y355246D01*
G01X157612Y356545D02*
X157250Y356775D01*
X157044Y357081D01*
X156992Y357426D01*
X157044Y357733D01*
X157302Y358040D01*
X157612Y358231D01*
X157922Y358270D01*
X158284Y358193D01*
X158542Y357925D01*
X158645Y357656D01*
Y357311D01*
G01Y357656D02*
X158800Y357886D01*
X159059Y358078D01*
X159369Y358155D01*
X159679Y358078D01*
X159937Y357886D01*
X160092Y357541D01*
X160040Y357196D01*
X159834Y356851D01*
G01X156992Y360488D02*
X160092D01*
X159472Y360028D01*
G01X156992D02*
Y360948D01*
G01X161182Y353521D02*
X164282D01*
Y354480D01*
X164127Y354786D01*
X163920Y354978D01*
X163507Y355055D01*
X163094Y354978D01*
X162835Y354748D01*
X162680Y354480D01*
Y353521D01*
G01Y354480D02*
X161182Y355055D01*
G01Y357388D02*
X164282D01*
X163662Y356928D01*
G01X161182D02*
Y357848D01*
G01X161802Y359645D02*
X161440Y359875D01*
X161234Y360181D01*
X161182Y360526D01*
X161234Y360833D01*
X161492Y361140D01*
X161802Y361331D01*
X162112Y361370D01*
X162474Y361293D01*
X162732Y361025D01*
X162835Y360756D01*
Y360411D01*
G01Y360756D02*
X162990Y360986D01*
X163249Y361178D01*
X163559Y361255D01*
X163869Y361178D01*
X164127Y360986D01*
X164282Y360641D01*
X164230Y360296D01*
X164024Y359951D01*
G01X163765Y362860D02*
X164075Y363090D01*
X164230Y363358D01*
X164282Y363665D01*
X164179Y364048D01*
X163920Y364316D01*
X163610Y364393D01*
X163300Y364355D01*
X163042Y364201D01*
X162525Y363435D01*
X162164Y363090D01*
X161647Y362860D01*
X161182Y362783D01*
Y364393D01*
G01X152756Y353521D02*
X155856D01*
Y354480D01*
X155701Y354786D01*
X155494Y354978D01*
X155081Y355055D01*
X154668Y354978D01*
X154409Y354748D01*
X154254Y354480D01*
Y353521D01*
G01Y354480D02*
X152756Y355055D01*
G01Y357388D02*
X155856D01*
X155236Y356928D01*
G01X152756D02*
Y357848D01*
G01X155339Y359760D02*
X155649Y359990D01*
X155804Y360258D01*
X155856Y360565D01*
X155753Y360948D01*
X155494Y361216D01*
X155184Y361293D01*
X154874Y361255D01*
X154616Y361101D01*
X154099Y360335D01*
X153738Y359990D01*
X153221Y359760D01*
X152756Y359683D01*
Y361293D01*
G01Y363588D02*
X152808Y363856D01*
X152963Y364163D01*
X153221Y364355D01*
X153583Y364431D01*
X153944Y364355D01*
X154254Y364125D01*
X154409Y363780D01*
Y363396D01*
X154513Y363166D01*
X154771Y362975D01*
X155133Y362898D01*
X155494Y363013D01*
X155753Y363281D01*
X155856Y363588D01*
X155753Y363895D01*
X155494Y364163D01*
X155133Y364278D01*
X154771Y364201D01*
X154513Y364010D01*
X154409Y363780D01*
Y363396D01*
X154254Y363051D01*
X153944Y362821D01*
X153583Y362745D01*
X153221Y362821D01*
X152963Y363013D01*
X152808Y363320D01*
X152756Y363588D01*
G01X150558Y371655D02*
X153558D01*
G01X153658Y374755D02*
X150458D01*
G01X153658Y368555D02*
Y374755D01*
G01X150458D02*
Y368555D01*
G01D02*
X153658D01*
G01X161658D02*
Y374755D01*
G01X158558Y371655D02*
X161558D01*
G01X161658Y374755D02*
X158458D01*
G01D02*
Y368555D01*
G01D02*
X161658D01*
G01X149658D02*
Y374755D01*
G01X157658D02*
X154458D01*
G01D02*
Y368555D01*
G01D02*
X157658D01*
G01D02*
Y374755D01*
G01X165658D02*
X162458D01*
G01D02*
Y368555D01*
G01D02*
X165658D01*
G01X149599Y379057D02*
Y385257D01*
G01X154777Y386373D02*
X157877D01*
Y387332D01*
X157722Y387638D01*
X157515Y387830D01*
X157102Y387907D01*
X156689Y387830D01*
X156430Y387600D01*
X156275Y387332D01*
Y386373D01*
G01Y387332D02*
X154777Y387907D01*
G01Y390240D02*
X157877D01*
X157257Y389780D01*
G01X154777D02*
Y390700D01*
G01X155397Y392497D02*
X155035Y392727D01*
X154829Y393033D01*
X154777Y393378D01*
X154829Y393685D01*
X155087Y393992D01*
X155397Y394183D01*
X155707Y394222D01*
X156069Y394145D01*
X156327Y393877D01*
X156430Y393608D01*
Y393263D01*
G01Y393608D02*
X156585Y393838D01*
X156844Y394030D01*
X157154Y394107D01*
X157464Y394030D01*
X157722Y393838D01*
X157877Y393493D01*
X157825Y393148D01*
X157619Y392803D01*
G01X154777Y396440D02*
X157877D01*
X157257Y395980D01*
G01X154777D02*
Y396900D01*
G01X157704Y379058D02*
Y385258D01*
G01D02*
X154504D01*
G01D02*
Y379058D01*
G01D02*
X157704D01*
G01X162260Y386557D02*
X165360D01*
Y387516D01*
X165205Y387822D01*
X164998Y388014D01*
X164585Y388091D01*
X164172Y388014D01*
X163913Y387784D01*
X163758Y387516D01*
Y386557D01*
G01Y387516D02*
X162260Y388091D01*
G01Y390424D02*
X165360D01*
X164740Y389964D01*
G01X162260D02*
Y390884D01*
G01X164843Y392796D02*
X165153Y393026D01*
X165308Y393294D01*
X165360Y393601D01*
X165257Y393984D01*
X164998Y394252D01*
X164688Y394329D01*
X164378Y394291D01*
X164120Y394137D01*
X163603Y393371D01*
X163242Y393026D01*
X162725Y392796D01*
X162260Y392719D01*
Y394329D01*
G01X164843Y395896D02*
X165153Y396126D01*
X165308Y396394D01*
X165360Y396701D01*
X165257Y397084D01*
X164998Y397352D01*
X164688Y397429D01*
X164378Y397391D01*
X164120Y397237D01*
X163603Y396471D01*
X163242Y396126D01*
X162725Y395896D01*
X162260Y395819D01*
Y397429D01*
G01X165335Y384969D02*
X162135D01*
G01D02*
Y378769D01*
G01D02*
X165335D01*
G01X154571Y418361D02*
X154726Y418131D01*
X154829Y417863D01*
Y417556D01*
X154674Y417211D01*
X154416Y416943D01*
X154106Y416751D01*
X153589Y416598D01*
X153124Y416560D01*
X152659Y416636D01*
X152349Y416751D01*
X152039Y416981D01*
X151832Y417250D01*
X151729Y417518D01*
Y417786D01*
X151832Y418055D01*
X151987Y418285D01*
X152194Y418476D01*
G01X151729Y420618D02*
X151781Y420886D01*
X151936Y421193D01*
X152194Y421385D01*
X152556Y421461D01*
X152917Y421385D01*
X153227Y421155D01*
X153382Y420810D01*
Y420426D01*
X153486Y420196D01*
X153744Y420005D01*
X154106Y419928D01*
X154467Y420043D01*
X154726Y420311D01*
X154829Y420618D01*
X154726Y420925D01*
X154467Y421193D01*
X154106Y421308D01*
X153744Y421231D01*
X153486Y421040D01*
X153382Y420810D01*
Y420426D01*
X153227Y420081D01*
X152917Y419851D01*
X152556Y419775D01*
X152194Y419851D01*
X151936Y420043D01*
X151781Y420350D01*
X151729Y420618D01*
G01X154312Y422990D02*
X154622Y423220D01*
X154777Y423488D01*
X154829Y423795D01*
X154726Y424178D01*
X154467Y424446D01*
X154157Y424523D01*
X153847Y424485D01*
X153589Y424331D01*
X153072Y423565D01*
X152711Y423220D01*
X152194Y422990D01*
X151729Y422913D01*
Y424523D01*
G01X154312Y426090D02*
X154622Y426320D01*
X154777Y426588D01*
X154829Y426895D01*
X154726Y427278D01*
X154467Y427546D01*
X154157Y427623D01*
X153847Y427585D01*
X153589Y427431D01*
X153072Y426665D01*
X152711Y426320D01*
X152194Y426090D01*
X151729Y426013D01*
Y427623D01*
G01X149209Y508353D02*
X152209D01*
G01X149109Y505253D02*
X152309D01*
G01X149109Y511453D02*
Y505253D01*
G01X152309Y511453D02*
X149109D01*
G01X152309Y505253D02*
Y511453D01*
G01X151082Y522253D02*
Y528453D01*
G01X151217Y539350D02*
Y542550D01*
G01X151317Y535408D02*
Y538608D01*
G01X151309Y548753D02*
Y551953D01*
G01Y543253D02*
Y546453D01*
G01X153809Y556753D02*
Y553753D01*
G01X150709Y556853D02*
Y553653D01*
G01X156909Y556853D02*
X150709D01*
G01X156909Y553653D02*
Y556853D01*
G01X150709Y553653D02*
X156909D01*
G01X153109Y567153D02*
Y562553D01*
G01D02*
X163309D01*
G01X158209D02*
Y567153D01*
G01X163309Y562553D02*
Y567153D01*
G01D02*
X153109D01*
G01X152410Y579413D02*
Y582613D01*
G01Y571505D02*
Y574705D01*
G01Y575505D02*
Y578705D01*
G01X149230Y599635D02*
Y596635D01*
G01X152330Y596535D02*
Y599735D01*
G01X149263Y595637D02*
Y592637D01*
G01X152363Y592537D02*
Y595737D01*
G01X164930Y594535D02*
X161730D01*
G01D02*
Y588335D01*
G01D02*
X164930D01*
G01X164830Y591435D02*
X161830D01*
G01X155863Y598533D02*
Y595333D01*
G01D02*
X162063D01*
G01D02*
Y598533D01*
G01X158963Y595433D02*
Y598433D01*
G01X153230Y586635D02*
X159430D01*
G01D02*
Y589835D01*
G01D02*
X153230D01*
G01D02*
Y586635D01*
G01X156330Y589735D02*
Y586735D01*
G01X149328Y612202D02*
Y609202D01*
G01X152428Y609102D02*
Y612302D01*
G01X155863Y612533D02*
Y609333D01*
G01D02*
X162063D01*
G01D02*
Y612533D01*
G01X158963Y609433D02*
Y612433D01*
G01X162030Y606735D02*
X155830D01*
G01D02*
Y603535D01*
G01D02*
X162030D01*
G01D02*
Y606735D01*
G01X158930Y603635D02*
Y606635D01*
G01X162063Y602533D02*
X155863D01*
G01D02*
Y599333D01*
G01D02*
X162063D01*
G01D02*
Y602533D01*
G01X158963Y599433D02*
Y602433D01*
G01X162063Y598533D02*
X155863D01*
G01X149328Y620535D02*
Y617535D01*
G01X152428Y617435D02*
Y620635D01*
G01X149328Y616235D02*
Y613235D01*
G01X152428Y613135D02*
Y616335D01*
G01X162663Y626633D02*
X165663D01*
G01X162563Y629733D02*
Y623533D01*
G01D02*
X165763D01*
G01X162063Y622533D02*
X155863D01*
G01D02*
Y619333D01*
G01D02*
X162063D01*
G01D02*
Y622533D01*
G01X158963Y619433D02*
Y622433D01*
G01X162130Y618335D02*
X155930D01*
G01D02*
Y615135D01*
G01D02*
X162130D01*
G01D02*
Y618335D01*
G01X159030Y615235D02*
Y618235D01*
G01X162063Y612533D02*
X155863D01*
G01X165763Y629733D02*
X162563D01*
G01X155483Y656483D02*
X155638Y656253D01*
X155741Y655985D01*
Y655678D01*
X155586Y655333D01*
X155328Y655065D01*
X155018Y654873D01*
X154501Y654720D01*
X154036Y654682D01*
X153571Y654758D01*
X153261Y654873D01*
X152951Y655103D01*
X152744Y655372D01*
X152641Y655640D01*
Y655908D01*
X152744Y656177D01*
X152899Y656407D01*
X153106Y656598D01*
G01X152641Y659200D02*
X155741D01*
X153519Y657782D01*
Y659698D01*
G01X155224Y661112D02*
X155534Y661342D01*
X155689Y661610D01*
X155741Y661917D01*
X155638Y662300D01*
X155379Y662568D01*
X155069Y662645D01*
X154759Y662607D01*
X154501Y662453D01*
X153984Y661687D01*
X153623Y661342D01*
X153106Y661112D01*
X152641Y661035D01*
Y662645D01*
G01Y664940D02*
X155741D01*
X155121Y664480D01*
G01X152641D02*
Y665400D01*
G01X154855Y704252D02*
X155010Y704022D01*
X155113Y703754D01*
Y703447D01*
X154958Y703102D01*
X154700Y702834D01*
X154390Y702642D01*
X153873Y702489D01*
X153408Y702451D01*
X152943Y702527D01*
X152633Y702642D01*
X152323Y702872D01*
X152116Y703141D01*
X152013Y703409D01*
Y703677D01*
X152116Y703946D01*
X152271Y704176D01*
X152478Y704367D01*
G01X153305Y705781D02*
X153666Y706049D01*
X153873Y706279D01*
X153976Y706586D01*
X153873Y706854D01*
X153666Y707046D01*
X153356Y707199D01*
X152995Y707237D01*
X152685Y707199D01*
X152375Y707046D01*
X152116Y706816D01*
X152013Y706547D01*
X152116Y706241D01*
X152426Y705972D01*
X152891Y705819D01*
X153408Y705781D01*
X154080Y705857D01*
X154441Y705972D01*
X154803Y706164D01*
X155061Y706432D01*
X155113Y706701D01*
X155010Y706969D01*
X154751Y707161D01*
G01X155113Y709609D02*
X155010Y709302D01*
X154751Y709072D01*
X154441Y708919D01*
X154028Y708804D01*
X153563Y708766D01*
X153098Y708804D01*
X152685Y708919D01*
X152375Y709072D01*
X152116Y709302D01*
X152013Y709609D01*
X152116Y709916D01*
X152375Y710146D01*
X152685Y710299D01*
X153098Y710414D01*
X153563Y710452D01*
X154028Y710414D01*
X154441Y710299D01*
X154751Y710146D01*
X155010Y709916D01*
X155113Y709609D01*
G01X152375Y712057D02*
X152116Y712326D01*
X152013Y712632D01*
X152116Y712939D01*
X152426Y713207D01*
X152891Y713399D01*
X153356Y713476D01*
X153925D01*
X154390Y713399D01*
X154803Y713207D01*
X155010Y712977D01*
X155113Y712709D01*
X155010Y712402D01*
X154803Y712172D01*
X154493Y712019D01*
X154080Y711942D01*
X153718Y712019D01*
X153356Y712211D01*
X153150Y712441D01*
X153098Y712709D01*
X153201Y713016D01*
X153460Y713246D01*
X153925Y713476D01*
G01X167159Y704252D02*
X167314Y704022D01*
X167417Y703754D01*
Y703447D01*
X167262Y703102D01*
X167004Y702834D01*
X166694Y702642D01*
X166177Y702489D01*
X165712Y702451D01*
X165247Y702527D01*
X164937Y702642D01*
X164627Y702872D01*
X164420Y703141D01*
X164317Y703409D01*
Y703677D01*
X164420Y703946D01*
X164575Y704176D01*
X164782Y704367D01*
G01X165609Y705781D02*
X165970Y706049D01*
X166177Y706279D01*
X166280Y706586D01*
X166177Y706854D01*
X165970Y707046D01*
X165660Y707199D01*
X165299Y707237D01*
X164989Y707199D01*
X164679Y707046D01*
X164420Y706816D01*
X164317Y706547D01*
X164420Y706241D01*
X164730Y705972D01*
X165195Y705819D01*
X165712Y705781D01*
X166384Y705857D01*
X166745Y705972D01*
X167107Y706164D01*
X167365Y706432D01*
X167417Y706701D01*
X167314Y706969D01*
X167055Y707161D01*
G01X167417Y709609D02*
X167314Y709302D01*
X167055Y709072D01*
X166745Y708919D01*
X166332Y708804D01*
X165867Y708766D01*
X165402Y708804D01*
X164989Y708919D01*
X164679Y709072D01*
X164420Y709302D01*
X164317Y709609D01*
X164420Y709916D01*
X164679Y710146D01*
X164989Y710299D01*
X165402Y710414D01*
X165867Y710452D01*
X166332Y710414D01*
X166745Y710299D01*
X167055Y710146D01*
X167314Y709916D01*
X167417Y709609D01*
G01X164317Y712709D02*
X167417D01*
X166797Y712249D01*
G01X164317D02*
Y713169D01*
G01X163119Y704252D02*
X163274Y704022D01*
X163377Y703754D01*
Y703447D01*
X163222Y703102D01*
X162964Y702834D01*
X162654Y702642D01*
X162137Y702489D01*
X161672Y702451D01*
X161207Y702527D01*
X160897Y702642D01*
X160587Y702872D01*
X160380Y703141D01*
X160277Y703409D01*
Y703677D01*
X160380Y703946D01*
X160535Y704176D01*
X160742Y704367D01*
G01X161569Y705781D02*
X161930Y706049D01*
X162137Y706279D01*
X162240Y706586D01*
X162137Y706854D01*
X161930Y707046D01*
X161620Y707199D01*
X161259Y707237D01*
X160949Y707199D01*
X160639Y707046D01*
X160380Y706816D01*
X160277Y706547D01*
X160380Y706241D01*
X160690Y705972D01*
X161155Y705819D01*
X161672Y705781D01*
X162344Y705857D01*
X162705Y705972D01*
X163067Y706164D01*
X163325Y706432D01*
X163377Y706701D01*
X163274Y706969D01*
X163015Y707161D01*
G01X163377Y709609D02*
X163274Y709302D01*
X163015Y709072D01*
X162705Y708919D01*
X162292Y708804D01*
X161827Y708766D01*
X161362Y708804D01*
X160949Y708919D01*
X160639Y709072D01*
X160380Y709302D01*
X160277Y709609D01*
X160380Y709916D01*
X160639Y710146D01*
X160949Y710299D01*
X161362Y710414D01*
X161827Y710452D01*
X162292Y710414D01*
X162705Y710299D01*
X163015Y710146D01*
X163274Y709916D01*
X163377Y709609D01*
G01X160897Y711866D02*
X160535Y712096D01*
X160329Y712402D01*
X160277Y712747D01*
X160329Y713054D01*
X160587Y713361D01*
X160897Y713552D01*
X161207Y713591D01*
X161569Y713514D01*
X161827Y713246D01*
X161930Y712977D01*
Y712632D01*
G01Y712977D02*
X162085Y713207D01*
X162344Y713399D01*
X162654Y713476D01*
X162964Y713399D01*
X163222Y713207D01*
X163377Y712862D01*
X163325Y712517D01*
X163119Y712172D01*
G01X158988Y704252D02*
X159143Y704022D01*
X159246Y703754D01*
Y703447D01*
X159091Y703102D01*
X158833Y702834D01*
X158523Y702642D01*
X158006Y702489D01*
X157541Y702451D01*
X157076Y702527D01*
X156766Y702642D01*
X156456Y702872D01*
X156249Y703141D01*
X156146Y703409D01*
Y703677D01*
X156249Y703946D01*
X156404Y704176D01*
X156611Y704367D01*
G01X157438Y705781D02*
X157799Y706049D01*
X158006Y706279D01*
X158109Y706586D01*
X158006Y706854D01*
X157799Y707046D01*
X157489Y707199D01*
X157128Y707237D01*
X156818Y707199D01*
X156508Y707046D01*
X156249Y706816D01*
X156146Y706547D01*
X156249Y706241D01*
X156559Y705972D01*
X157024Y705819D01*
X157541Y705781D01*
X158213Y705857D01*
X158574Y705972D01*
X158936Y706164D01*
X159194Y706432D01*
X159246Y706701D01*
X159143Y706969D01*
X158884Y707161D01*
G01X159246Y709609D02*
X159143Y709302D01*
X158884Y709072D01*
X158574Y708919D01*
X158161Y708804D01*
X157696Y708766D01*
X157231Y708804D01*
X156818Y708919D01*
X156508Y709072D01*
X156249Y709302D01*
X156146Y709609D01*
X156249Y709916D01*
X156508Y710146D01*
X156818Y710299D01*
X157231Y710414D01*
X157696Y710452D01*
X158161Y710414D01*
X158574Y710299D01*
X158884Y710146D01*
X159143Y709916D01*
X159246Y709609D01*
G01X157438Y711981D02*
X157799Y712249D01*
X158006Y712479D01*
X158109Y712786D01*
X158006Y713054D01*
X157799Y713246D01*
X157489Y713399D01*
X157128Y713437D01*
X156818Y713399D01*
X156508Y713246D01*
X156249Y713016D01*
X156146Y712747D01*
X156249Y712441D01*
X156559Y712172D01*
X157024Y712019D01*
X157541Y711981D01*
X158213Y712057D01*
X158574Y712172D01*
X158936Y712364D01*
X159194Y712632D01*
X159246Y712901D01*
X159143Y713169D01*
X158884Y713361D01*
G01X185227Y111618D02*
Y114718D01*
X184268D01*
X183962Y114563D01*
X183770Y114356D01*
X183693Y113943D01*
X183770Y113530D01*
X184000Y113271D01*
X184268Y113116D01*
X185227D01*
G01X184268D02*
X183693Y111618D01*
G01X182088Y114201D02*
X181858Y114511D01*
X181590Y114666D01*
X181283Y114718D01*
X180900Y114615D01*
X180632Y114356D01*
X180555Y114046D01*
X180593Y113736D01*
X180747Y113478D01*
X181513Y112961D01*
X181858Y112600D01*
X182088Y112083D01*
X182165Y111618D01*
X180555D01*
G01X178260D02*
Y114718D01*
X178720Y114098D01*
G01Y111618D02*
X177800D01*
G01X175160D02*
Y114718D01*
X175620Y114098D01*
G01Y111618D02*
X174700D01*
G01X172332Y137602D02*
X172487Y137372D01*
X172590Y137104D01*
Y136797D01*
X172435Y136452D01*
X172177Y136184D01*
X171867Y135992D01*
X171350Y135839D01*
X170885Y135801D01*
X170420Y135877D01*
X170110Y135992D01*
X169800Y136222D01*
X169593Y136491D01*
X169490Y136759D01*
Y137027D01*
X169593Y137296D01*
X169748Y137526D01*
X169955Y137717D01*
G01X169852Y139207D02*
X169593Y139476D01*
X169490Y139782D01*
X169593Y140089D01*
X169903Y140357D01*
X170368Y140549D01*
X170833Y140626D01*
X171402D01*
X171867Y140549D01*
X172280Y140357D01*
X172487Y140127D01*
X172590Y139859D01*
X172487Y139552D01*
X172280Y139322D01*
X171970Y139169D01*
X171557Y139092D01*
X171195Y139169D01*
X170833Y139361D01*
X170627Y139591D01*
X170575Y139859D01*
X170678Y140166D01*
X170937Y140396D01*
X171402Y140626D01*
G01X169490Y143419D02*
X172590D01*
X170368Y142001D01*
Y143917D01*
G01X173520Y129354D02*
X176620D01*
Y130313D01*
X176465Y130619D01*
X176258Y130811D01*
X175845Y130888D01*
X175432Y130811D01*
X175173Y130581D01*
X175018Y130313D01*
Y129354D01*
G01Y130313D02*
X173520Y130888D01*
G01Y133221D02*
X176620D01*
X176000Y132761D01*
G01X173520D02*
Y133681D01*
G01X176620Y136321D02*
X176517Y136014D01*
X176258Y135784D01*
X175948Y135631D01*
X175535Y135516D01*
X175070Y135478D01*
X174605Y135516D01*
X174192Y135631D01*
X173882Y135784D01*
X173623Y136014D01*
X173520Y136321D01*
X173623Y136628D01*
X173882Y136858D01*
X174192Y137011D01*
X174605Y137126D01*
X175070Y137164D01*
X175535Y137126D01*
X175948Y137011D01*
X176258Y136858D01*
X176517Y136628D01*
X176620Y136321D01*
G01X173520Y139881D02*
X176620D01*
X174398Y138463D01*
Y140379D01*
G01X173520Y142981D02*
X176620D01*
X174398Y141563D01*
Y143479D01*
G01X179082Y155146D02*
X179237Y154916D01*
X179340Y154648D01*
Y154341D01*
X179185Y153996D01*
X178927Y153728D01*
X178617Y153536D01*
X178100Y153383D01*
X177635Y153345D01*
X177170Y153421D01*
X176860Y153536D01*
X176550Y153766D01*
X176343Y154035D01*
X176240Y154303D01*
Y154571D01*
X176343Y154840D01*
X176498Y155070D01*
X176705Y155261D01*
G01X176240Y157403D02*
X179340D01*
X178720Y156943D01*
G01X176240D02*
Y157863D01*
G01X178823Y159775D02*
X179133Y160005D01*
X179288Y160273D01*
X179340Y160580D01*
X179237Y160963D01*
X178978Y161231D01*
X178668Y161308D01*
X178358Y161270D01*
X178100Y161116D01*
X177583Y160350D01*
X177222Y160005D01*
X176705Y159775D01*
X176240Y159698D01*
Y161308D01*
G01Y163603D02*
X176292Y163871D01*
X176447Y164178D01*
X176705Y164370D01*
X177067Y164446D01*
X177428Y164370D01*
X177738Y164140D01*
X177893Y163795D01*
Y163411D01*
X177997Y163181D01*
X178255Y162990D01*
X178617Y162913D01*
X178978Y163028D01*
X179237Y163296D01*
X179340Y163603D01*
X179237Y163910D01*
X178978Y164178D01*
X178617Y164293D01*
X178255Y164216D01*
X177997Y164025D01*
X177893Y163795D01*
Y163411D01*
X177738Y163066D01*
X177428Y162836D01*
X177067Y162760D01*
X176705Y162836D01*
X176447Y163028D01*
X176292Y163335D01*
X176240Y163603D01*
G01X172362Y157220D02*
X172517Y156990D01*
X172620Y156722D01*
Y156415D01*
X172465Y156070D01*
X172207Y155802D01*
X171897Y155610D01*
X171380Y155457D01*
X170915Y155419D01*
X170450Y155495D01*
X170140Y155610D01*
X169830Y155840D01*
X169623Y156109D01*
X169520Y156377D01*
Y156645D01*
X169623Y156914D01*
X169778Y157144D01*
X169985Y157335D01*
G01X169520Y159937D02*
X172620D01*
X170398Y158519D01*
Y160435D01*
G01X170140Y161734D02*
X169778Y161964D01*
X169572Y162270D01*
X169520Y162615D01*
X169572Y162922D01*
X169830Y163229D01*
X170140Y163420D01*
X170450Y163459D01*
X170812Y163382D01*
X171070Y163114D01*
X171173Y162845D01*
Y162500D01*
G01Y162845D02*
X171328Y163075D01*
X171587Y163267D01*
X171897Y163344D01*
X172207Y163267D01*
X172465Y163075D01*
X172620Y162730D01*
X172568Y162385D01*
X172362Y162040D01*
G01X170030Y144669D02*
X173130D01*
Y145589D01*
X172975Y145896D01*
X172613Y146126D01*
X172200Y146203D01*
X171787Y146126D01*
X171477Y145934D01*
X171322Y145589D01*
Y144669D01*
G01X170650Y147769D02*
X170340Y147961D01*
X170133Y148191D01*
X170030Y148459D01*
X170133Y148766D01*
X170340Y148996D01*
X170650Y149226D01*
X171063Y149303D01*
X173130D01*
G01X170030Y151559D02*
X170702Y151636D01*
X171270Y151751D01*
X171787Y151904D01*
X172355Y152096D01*
X173130Y152403D01*
Y150869D01*
G01X174360Y144506D02*
X177460D01*
Y145426D01*
X177305Y145733D01*
X176943Y145963D01*
X176530Y146040D01*
X176117Y145963D01*
X175807Y145771D01*
X175652Y145426D01*
Y144506D01*
G01X174980Y147606D02*
X174670Y147798D01*
X174463Y148028D01*
X174360Y148296D01*
X174463Y148603D01*
X174670Y148833D01*
X174980Y149063D01*
X175393Y149140D01*
X177460D01*
G01X174360Y151473D02*
X174412Y151741D01*
X174567Y152048D01*
X174825Y152240D01*
X175187Y152316D01*
X175548Y152240D01*
X175858Y152010D01*
X176013Y151665D01*
Y151281D01*
X176117Y151051D01*
X176375Y150860D01*
X176737Y150783D01*
X177098Y150898D01*
X177357Y151166D01*
X177460Y151473D01*
X177357Y151780D01*
X177098Y152048D01*
X176737Y152163D01*
X176375Y152086D01*
X176117Y151895D01*
X176013Y151665D01*
Y151281D01*
X175858Y150936D01*
X175548Y150706D01*
X175187Y150630D01*
X174825Y150706D01*
X174567Y150898D01*
X174412Y151205D01*
X174360Y151473D01*
G01X179472Y166894D02*
X179627Y166664D01*
X179730Y166396D01*
Y166089D01*
X179575Y165744D01*
X179317Y165476D01*
X179007Y165284D01*
X178490Y165131D01*
X178025Y165093D01*
X177560Y165169D01*
X177250Y165284D01*
X176940Y165514D01*
X176733Y165783D01*
X176630Y166051D01*
Y166319D01*
X176733Y166588D01*
X176888Y166818D01*
X177095Y167009D01*
G01X176630Y169151D02*
X179730D01*
X179110Y168691D01*
G01X176630D02*
Y169611D01*
G01X179213Y171523D02*
X179523Y171753D01*
X179678Y172021D01*
X179730Y172328D01*
X179627Y172711D01*
X179368Y172979D01*
X179058Y173056D01*
X178748Y173018D01*
X178490Y172864D01*
X177973Y172098D01*
X177612Y171753D01*
X177095Y171523D01*
X176630Y171446D01*
Y173056D01*
G01Y175274D02*
X177302Y175351D01*
X177870Y175466D01*
X178387Y175619D01*
X178955Y175811D01*
X179730Y176118D01*
Y174584D01*
G01X172242Y165930D02*
X172397Y165700D01*
X172500Y165432D01*
Y165125D01*
X172345Y164780D01*
X172087Y164512D01*
X171777Y164320D01*
X171260Y164167D01*
X170795Y164129D01*
X170330Y164205D01*
X170020Y164320D01*
X169710Y164550D01*
X169503Y164819D01*
X169400Y165087D01*
Y165355D01*
X169503Y165624D01*
X169658Y165854D01*
X169865Y166045D01*
G01X169400Y168187D02*
X172500D01*
X171880Y167727D01*
G01X169400D02*
Y168647D01*
G01X171983Y170559D02*
X172293Y170789D01*
X172448Y171057D01*
X172500Y171364D01*
X172397Y171747D01*
X172138Y172015D01*
X171828Y172092D01*
X171518Y172054D01*
X171260Y171900D01*
X170743Y171134D01*
X170382Y170789D01*
X169865Y170559D01*
X169400Y170482D01*
Y172092D01*
G01X170020Y173544D02*
X169658Y173774D01*
X169452Y174080D01*
X169400Y174425D01*
X169452Y174732D01*
X169710Y175039D01*
X170020Y175230D01*
X170330Y175269D01*
X170692Y175192D01*
X170950Y174924D01*
X171053Y174655D01*
Y174310D01*
G01Y174655D02*
X171208Y174885D01*
X171467Y175077D01*
X171777Y175154D01*
X172087Y175077D01*
X172345Y174885D01*
X172500Y174540D01*
X172448Y174195D01*
X172242Y173850D01*
G01X168330Y158078D02*
X165230D01*
Y159612D01*
G01Y161868D02*
X165902Y161945D01*
X166470Y162060D01*
X166987Y162213D01*
X167555Y162405D01*
X168330Y162712D01*
Y161178D01*
G01X172172Y186684D02*
X172327Y186454D01*
X172430Y186186D01*
Y185879D01*
X172275Y185534D01*
X172017Y185266D01*
X171707Y185074D01*
X171190Y184921D01*
X170725Y184883D01*
X170260Y184959D01*
X169950Y185074D01*
X169640Y185304D01*
X169433Y185573D01*
X169330Y185841D01*
Y186109D01*
X169433Y186378D01*
X169588Y186608D01*
X169795Y186799D01*
G01X169330Y189401D02*
X172430D01*
X170208Y187983D01*
Y189899D01*
G01X169330Y192501D02*
X172430D01*
X170208Y191083D01*
Y192999D01*
G01X172172Y177849D02*
X172327Y177619D01*
X172430Y177351D01*
Y177044D01*
X172275Y176699D01*
X172017Y176431D01*
X171707Y176239D01*
X171190Y176086D01*
X170725Y176048D01*
X170260Y176124D01*
X169950Y176239D01*
X169640Y176469D01*
X169433Y176738D01*
X169330Y177006D01*
Y177274D01*
X169433Y177543D01*
X169588Y177773D01*
X169795Y177964D01*
G01X169330Y180566D02*
X172430D01*
X170208Y179148D01*
Y181064D01*
G01X169795Y182363D02*
X169537Y182593D01*
X169382Y182861D01*
X169330Y183206D01*
X169433Y183551D01*
X169640Y183819D01*
X170002Y184011D01*
X170415Y184049D01*
X170828Y183973D01*
X171087Y183781D01*
X171293Y183513D01*
X171345Y183244D01*
X171293Y182976D01*
X171087Y182631D01*
X172430Y182746D01*
Y183781D01*
G01X179852Y188691D02*
X180007Y188461D01*
X180110Y188193D01*
Y187886D01*
X179955Y187541D01*
X179697Y187273D01*
X179387Y187081D01*
X178870Y186928D01*
X178405Y186890D01*
X177940Y186966D01*
X177630Y187081D01*
X177320Y187311D01*
X177113Y187580D01*
X177010Y187848D01*
Y188116D01*
X177113Y188385D01*
X177268Y188615D01*
X177475Y188806D01*
G01X177372Y190296D02*
X177113Y190565D01*
X177010Y190871D01*
X177113Y191178D01*
X177423Y191446D01*
X177888Y191638D01*
X178353Y191715D01*
X178922D01*
X179387Y191638D01*
X179800Y191446D01*
X180007Y191216D01*
X180110Y190948D01*
X180007Y190641D01*
X179800Y190411D01*
X179490Y190258D01*
X179077Y190181D01*
X178715Y190258D01*
X178353Y190450D01*
X178147Y190680D01*
X178095Y190948D01*
X178198Y191255D01*
X178457Y191485D01*
X178922Y191715D01*
G01X177010Y194048D02*
X177062Y194316D01*
X177217Y194623D01*
X177475Y194815D01*
X177837Y194891D01*
X178198Y194815D01*
X178508Y194585D01*
X178663Y194240D01*
Y193856D01*
X178767Y193626D01*
X179025Y193435D01*
X179387Y193358D01*
X179748Y193473D01*
X180007Y193741D01*
X180110Y194048D01*
X180007Y194355D01*
X179748Y194623D01*
X179387Y194738D01*
X179025Y194661D01*
X178767Y194470D01*
X178663Y194240D01*
Y193856D01*
X178508Y193511D01*
X178198Y193281D01*
X177837Y193205D01*
X177475Y193281D01*
X177217Y193473D01*
X177062Y193780D01*
X177010Y194048D01*
G01X176222Y180115D02*
X176377Y179885D01*
X176480Y179617D01*
Y179310D01*
X176325Y178965D01*
X176067Y178697D01*
X175757Y178505D01*
X175240Y178352D01*
X174775Y178314D01*
X174310Y178390D01*
X174000Y178505D01*
X173690Y178735D01*
X173483Y179004D01*
X173380Y179272D01*
Y179540D01*
X173483Y179809D01*
X173638Y180039D01*
X173845Y180230D01*
G01X173380Y182372D02*
X176480D01*
X175860Y181912D01*
G01X173380D02*
Y182832D01*
G01X176480Y185472D02*
X176377Y185165D01*
X176118Y184935D01*
X175808Y184782D01*
X175395Y184667D01*
X174930Y184629D01*
X174465Y184667D01*
X174052Y184782D01*
X173742Y184935D01*
X173483Y185165D01*
X173380Y185472D01*
X173483Y185779D01*
X173742Y186009D01*
X174052Y186162D01*
X174465Y186277D01*
X174930Y186315D01*
X175395Y186277D01*
X175808Y186162D01*
X176118Y186009D01*
X176377Y185779D01*
X176480Y185472D01*
G01X175963Y187844D02*
X176273Y188074D01*
X176428Y188342D01*
X176480Y188649D01*
X176377Y189032D01*
X176118Y189300D01*
X175808Y189377D01*
X175498Y189339D01*
X175240Y189185D01*
X174723Y188419D01*
X174362Y188074D01*
X173845Y187844D01*
X173380Y187767D01*
Y189377D01*
G01X180312Y178593D02*
X180467Y178363D01*
X180570Y178095D01*
Y177788D01*
X180415Y177443D01*
X180157Y177175D01*
X179847Y176983D01*
X179330Y176830D01*
X178865Y176792D01*
X178400Y176868D01*
X178090Y176983D01*
X177780Y177213D01*
X177573Y177482D01*
X177470Y177750D01*
Y178018D01*
X177573Y178287D01*
X177728Y178517D01*
X177935Y178708D01*
G01Y180007D02*
X177677Y180237D01*
X177522Y180505D01*
X177470Y180850D01*
X177573Y181195D01*
X177780Y181463D01*
X178142Y181655D01*
X178555Y181693D01*
X178968Y181617D01*
X179227Y181425D01*
X179433Y181157D01*
X179485Y180888D01*
X179433Y180620D01*
X179227Y180275D01*
X180570Y180390D01*
Y181425D01*
G01X180053Y183222D02*
X180363Y183452D01*
X180518Y183720D01*
X180570Y184027D01*
X180467Y184410D01*
X180208Y184678D01*
X179898Y184755D01*
X179588Y184717D01*
X179330Y184563D01*
X178813Y183797D01*
X178452Y183452D01*
X177935Y183222D01*
X177470Y183145D01*
Y184755D01*
G01X174537Y196268D02*
X174767Y196423D01*
X175035Y196526D01*
X175342D01*
X175687Y196371D01*
X175955Y196113D01*
X176147Y195803D01*
X176300Y195286D01*
X176338Y194821D01*
X176262Y194356D01*
X176147Y194046D01*
X175917Y193736D01*
X175648Y193529D01*
X175380Y193426D01*
X175112D01*
X174843Y193529D01*
X174613Y193684D01*
X174422Y193891D01*
G01X171820Y193426D02*
Y196526D01*
X173238Y194304D01*
X171322D01*
G01X169908Y194718D02*
X169640Y195079D01*
X169410Y195286D01*
X169103Y195389D01*
X168835Y195286D01*
X168643Y195079D01*
X168490Y194769D01*
X168452Y194408D01*
X168490Y194098D01*
X168643Y193788D01*
X168873Y193529D01*
X169142Y193426D01*
X169448Y193529D01*
X169717Y193839D01*
X169870Y194304D01*
X169908Y194821D01*
X169832Y195493D01*
X169717Y195854D01*
X169525Y196216D01*
X169257Y196474D01*
X168988Y196526D01*
X168720Y196423D01*
X168528Y196164D01*
G01X181467Y204096D02*
X181697Y204251D01*
X181965Y204354D01*
X182272D01*
X182617Y204199D01*
X182885Y203941D01*
X183077Y203631D01*
X183230Y203114D01*
X183268Y202649D01*
X183192Y202184D01*
X183077Y201874D01*
X182847Y201564D01*
X182578Y201357D01*
X182310Y201254D01*
X182042D01*
X181773Y201357D01*
X181543Y201512D01*
X181352Y201719D01*
G01X178750Y201254D02*
Y204354D01*
X180168Y202132D01*
X178252D01*
G01X176110Y204354D02*
X176417Y204251D01*
X176647Y203992D01*
X176800Y203682D01*
X176915Y203269D01*
X176953Y202804D01*
X176915Y202339D01*
X176800Y201926D01*
X176647Y201616D01*
X176417Y201357D01*
X176110Y201254D01*
X175803Y201357D01*
X175573Y201616D01*
X175420Y201926D01*
X175305Y202339D01*
X175267Y202804D01*
X175305Y203269D01*
X175420Y203682D01*
X175573Y203992D01*
X175803Y204251D01*
X176110Y204354D01*
G01X181077Y200263D02*
X181307Y200418D01*
X181575Y200521D01*
X181882D01*
X182227Y200366D01*
X182495Y200108D01*
X182687Y199798D01*
X182840Y199281D01*
X182878Y198816D01*
X182802Y198351D01*
X182687Y198041D01*
X182457Y197731D01*
X182188Y197524D01*
X181920Y197421D01*
X181652D01*
X181383Y197524D01*
X181153Y197679D01*
X180962Y197886D01*
G01X178360Y197421D02*
Y200521D01*
X179778Y198299D01*
X177862D01*
G01X175720Y197421D02*
Y200521D01*
X176180Y199901D01*
G01Y197421D02*
X175260D01*
G01X172218Y230842D02*
X172373Y230612D01*
X172476Y230344D01*
Y230037D01*
X172321Y229692D01*
X172063Y229424D01*
X171753Y229232D01*
X171236Y229079D01*
X170771Y229041D01*
X170306Y229117D01*
X169996Y229232D01*
X169686Y229462D01*
X169479Y229731D01*
X169376Y229999D01*
Y230267D01*
X169479Y230536D01*
X169634Y230766D01*
X169841Y230957D01*
G01X171959Y232371D02*
X172269Y232601D01*
X172424Y232869D01*
X172476Y233176D01*
X172373Y233559D01*
X172114Y233827D01*
X171804Y233904D01*
X171494Y233866D01*
X171236Y233712D01*
X170719Y232946D01*
X170358Y232601D01*
X169841Y232371D01*
X169376Y232294D01*
Y233904D01*
G01Y236199D02*
X172476D01*
X171856Y235739D01*
G01X169376D02*
Y236659D01*
G01X168218Y230842D02*
X168373Y230612D01*
X168476Y230344D01*
Y230037D01*
X168321Y229692D01*
X168063Y229424D01*
X167753Y229232D01*
X167236Y229079D01*
X166771Y229041D01*
X166306Y229117D01*
X165996Y229232D01*
X165686Y229462D01*
X165479Y229731D01*
X165376Y229999D01*
Y230267D01*
X165479Y230536D01*
X165634Y230766D01*
X165841Y230957D01*
G01X167959Y232371D02*
X168269Y232601D01*
X168424Y232869D01*
X168476Y233176D01*
X168373Y233559D01*
X168114Y233827D01*
X167804Y233904D01*
X167494Y233866D01*
X167236Y233712D01*
X166719Y232946D01*
X166358Y232601D01*
X165841Y232371D01*
X165376Y232294D01*
Y233904D01*
G01X167959Y235471D02*
X168269Y235701D01*
X168424Y235969D01*
X168476Y236276D01*
X168373Y236659D01*
X168114Y236927D01*
X167804Y237004D01*
X167494Y236966D01*
X167236Y236812D01*
X166719Y236046D01*
X166358Y235701D01*
X165841Y235471D01*
X165376Y235394D01*
Y237004D01*
G01X178127Y237974D02*
X181127D01*
G01X181227Y241074D02*
X178027D01*
G01D02*
Y234874D01*
G01D02*
X181227D01*
G01X177227D02*
Y241074D01*
G01X174127Y237974D02*
X177127D01*
G01X177227Y241074D02*
X174027D01*
G01D02*
Y234874D01*
G01D02*
X177227D01*
G01X172376Y297078D02*
X172531Y296848D01*
X172634Y296580D01*
Y296273D01*
X172479Y295928D01*
X172221Y295660D01*
X171911Y295468D01*
X171394Y295315D01*
X170929Y295277D01*
X170464Y295353D01*
X170154Y295468D01*
X169844Y295698D01*
X169637Y295967D01*
X169534Y296235D01*
Y296503D01*
X169637Y296772D01*
X169792Y297002D01*
X169999Y297193D01*
G01X170154Y298492D02*
X169792Y298722D01*
X169586Y299028D01*
X169534Y299373D01*
X169586Y299680D01*
X169844Y299987D01*
X170154Y300178D01*
X170464Y300217D01*
X170826Y300140D01*
X171084Y299872D01*
X171187Y299603D01*
Y299258D01*
G01Y299603D02*
X171342Y299833D01*
X171601Y300025D01*
X171911Y300102D01*
X172221Y300025D01*
X172479Y299833D01*
X172634Y299488D01*
X172582Y299143D01*
X172376Y298798D01*
G01X169896Y301783D02*
X169637Y302052D01*
X169534Y302358D01*
X169637Y302665D01*
X169947Y302933D01*
X170412Y303125D01*
X170877Y303202D01*
X171446D01*
X171911Y303125D01*
X172324Y302933D01*
X172531Y302703D01*
X172634Y302435D01*
X172531Y302128D01*
X172324Y301898D01*
X172014Y301745D01*
X171601Y301668D01*
X171239Y301745D01*
X170877Y301937D01*
X170671Y302167D01*
X170619Y302435D01*
X170722Y302742D01*
X170981Y302972D01*
X171446Y303202D01*
G01X168597Y295299D02*
Y305499D01*
G01X164427Y283747D02*
X170627D01*
G01D02*
Y286947D01*
G01D02*
X164427D01*
G01D02*
Y283747D01*
G01Y287747D02*
X170627D01*
Y290947D01*
X164427D01*
Y287747D01*
G01X168167Y355131D02*
X168322Y354901D01*
X168425Y354633D01*
Y354326D01*
X168270Y353981D01*
X168012Y353713D01*
X167702Y353521D01*
X167185Y353368D01*
X166720Y353330D01*
X166255Y353406D01*
X165945Y353521D01*
X165635Y353751D01*
X165428Y354020D01*
X165325Y354288D01*
Y354556D01*
X165428Y354825D01*
X165583Y355055D01*
X165790Y355246D01*
G01X167908Y356660D02*
X168218Y356890D01*
X168373Y357158D01*
X168425Y357465D01*
X168322Y357848D01*
X168063Y358116D01*
X167753Y358193D01*
X167443Y358155D01*
X167185Y358001D01*
X166668Y357235D01*
X166307Y356890D01*
X165790Y356660D01*
X165325Y356583D01*
Y358193D01*
G01Y360411D02*
X165997Y360488D01*
X166565Y360603D01*
X167082Y360756D01*
X167650Y360948D01*
X168425Y361255D01*
Y359721D01*
G01X169608Y353521D02*
X172708D01*
Y354480D01*
X172553Y354786D01*
X172346Y354978D01*
X171933Y355055D01*
X171520Y354978D01*
X171261Y354748D01*
X171106Y354480D01*
Y353521D01*
G01Y354480D02*
X169608Y355055D01*
G01Y357388D02*
X172708D01*
X172088Y356928D01*
G01X169608D02*
Y357848D01*
G01X172191Y359760D02*
X172501Y359990D01*
X172656Y360258D01*
X172708Y360565D01*
X172605Y360948D01*
X172346Y361216D01*
X172036Y361293D01*
X171726Y361255D01*
X171468Y361101D01*
X170951Y360335D01*
X170590Y359990D01*
X170073Y359760D01*
X169608Y359683D01*
Y361293D01*
G01X170228Y362745D02*
X169866Y362975D01*
X169660Y363281D01*
X169608Y363626D01*
X169660Y363933D01*
X169918Y364240D01*
X170228Y364431D01*
X170538Y364470D01*
X170900Y364393D01*
X171158Y364125D01*
X171261Y363856D01*
Y363511D01*
G01Y363856D02*
X171416Y364086D01*
X171675Y364278D01*
X171985Y364355D01*
X172295Y364278D01*
X172553Y364086D01*
X172708Y363741D01*
X172656Y363396D01*
X172450Y363051D01*
G01X177658Y368555D02*
Y374755D01*
G01X174558Y371655D02*
X177558D01*
G01X177658Y374755D02*
X174458D01*
G01D02*
Y368555D01*
G01D02*
X177658D01*
G01X166558Y371655D02*
X169558D01*
G01X169658Y374755D02*
X166458D01*
G01X169658Y368555D02*
Y374755D01*
G01X166458D02*
Y368555D01*
G01D02*
X169658D01*
G01X165658D02*
Y374755D01*
G01X181658D02*
X178458D01*
G01D02*
Y368555D01*
G01D02*
X181658D01*
G01X173658Y374755D02*
X170458D01*
G01D02*
Y368555D01*
G01D02*
X173658D01*
G01D02*
Y374755D01*
G01X165335Y378769D02*
Y384969D01*
G01X181401Y385297D02*
X178201D01*
G01D02*
Y379097D01*
G01D02*
X181401D01*
G01X170670Y388357D02*
X173770D01*
Y389316D01*
X173615Y389622D01*
X173408Y389814D01*
X172995Y389891D01*
X172582Y389814D01*
X172323Y389584D01*
X172168Y389316D01*
Y388357D01*
G01Y389316D02*
X170670Y389891D01*
G01Y392224D02*
X173770D01*
X173150Y391764D01*
G01X170670D02*
Y392684D01*
G01X173253Y394596D02*
X173563Y394826D01*
X173718Y395094D01*
X173770Y395401D01*
X173667Y395784D01*
X173408Y396052D01*
X173098Y396129D01*
X172788Y396091D01*
X172530Y395937D01*
X172013Y395171D01*
X171652Y394826D01*
X171135Y394596D01*
X170670Y394519D01*
Y396129D01*
G01X171032Y397772D02*
X170773Y398041D01*
X170670Y398347D01*
X170773Y398654D01*
X171083Y398922D01*
X171548Y399114D01*
X172013Y399191D01*
X172582D01*
X173047Y399114D01*
X173460Y398922D01*
X173667Y398692D01*
X173770Y398424D01*
X173667Y398117D01*
X173460Y397887D01*
X173150Y397734D01*
X172737Y397657D01*
X172375Y397734D01*
X172013Y397926D01*
X171807Y398156D01*
X171755Y398424D01*
X171858Y398731D01*
X172117Y398961D01*
X172582Y399191D01*
G01X173534Y379202D02*
Y385402D01*
G01D02*
X170334D01*
G01D02*
Y379202D01*
G01D02*
X173534D01*
G01X179109Y521653D02*
Y518453D01*
G01X185309Y521653D02*
X179109D01*
G01Y518453D02*
X185309D01*
G01X177407Y535872D02*
X177637Y536027D01*
X177905Y536130D01*
X178212D01*
X178557Y535975D01*
X178825Y535717D01*
X179017Y535407D01*
X179170Y534890D01*
X179208Y534425D01*
X179132Y533960D01*
X179017Y533650D01*
X178787Y533340D01*
X178518Y533133D01*
X178250Y533030D01*
X177982D01*
X177713Y533133D01*
X177483Y533288D01*
X177292Y533495D01*
G01X175878Y535613D02*
X175648Y535923D01*
X175380Y536078D01*
X175073Y536130D01*
X174690Y536027D01*
X174422Y535768D01*
X174345Y535458D01*
X174383Y535148D01*
X174537Y534890D01*
X175303Y534373D01*
X175648Y534012D01*
X175878Y533495D01*
X175955Y533030D01*
X174345D01*
G01X172893Y533650D02*
X172663Y533288D01*
X172357Y533082D01*
X172012Y533030D01*
X171705Y533082D01*
X171398Y533340D01*
X171207Y533650D01*
X171168Y533960D01*
X171245Y534322D01*
X171513Y534580D01*
X171782Y534683D01*
X172127D01*
G01X171782D02*
X171552Y534838D01*
X171360Y535097D01*
X171283Y535407D01*
X171360Y535717D01*
X171552Y535975D01*
X171897Y536130D01*
X172242Y536078D01*
X172587Y535872D01*
G01X168950Y533030D02*
Y536130D01*
X169410Y535510D01*
G01Y533030D02*
X168490D01*
G01X176871Y522537D02*
X183071D01*
G01X176871Y525737D02*
Y522537D01*
G01X183071Y525737D02*
X176871D01*
G01X174379Y538147D02*
Y541147D01*
G01X171279Y538047D02*
X177479D01*
G01X171279Y541247D02*
Y538047D01*
G01X177479Y541247D02*
X171279D01*
G01X177479Y538047D02*
Y541247D01*
G01X164930Y588335D02*
Y594535D01*
G01X170930D02*
X167730D01*
G01D02*
Y588335D01*
G01D02*
X170930D01*
G01D02*
Y594535D01*
G01X170830Y591435D02*
X167830D01*
G01X177863Y594633D02*
X174663D01*
G01D02*
Y588433D01*
G01D02*
X177863D01*
G01D02*
Y594633D01*
G01X177763Y591533D02*
X174763D01*
G01X165763Y623533D02*
Y629733D01*
G01X175330Y626635D02*
X178330D01*
G01X178430Y623535D02*
Y629735D01*
G01X175230D02*
Y623535D01*
G01D02*
X178430D01*
G01X171030Y626635D02*
X174030D01*
G01X174130Y623535D02*
Y629735D01*
G01X170930D02*
Y623535D01*
G01D02*
X174130D01*
G01X166930Y626535D02*
X169930D01*
G01X166830Y629635D02*
Y623435D01*
G01X170030D02*
Y629635D01*
G01X166830Y623435D02*
X170030D01*
G01X178430Y629735D02*
X175230D01*
G01X174130D02*
X170930D01*
G01X170030Y629635D02*
X166830D01*
G01X188409Y709635D02*
X188639Y709790D01*
X188907Y709893D01*
X189214D01*
X189559Y709738D01*
X189827Y709480D01*
X190019Y709170D01*
X190172Y708653D01*
X190210Y708188D01*
X190134Y707723D01*
X190019Y707413D01*
X189789Y707103D01*
X189520Y706896D01*
X189252Y706793D01*
X188984D01*
X188715Y706896D01*
X188485Y707051D01*
X188294Y707258D01*
G01X186995D02*
X186765Y707000D01*
X186497Y706845D01*
X186152Y706793D01*
X185807Y706896D01*
X185539Y707103D01*
X185347Y707465D01*
X185309Y707878D01*
X185385Y708291D01*
X185577Y708550D01*
X185845Y708756D01*
X186114Y708808D01*
X186382Y708756D01*
X186727Y708550D01*
X186612Y709893D01*
X185577D01*
G01X183780Y708085D02*
X183512Y708446D01*
X183282Y708653D01*
X182975Y708756D01*
X182707Y708653D01*
X182515Y708446D01*
X182362Y708136D01*
X182324Y707775D01*
X182362Y707465D01*
X182515Y707155D01*
X182745Y706896D01*
X183014Y706793D01*
X183320Y706896D01*
X183589Y707206D01*
X183742Y707671D01*
X183780Y708188D01*
X183704Y708860D01*
X183589Y709221D01*
X183397Y709583D01*
X183129Y709841D01*
X182860Y709893D01*
X182592Y709790D01*
X182400Y709531D01*
G01X180604Y707155D02*
X180335Y706896D01*
X180029Y706793D01*
X179722Y706896D01*
X179454Y707206D01*
X179262Y707671D01*
X179185Y708136D01*
Y708705D01*
X179262Y709170D01*
X179454Y709583D01*
X179684Y709790D01*
X179952Y709893D01*
X180259Y709790D01*
X180489Y709583D01*
X180642Y709273D01*
X180719Y708860D01*
X180642Y708498D01*
X180450Y708136D01*
X180220Y707930D01*
X179952Y707878D01*
X179645Y707981D01*
X179415Y708240D01*
X179185Y708705D01*
G01X178093Y724942D02*
X181293D01*
G01X178093Y731142D02*
Y724942D01*
G01X181293Y731142D02*
X178093D01*
G01X178545Y745884D02*
X181645D01*
Y746843D01*
X181490Y747149D01*
X181283Y747341D01*
X180870Y747418D01*
X180457Y747341D01*
X180198Y747111D01*
X180043Y746843D01*
Y745884D01*
G01Y746843D02*
X178545Y747418D01*
G01Y749751D02*
X178597Y750019D01*
X178752Y750326D01*
X179010Y750518D01*
X179372Y750594D01*
X179733Y750518D01*
X180043Y750288D01*
X180198Y749943D01*
Y749559D01*
X180302Y749329D01*
X180560Y749138D01*
X180922Y749061D01*
X181283Y749176D01*
X181542Y749444D01*
X181645Y749751D01*
X181542Y750058D01*
X181283Y750326D01*
X180922Y750441D01*
X180560Y750364D01*
X180302Y750173D01*
X180198Y749943D01*
Y749559D01*
X180043Y749214D01*
X179733Y748984D01*
X179372Y748908D01*
X179010Y748984D01*
X178752Y749176D01*
X178597Y749483D01*
X178545Y749751D01*
G01X179165Y752008D02*
X178803Y752238D01*
X178597Y752544D01*
X178545Y752889D01*
X178597Y753196D01*
X178855Y753503D01*
X179165Y753694D01*
X179475Y753733D01*
X179837Y753656D01*
X180095Y753388D01*
X180198Y753119D01*
Y752774D01*
G01Y753119D02*
X180353Y753349D01*
X180612Y753541D01*
X180922Y753618D01*
X181232Y753541D01*
X181490Y753349D01*
X181645Y753004D01*
X181593Y752659D01*
X181387Y752314D01*
G01X179010Y755108D02*
X178752Y755338D01*
X178597Y755606D01*
X178545Y755951D01*
X178648Y756296D01*
X178855Y756564D01*
X179217Y756756D01*
X179630Y756794D01*
X180043Y756718D01*
X180302Y756526D01*
X180508Y756258D01*
X180560Y755989D01*
X180508Y755721D01*
X180302Y755376D01*
X181645Y755491D01*
Y756526D01*
G01X188473Y114577D02*
Y111377D01*
G01D02*
X194673D01*
G01D02*
Y114577D01*
G01D02*
X188473D01*
G01X186200Y123530D02*
X189300D01*
Y124489D01*
X189145Y124795D01*
X188938Y124987D01*
X188525Y125064D01*
X188112Y124987D01*
X187853Y124757D01*
X187698Y124489D01*
Y123530D01*
G01Y124489D02*
X186200Y125064D01*
G01Y127397D02*
X189300D01*
X188680Y126937D01*
G01X186200D02*
Y127857D01*
G01X189300Y130497D02*
X189197Y130190D01*
X188938Y129960D01*
X188628Y129807D01*
X188215Y129692D01*
X187750Y129654D01*
X187285Y129692D01*
X186872Y129807D01*
X186562Y129960D01*
X186303Y130190D01*
X186200Y130497D01*
X186303Y130804D01*
X186562Y131034D01*
X186872Y131187D01*
X187285Y131302D01*
X187750Y131340D01*
X188215Y131302D01*
X188628Y131187D01*
X188938Y131034D01*
X189197Y130804D01*
X189300Y130497D01*
G01X186200Y134057D02*
X189300D01*
X187078Y132639D01*
Y134555D01*
G01X189300Y136697D02*
X189197Y136390D01*
X188938Y136160D01*
X188628Y136007D01*
X188215Y135892D01*
X187750Y135854D01*
X187285Y135892D01*
X186872Y136007D01*
X186562Y136160D01*
X186303Y136390D01*
X186200Y136697D01*
X186303Y137004D01*
X186562Y137234D01*
X186872Y137387D01*
X187285Y137502D01*
X187750Y137540D01*
X188215Y137502D01*
X188628Y137387D01*
X188938Y137234D01*
X189197Y137004D01*
X189300Y136697D01*
G01X193842Y140295D02*
X193997Y140065D01*
X194100Y139797D01*
Y139490D01*
X193945Y139145D01*
X193687Y138877D01*
X193377Y138685D01*
X192860Y138532D01*
X192395Y138494D01*
X191930Y138570D01*
X191620Y138685D01*
X191310Y138915D01*
X191103Y139184D01*
X191000Y139452D01*
Y139720D01*
X191103Y139989D01*
X191258Y140219D01*
X191465Y140410D01*
G01X191000Y142552D02*
X194100D01*
X193480Y142092D01*
G01X191000D02*
Y143012D01*
G01X191620Y144809D02*
X191258Y145039D01*
X191052Y145345D01*
X191000Y145690D01*
X191052Y145997D01*
X191310Y146304D01*
X191620Y146495D01*
X191930Y146534D01*
X192292Y146457D01*
X192550Y146189D01*
X192653Y145920D01*
Y145575D01*
G01Y145920D02*
X192808Y146150D01*
X193067Y146342D01*
X193377Y146419D01*
X193687Y146342D01*
X193945Y146150D01*
X194100Y145805D01*
X194048Y145460D01*
X193842Y145115D01*
G01X193583Y148024D02*
X193893Y148254D01*
X194048Y148522D01*
X194100Y148829D01*
X193997Y149212D01*
X193738Y149480D01*
X193428Y149557D01*
X193118Y149519D01*
X192860Y149365D01*
X192343Y148599D01*
X191982Y148254D01*
X191465Y148024D01*
X191000Y147947D01*
Y149557D01*
G01X189752Y140361D02*
X189907Y140131D01*
X190010Y139863D01*
Y139556D01*
X189855Y139211D01*
X189597Y138943D01*
X189287Y138751D01*
X188770Y138598D01*
X188305Y138560D01*
X187840Y138636D01*
X187530Y138751D01*
X187220Y138981D01*
X187013Y139250D01*
X186910Y139518D01*
Y139786D01*
X187013Y140055D01*
X187168Y140285D01*
X187375Y140476D01*
G01X186910Y142618D02*
X190010D01*
X189390Y142158D01*
G01X186910D02*
Y143078D01*
G01X187530Y144875D02*
X187168Y145105D01*
X186962Y145411D01*
X186910Y145756D01*
X186962Y146063D01*
X187220Y146370D01*
X187530Y146561D01*
X187840Y146600D01*
X188202Y146523D01*
X188460Y146255D01*
X188563Y145986D01*
Y145641D01*
G01Y145986D02*
X188718Y146216D01*
X188977Y146408D01*
X189287Y146485D01*
X189597Y146408D01*
X189855Y146216D01*
X190010Y145871D01*
X189958Y145526D01*
X189752Y145181D01*
G01X186910Y148818D02*
X190010D01*
X189390Y148358D01*
G01X186910D02*
Y149278D01*
G01X196452Y126425D02*
X196607Y126195D01*
X196710Y125927D01*
Y125620D01*
X196555Y125275D01*
X196297Y125007D01*
X195987Y124815D01*
X195470Y124662D01*
X195005Y124624D01*
X194540Y124700D01*
X194230Y124815D01*
X193920Y125045D01*
X193713Y125314D01*
X193610Y125582D01*
Y125850D01*
X193713Y126119D01*
X193868Y126349D01*
X194075Y126540D01*
G01X193610Y128682D02*
X196710D01*
X196090Y128222D01*
G01X193610D02*
Y129142D01*
G01Y131782D02*
X196710D01*
X196090Y131322D01*
G01X193610D02*
Y132242D01*
G01X193972Y134230D02*
X193713Y134499D01*
X193610Y134805D01*
X193713Y135112D01*
X194023Y135380D01*
X194488Y135572D01*
X194953Y135649D01*
X195522D01*
X195987Y135572D01*
X196400Y135380D01*
X196607Y135150D01*
X196710Y134882D01*
X196607Y134575D01*
X196400Y134345D01*
X196090Y134192D01*
X195677Y134115D01*
X195315Y134192D01*
X194953Y134384D01*
X194747Y134614D01*
X194695Y134882D01*
X194798Y135189D01*
X195057Y135419D01*
X195522Y135649D01*
G01X197860Y137418D02*
X194760D01*
Y138952D01*
G01Y141285D02*
X197860D01*
X197240Y140825D01*
G01X194760D02*
Y141745D01*
G01X197860Y144385D02*
X197757Y144078D01*
X197498Y143848D01*
X197188Y143695D01*
X196775Y143580D01*
X196310Y143542D01*
X195845Y143580D01*
X195432Y143695D01*
X195122Y143848D01*
X194863Y144078D01*
X194760Y144385D01*
X194863Y144692D01*
X195122Y144922D01*
X195432Y145075D01*
X195845Y145190D01*
X196310Y145228D01*
X196775Y145190D01*
X197188Y145075D01*
X197498Y144922D01*
X197757Y144692D01*
X197860Y144385D01*
G01X198822Y151298D02*
X198977Y151068D01*
X199080Y150800D01*
Y150493D01*
X198925Y150148D01*
X198667Y149880D01*
X198357Y149688D01*
X197840Y149535D01*
X197375Y149497D01*
X196910Y149573D01*
X196600Y149688D01*
X196290Y149918D01*
X196083Y150187D01*
X195980Y150455D01*
Y150723D01*
X196083Y150992D01*
X196238Y151222D01*
X196445Y151413D01*
G01X197272Y152827D02*
X197633Y153095D01*
X197840Y153325D01*
X197943Y153632D01*
X197840Y153900D01*
X197633Y154092D01*
X197323Y154245D01*
X196962Y154283D01*
X196652Y154245D01*
X196342Y154092D01*
X196083Y153862D01*
X195980Y153593D01*
X196083Y153287D01*
X196393Y153018D01*
X196858Y152865D01*
X197375Y152827D01*
X198047Y152903D01*
X198408Y153018D01*
X198770Y153210D01*
X199028Y153478D01*
X199080Y153747D01*
X198977Y154015D01*
X198718Y154207D01*
G01X198563Y155927D02*
X198873Y156157D01*
X199028Y156425D01*
X199080Y156732D01*
X198977Y157115D01*
X198718Y157383D01*
X198408Y157460D01*
X198098Y157422D01*
X197840Y157268D01*
X197323Y156502D01*
X196962Y156157D01*
X196445Y155927D01*
X195980Y155850D01*
Y157460D01*
G01X185442Y151495D02*
X185597Y151265D01*
X185700Y150997D01*
Y150690D01*
X185545Y150345D01*
X185287Y150077D01*
X184977Y149885D01*
X184460Y149732D01*
X183995Y149694D01*
X183530Y149770D01*
X183220Y149885D01*
X182910Y150115D01*
X182703Y150384D01*
X182600Y150652D01*
Y150920D01*
X182703Y151189D01*
X182858Y151419D01*
X183065Y151610D01*
G01X182600Y153752D02*
X185700D01*
X185080Y153292D01*
G01X182600D02*
Y154212D01*
G01X185700Y156852D02*
X185597Y156545D01*
X185338Y156315D01*
X185028Y156162D01*
X184615Y156047D01*
X184150Y156009D01*
X183685Y156047D01*
X183272Y156162D01*
X182962Y156315D01*
X182703Y156545D01*
X182600Y156852D01*
X182703Y157159D01*
X182962Y157389D01*
X183272Y157542D01*
X183685Y157657D01*
X184150Y157695D01*
X184615Y157657D01*
X185028Y157542D01*
X185338Y157389D01*
X185597Y157159D01*
X185700Y156852D01*
G01X182600Y159875D02*
X183272Y159952D01*
X183840Y160067D01*
X184357Y160220D01*
X184925Y160412D01*
X185700Y160719D01*
Y159185D01*
G01X190252Y151341D02*
X190407Y151111D01*
X190510Y150843D01*
Y150536D01*
X190355Y150191D01*
X190097Y149923D01*
X189787Y149731D01*
X189270Y149578D01*
X188805Y149540D01*
X188340Y149616D01*
X188030Y149731D01*
X187720Y149961D01*
X187513Y150230D01*
X187410Y150498D01*
Y150766D01*
X187513Y151035D01*
X187668Y151265D01*
X187875Y151456D01*
G01X187410Y153598D02*
X190510D01*
X189890Y153138D01*
G01X187410D02*
Y154058D01*
G01X189993Y155970D02*
X190303Y156200D01*
X190458Y156468D01*
X190510Y156775D01*
X190407Y157158D01*
X190148Y157426D01*
X189838Y157503D01*
X189528Y157465D01*
X189270Y157311D01*
X188753Y156545D01*
X188392Y156200D01*
X187875Y155970D01*
X187410Y155893D01*
Y157503D01*
G01Y160258D02*
X190510D01*
X188288Y158840D01*
Y160756D01*
G01X194660Y150331D02*
X191560D01*
Y151865D01*
G01X192025Y153355D02*
X191767Y153585D01*
X191612Y153853D01*
X191560Y154198D01*
X191663Y154543D01*
X191870Y154811D01*
X192232Y155003D01*
X192645Y155041D01*
X193058Y154965D01*
X193317Y154773D01*
X193523Y154505D01*
X193575Y154236D01*
X193523Y153968D01*
X193317Y153623D01*
X194660Y153738D01*
Y154773D01*
G01X203117Y161820D02*
X203347Y161975D01*
X203615Y162078D01*
X203922D01*
X204267Y161923D01*
X204535Y161665D01*
X204727Y161355D01*
X204880Y160838D01*
X204918Y160373D01*
X204842Y159908D01*
X204727Y159598D01*
X204497Y159288D01*
X204228Y159081D01*
X203960Y158978D01*
X203692D01*
X203423Y159081D01*
X203193Y159236D01*
X203002Y159443D01*
G01X200860Y158978D02*
Y162078D01*
X201320Y161458D01*
G01Y158978D02*
X200400D01*
G01X197760Y162078D02*
X198067Y161975D01*
X198297Y161716D01*
X198450Y161406D01*
X198565Y160993D01*
X198603Y160528D01*
X198565Y160063D01*
X198450Y159650D01*
X198297Y159340D01*
X198067Y159081D01*
X197760Y158978D01*
X197453Y159081D01*
X197223Y159340D01*
X197070Y159650D01*
X196955Y160063D01*
X196917Y160528D01*
X196955Y160993D01*
X197070Y161406D01*
X197223Y161716D01*
X197453Y161975D01*
X197760Y162078D01*
G01X194660Y158978D02*
Y162078D01*
X195120Y161458D01*
G01Y158978D02*
X194200D01*
G01X190332Y163537D02*
X190487Y163307D01*
X190590Y163039D01*
Y162732D01*
X190435Y162387D01*
X190177Y162119D01*
X189867Y161927D01*
X189350Y161774D01*
X188885Y161736D01*
X188420Y161812D01*
X188110Y161927D01*
X187800Y162157D01*
X187593Y162426D01*
X187490Y162694D01*
Y162962D01*
X187593Y163231D01*
X187748Y163461D01*
X187955Y163652D01*
G01X187490Y165794D02*
X190590D01*
X189970Y165334D01*
G01X187490D02*
Y166254D01*
G01X190073Y168166D02*
X190383Y168396D01*
X190538Y168664D01*
X190590Y168971D01*
X190487Y169354D01*
X190228Y169622D01*
X189918Y169699D01*
X189608Y169661D01*
X189350Y169507D01*
X188833Y168741D01*
X188472Y168396D01*
X187955Y168166D01*
X187490Y168089D01*
Y169699D01*
G01X190073Y171266D02*
X190383Y171496D01*
X190538Y171764D01*
X190590Y172071D01*
X190487Y172454D01*
X190228Y172722D01*
X189918Y172799D01*
X189608Y172761D01*
X189350Y172607D01*
X188833Y171841D01*
X188472Y171496D01*
X187955Y171266D01*
X187490Y171189D01*
Y172799D01*
G01X185052Y187911D02*
X185207Y187681D01*
X185310Y187413D01*
Y187106D01*
X185155Y186761D01*
X184897Y186493D01*
X184587Y186301D01*
X184070Y186148D01*
X183605Y186110D01*
X183140Y186186D01*
X182830Y186301D01*
X182520Y186531D01*
X182313Y186800D01*
X182210Y187068D01*
Y187336D01*
X182313Y187605D01*
X182468Y187835D01*
X182675Y188026D01*
G01X182210Y190168D02*
X185310D01*
X184690Y189708D01*
G01X182210D02*
Y190628D01*
G01X185310Y193268D02*
X185207Y192961D01*
X184948Y192731D01*
X184638Y192578D01*
X184225Y192463D01*
X183760Y192425D01*
X183295Y192463D01*
X182882Y192578D01*
X182572Y192731D01*
X182313Y192961D01*
X182210Y193268D01*
X182313Y193575D01*
X182572Y193805D01*
X182882Y193958D01*
X183295Y194073D01*
X183760Y194111D01*
X184225Y194073D01*
X184638Y193958D01*
X184948Y193805D01*
X185207Y193575D01*
X185310Y193268D01*
G01Y196368D02*
X185207Y196061D01*
X184948Y195831D01*
X184638Y195678D01*
X184225Y195563D01*
X183760Y195525D01*
X183295Y195563D01*
X182882Y195678D01*
X182572Y195831D01*
X182313Y196061D01*
X182210Y196368D01*
X182313Y196675D01*
X182572Y196905D01*
X182882Y197058D01*
X183295Y197173D01*
X183760Y197211D01*
X184225Y197173D01*
X184638Y197058D01*
X184948Y196905D01*
X185207Y196675D01*
X185310Y196368D01*
G01X193052Y186873D02*
X193207Y186643D01*
X193310Y186375D01*
Y186068D01*
X193155Y185723D01*
X192897Y185455D01*
X192587Y185263D01*
X192070Y185110D01*
X191605Y185072D01*
X191140Y185148D01*
X190830Y185263D01*
X190520Y185493D01*
X190313Y185762D01*
X190210Y186030D01*
Y186298D01*
X190313Y186567D01*
X190468Y186797D01*
X190675Y186988D01*
G01X191502Y188402D02*
X191863Y188670D01*
X192070Y188900D01*
X192173Y189207D01*
X192070Y189475D01*
X191863Y189667D01*
X191553Y189820D01*
X191192Y189858D01*
X190882Y189820D01*
X190572Y189667D01*
X190313Y189437D01*
X190210Y189168D01*
X190313Y188862D01*
X190623Y188593D01*
X191088Y188440D01*
X191605Y188402D01*
X192277Y188478D01*
X192638Y188593D01*
X193000Y188785D01*
X193258Y189053D01*
X193310Y189322D01*
X193207Y189590D01*
X192948Y189782D01*
G01X190210Y192230D02*
X190262Y192498D01*
X190417Y192805D01*
X190675Y192997D01*
X191037Y193073D01*
X191398Y192997D01*
X191708Y192767D01*
X191863Y192422D01*
Y192038D01*
X191967Y191808D01*
X192225Y191617D01*
X192587Y191540D01*
X192948Y191655D01*
X193207Y191923D01*
X193310Y192230D01*
X193207Y192537D01*
X192948Y192805D01*
X192587Y192920D01*
X192225Y192843D01*
X191967Y192652D01*
X191863Y192422D01*
Y192038D01*
X191708Y191693D01*
X191398Y191463D01*
X191037Y191387D01*
X190675Y191463D01*
X190417Y191655D01*
X190262Y191962D01*
X190210Y192230D01*
G01X196822Y186938D02*
X196977Y186708D01*
X197080Y186440D01*
Y186133D01*
X196925Y185788D01*
X196667Y185520D01*
X196357Y185328D01*
X195840Y185175D01*
X195375Y185137D01*
X194910Y185213D01*
X194600Y185328D01*
X194290Y185558D01*
X194083Y185827D01*
X193980Y186095D01*
Y186363D01*
X194083Y186632D01*
X194238Y186862D01*
X194445Y187053D01*
G01X193980Y189195D02*
X194032Y189463D01*
X194187Y189770D01*
X194445Y189962D01*
X194807Y190038D01*
X195168Y189962D01*
X195478Y189732D01*
X195633Y189387D01*
Y189003D01*
X195737Y188773D01*
X195995Y188582D01*
X196357Y188505D01*
X196718Y188620D01*
X196977Y188888D01*
X197080Y189195D01*
X196977Y189502D01*
X196718Y189770D01*
X196357Y189885D01*
X195995Y189808D01*
X195737Y189617D01*
X195633Y189387D01*
Y189003D01*
X195478Y188658D01*
X195168Y188428D01*
X194807Y188352D01*
X194445Y188428D01*
X194187Y188620D01*
X194032Y188927D01*
X193980Y189195D01*
G01Y192295D02*
X197080D01*
X196460Y191835D01*
G01X193980D02*
Y192755D01*
G01X189082Y189211D02*
X189237Y188981D01*
X189340Y188713D01*
Y188406D01*
X189185Y188061D01*
X188927Y187793D01*
X188617Y187601D01*
X188100Y187448D01*
X187635Y187410D01*
X187170Y187486D01*
X186860Y187601D01*
X186550Y187831D01*
X186343Y188100D01*
X186240Y188368D01*
Y188636D01*
X186343Y188905D01*
X186498Y189135D01*
X186705Y189326D01*
G01X186240Y191468D02*
X186292Y191736D01*
X186447Y192043D01*
X186705Y192235D01*
X187067Y192311D01*
X187428Y192235D01*
X187738Y192005D01*
X187893Y191660D01*
Y191276D01*
X187997Y191046D01*
X188255Y190855D01*
X188617Y190778D01*
X188978Y190893D01*
X189237Y191161D01*
X189340Y191468D01*
X189237Y191775D01*
X188978Y192043D01*
X188617Y192158D01*
X188255Y192081D01*
X187997Y191890D01*
X187893Y191660D01*
Y191276D01*
X187738Y190931D01*
X187428Y190701D01*
X187067Y190625D01*
X186705Y190701D01*
X186447Y190893D01*
X186292Y191200D01*
X186240Y191468D01*
G01X186860Y193725D02*
X186498Y193955D01*
X186292Y194261D01*
X186240Y194606D01*
X186292Y194913D01*
X186550Y195220D01*
X186860Y195411D01*
X187170Y195450D01*
X187532Y195373D01*
X187790Y195105D01*
X187893Y194836D01*
Y194491D01*
G01Y194836D02*
X188048Y195066D01*
X188307Y195258D01*
X188617Y195335D01*
X188927Y195258D01*
X189185Y195066D01*
X189340Y194721D01*
X189288Y194376D01*
X189082Y194031D01*
G01X192837Y180949D02*
X193067Y181104D01*
X193335Y181207D01*
X193642D01*
X193987Y181052D01*
X194255Y180794D01*
X194447Y180484D01*
X194600Y179967D01*
X194638Y179502D01*
X194562Y179037D01*
X194447Y178727D01*
X194217Y178417D01*
X193948Y178210D01*
X193680Y178107D01*
X193412D01*
X193143Y178210D01*
X192913Y178365D01*
X192722Y178572D01*
G01X190120Y178107D02*
Y181207D01*
X191538Y178985D01*
X189622D01*
G01X187557Y178107D02*
X187480Y178779D01*
X187365Y179347D01*
X187212Y179864D01*
X187020Y180432D01*
X186713Y181207D01*
X188247D01*
G01X192587Y176621D02*
X192817Y176776D01*
X193085Y176879D01*
X193392D01*
X193737Y176724D01*
X194005Y176466D01*
X194197Y176156D01*
X194350Y175639D01*
X194388Y175174D01*
X194312Y174709D01*
X194197Y174399D01*
X193967Y174089D01*
X193698Y173882D01*
X193430Y173779D01*
X193162D01*
X192893Y173882D01*
X192663Y174037D01*
X192472Y174244D01*
G01X190330Y173779D02*
Y176879D01*
X190790Y176259D01*
G01Y173779D02*
X189870D01*
G01X188073Y174399D02*
X187843Y174037D01*
X187537Y173831D01*
X187192Y173779D01*
X186885Y173831D01*
X186578Y174089D01*
X186387Y174399D01*
X186348Y174709D01*
X186425Y175071D01*
X186693Y175329D01*
X186962Y175432D01*
X187307D01*
G01X186962D02*
X186732Y175587D01*
X186540Y175846D01*
X186463Y176156D01*
X186540Y176466D01*
X186732Y176724D01*
X187077Y176879D01*
X187422Y176827D01*
X187767Y176621D01*
G01X184130Y176879D02*
X184437Y176776D01*
X184667Y176517D01*
X184820Y176207D01*
X184935Y175794D01*
X184973Y175329D01*
X184935Y174864D01*
X184820Y174451D01*
X184667Y174141D01*
X184437Y173882D01*
X184130Y173779D01*
X183823Y173882D01*
X183593Y174141D01*
X183440Y174451D01*
X183325Y174864D01*
X183287Y175329D01*
X183325Y175794D01*
X183440Y176207D01*
X183593Y176517D01*
X183823Y176776D01*
X184130Y176879D01*
G01X195852Y198436D02*
X196007Y198206D01*
X196110Y197938D01*
Y197631D01*
X195955Y197286D01*
X195697Y197018D01*
X195387Y196826D01*
X194870Y196673D01*
X194405Y196635D01*
X193940Y196711D01*
X193630Y196826D01*
X193320Y197056D01*
X193113Y197325D01*
X193010Y197593D01*
Y197861D01*
X193113Y198130D01*
X193268Y198360D01*
X193475Y198551D01*
G01X193010Y200616D02*
X193682Y200693D01*
X194250Y200808D01*
X194767Y200961D01*
X195335Y201153D01*
X196110Y201460D01*
Y199926D01*
G01X193010Y203716D02*
X193682Y203793D01*
X194250Y203908D01*
X194767Y204061D01*
X195335Y204253D01*
X196110Y204560D01*
Y203026D01*
G01X189672Y199060D02*
X189827Y198830D01*
X189930Y198562D01*
Y198255D01*
X189775Y197910D01*
X189517Y197642D01*
X189207Y197450D01*
X188690Y197297D01*
X188225Y197259D01*
X187760Y197335D01*
X187450Y197450D01*
X187140Y197680D01*
X186933Y197949D01*
X186830Y198217D01*
Y198485D01*
X186933Y198754D01*
X187088Y198984D01*
X187295Y199175D01*
G01X186830Y201240D02*
X187502Y201317D01*
X188070Y201432D01*
X188587Y201585D01*
X189155Y201777D01*
X189930Y202084D01*
Y200550D01*
G01X187295Y203574D02*
X187037Y203804D01*
X186882Y204072D01*
X186830Y204417D01*
X186933Y204762D01*
X187140Y205030D01*
X187502Y205222D01*
X187915Y205260D01*
X188328Y205184D01*
X188587Y204992D01*
X188793Y204724D01*
X188845Y204455D01*
X188793Y204187D01*
X188587Y203842D01*
X189930Y203957D01*
Y204992D01*
G01X191880Y207340D02*
X239060D01*
G01X191880Y214250D02*
Y207340D01*
G01X181227Y234874D02*
Y241074D01*
G01X193260Y264200D02*
Y264653D01*
G01Y264200D02*
X196347D01*
G01X193260Y272070D02*
Y278067D01*
G01Y267170D02*
Y269504D01*
G01Y296327D02*
Y296081D01*
G01Y287987D02*
Y292602D01*
G01Y282706D02*
Y284680D01*
G01X185170Y311972D02*
Y315945D01*
G01Y304199D02*
Y309578D01*
G01Y300720D02*
Y301460D01*
G01X193260Y300720D02*
Y299042D01*
G01Y300720D02*
X185170D01*
G01X193730Y310003D02*
Y313203D01*
G01X190630Y310103D02*
Y313103D01*
G01X193730Y313203D02*
X187530D01*
G01D02*
Y310003D01*
G01D02*
X193730D01*
G01X193857Y304219D02*
Y307419D01*
G01D02*
X187657D01*
G01X190757Y307319D02*
Y304319D01*
G01X187657Y304219D02*
X193857D01*
G01X187657Y307419D02*
Y304219D01*
G01X194847Y312017D02*
X201047D01*
G01X194847Y315217D02*
Y312017D01*
G01X189723Y327640D02*
Y332640D01*
X188457D01*
X187950Y332390D01*
X187570Y332057D01*
X187253Y331557D01*
X187000Y330973D01*
X186937Y330140D01*
X187000Y329307D01*
X187253Y328723D01*
X187570Y328223D01*
X187950Y327890D01*
X188457Y327640D01*
X189723D01*
G01X185170Y327740D02*
Y330825D01*
G01Y317919D02*
Y325130D01*
G01X201047Y315217D02*
X194847D01*
G01X198487Y328147D02*
X195287D01*
G01D02*
Y321947D01*
G01D02*
X198487D01*
G01X193830Y333690D02*
X193632D01*
G01X186723D02*
X189511D01*
G01X193830D02*
X199037D01*
G01X194829Y329414D02*
X201029D01*
G01Y332614D02*
X194829D01*
G01D02*
Y329414D01*
G01X188113Y352300D02*
X191213D01*
Y353259D01*
X191058Y353565D01*
X190851Y353757D01*
X190438Y353834D01*
X190025Y353757D01*
X189766Y353527D01*
X189611Y353259D01*
Y352300D01*
G01Y353259D02*
X188113Y353834D01*
G01X188475Y355515D02*
X188216Y355784D01*
X188113Y356090D01*
X188216Y356397D01*
X188526Y356665D01*
X188991Y356857D01*
X189456Y356934D01*
X190025D01*
X190490Y356857D01*
X190903Y356665D01*
X191110Y356435D01*
X191213Y356167D01*
X191110Y355860D01*
X190903Y355630D01*
X190593Y355477D01*
X190180Y355400D01*
X189818Y355477D01*
X189456Y355669D01*
X189250Y355899D01*
X189198Y356167D01*
X189301Y356474D01*
X189560Y356704D01*
X190025Y356934D01*
G01X188113Y359190D02*
X188785Y359267D01*
X189353Y359382D01*
X189870Y359535D01*
X190438Y359727D01*
X191213Y360034D01*
Y358500D01*
G01X188458Y351419D02*
Y345219D01*
G01D02*
X191658D01*
G01D02*
Y351419D01*
G01D02*
X188458D01*
G01X193915Y352347D02*
X197015D01*
Y353306D01*
X196860Y353612D01*
X196653Y353804D01*
X196240Y353881D01*
X195827Y353804D01*
X195568Y353574D01*
X195413Y353306D01*
Y352347D01*
G01Y353306D02*
X193915Y353881D01*
G01X194277Y355562D02*
X194018Y355831D01*
X193915Y356137D01*
X194018Y356444D01*
X194328Y356712D01*
X194793Y356904D01*
X195258Y356981D01*
X195827D01*
X196292Y356904D01*
X196705Y356712D01*
X196912Y356482D01*
X197015Y356214D01*
X196912Y355907D01*
X196705Y355677D01*
X196395Y355524D01*
X195982Y355447D01*
X195620Y355524D01*
X195258Y355716D01*
X195052Y355946D01*
X195000Y356214D01*
X195103Y356521D01*
X195362Y356751D01*
X195827Y356981D01*
G01X194277Y358662D02*
X194018Y358931D01*
X193915Y359237D01*
X194018Y359544D01*
X194328Y359812D01*
X194793Y360004D01*
X195258Y360081D01*
X195827D01*
X196292Y360004D01*
X196705Y359812D01*
X196912Y359582D01*
X197015Y359314D01*
X196912Y359007D01*
X196705Y358777D01*
X196395Y358624D01*
X195982Y358547D01*
X195620Y358624D01*
X195258Y358816D01*
X195052Y359046D01*
X195000Y359314D01*
X195103Y359621D01*
X195362Y359851D01*
X195827Y360081D01*
G01X192585Y351509D02*
Y345309D01*
G01D02*
X195785D01*
G01Y351509D02*
X192585D01*
G01X182558Y371655D02*
X185558D01*
G01X185658Y374755D02*
X182458D01*
G01X185658Y368555D02*
Y374755D01*
G01X182458D02*
Y368555D01*
G01D02*
X185658D01*
G01X181658D02*
Y374755D01*
G01X189658D02*
X186458D01*
G01D02*
Y368555D01*
G01D02*
X189658D01*
G01D02*
Y374755D01*
G01X182400Y386683D02*
X185500D01*
Y387642D01*
X185345Y387948D01*
X185138Y388140D01*
X184725Y388217D01*
X184312Y388140D01*
X184053Y387910D01*
X183898Y387642D01*
Y386683D01*
G01Y387642D02*
X182400Y388217D01*
G01Y390550D02*
X185500D01*
X184880Y390090D01*
G01X182400D02*
Y391010D01*
G01X183020Y392807D02*
X182658Y393037D01*
X182452Y393343D01*
X182400Y393688D01*
X182452Y393995D01*
X182710Y394302D01*
X183020Y394493D01*
X183330Y394532D01*
X183692Y394455D01*
X183950Y394187D01*
X184053Y393918D01*
Y393573D01*
G01Y393918D02*
X184208Y394148D01*
X184467Y394340D01*
X184777Y394417D01*
X185087Y394340D01*
X185345Y394148D01*
X185500Y393803D01*
X185448Y393458D01*
X185242Y393113D01*
G01X183020Y395907D02*
X182658Y396137D01*
X182452Y396443D01*
X182400Y396788D01*
X182452Y397095D01*
X182710Y397402D01*
X183020Y397593D01*
X183330Y397632D01*
X183692Y397555D01*
X183950Y397287D01*
X184053Y397018D01*
Y396673D01*
G01Y397018D02*
X184208Y397248D01*
X184467Y397440D01*
X184777Y397517D01*
X185087Y397440D01*
X185345Y397248D01*
X185500Y396903D01*
X185448Y396558D01*
X185242Y396213D01*
G01X181401Y379097D02*
Y385297D01*
G01X188482Y386465D02*
X191582D01*
Y387424D01*
X191427Y387730D01*
X191220Y387922D01*
X190807Y387999D01*
X190394Y387922D01*
X190135Y387692D01*
X189980Y387424D01*
Y386465D01*
G01Y387424D02*
X188482Y387999D01*
G01Y390332D02*
X191582D01*
X190962Y389872D01*
G01X188482D02*
Y390792D01*
G01X191065Y392704D02*
X191375Y392934D01*
X191530Y393202D01*
X191582Y393509D01*
X191479Y393892D01*
X191220Y394160D01*
X190910Y394237D01*
X190600Y394199D01*
X190342Y394045D01*
X189825Y393279D01*
X189464Y392934D01*
X188947Y392704D01*
X188482Y392627D01*
Y394237D01*
G01Y396992D02*
X191582D01*
X189360Y395574D01*
Y397490D01*
G01X189570Y379201D02*
Y385401D01*
G01D02*
X186370D01*
G01D02*
Y379201D01*
G01D02*
X189570D01*
G01X181746Y415536D02*
X204000D01*
Y418921D01*
X244246D01*
Y403374D01*
X204188D01*
Y405255D01*
X179928D01*
Y415536D01*
X181746D01*
G01X189742Y406296D02*
X192842D01*
Y407255D01*
X192687Y407561D01*
X192480Y407753D01*
X192067Y407830D01*
X191654Y407753D01*
X191395Y407523D01*
X191240Y407255D01*
Y406296D01*
G01Y407255D02*
X189742Y407830D01*
G01X190207Y409320D02*
X189949Y409550D01*
X189794Y409818D01*
X189742Y410163D01*
X189845Y410508D01*
X190052Y410776D01*
X190414Y410968D01*
X190827Y411006D01*
X191240Y410930D01*
X191499Y410738D01*
X191705Y410470D01*
X191757Y410201D01*
X191705Y409933D01*
X191499Y409588D01*
X192842Y409703D01*
Y410738D01*
G01X189742Y413263D02*
X192842D01*
X192222Y412803D01*
G01X189742D02*
Y413723D01*
G01X181592Y406296D02*
X184692D01*
Y407255D01*
X184537Y407561D01*
X184330Y407753D01*
X183917Y407830D01*
X183504Y407753D01*
X183245Y407523D01*
X183090Y407255D01*
Y406296D01*
G01Y407255D02*
X181592Y407830D01*
G01Y410086D02*
X182264Y410163D01*
X182832Y410278D01*
X183349Y410431D01*
X183917Y410623D01*
X184692Y410930D01*
Y409396D01*
G01X181954Y412611D02*
X181695Y412880D01*
X181592Y413186D01*
X181695Y413493D01*
X182005Y413761D01*
X182470Y413953D01*
X182935Y414030D01*
X183504D01*
X183969Y413953D01*
X184382Y413761D01*
X184589Y413531D01*
X184692Y413263D01*
X184589Y412956D01*
X184382Y412726D01*
X184072Y412573D01*
X183659Y412496D01*
X183297Y412573D01*
X182935Y412765D01*
X182729Y412995D01*
X182677Y413263D01*
X182780Y413570D01*
X183039Y413800D01*
X183504Y414030D01*
G01X185598Y406296D02*
X188698D01*
Y407255D01*
X188543Y407561D01*
X188336Y407753D01*
X187923Y407830D01*
X187510Y407753D01*
X187251Y407523D01*
X187096Y407255D01*
Y406296D01*
G01Y407255D02*
X185598Y407830D01*
G01X186063Y409320D02*
X185805Y409550D01*
X185650Y409818D01*
X185598Y410163D01*
X185701Y410508D01*
X185908Y410776D01*
X186270Y410968D01*
X186683Y411006D01*
X187096Y410930D01*
X187355Y410738D01*
X187561Y410470D01*
X187613Y410201D01*
X187561Y409933D01*
X187355Y409588D01*
X188698Y409703D01*
Y410738D01*
G01Y413263D02*
X188595Y412956D01*
X188336Y412726D01*
X188026Y412573D01*
X187613Y412458D01*
X187148Y412420D01*
X186683Y412458D01*
X186270Y412573D01*
X185960Y412726D01*
X185701Y412956D01*
X185598Y413263D01*
X185701Y413570D01*
X185960Y413800D01*
X186270Y413953D01*
X186683Y414068D01*
X187148Y414106D01*
X187613Y414068D01*
X188026Y413953D01*
X188336Y413800D01*
X188595Y413570D01*
X188698Y413263D01*
G01X193886Y406296D02*
X196986D01*
Y407255D01*
X196831Y407561D01*
X196624Y407753D01*
X196211Y407830D01*
X195798Y407753D01*
X195539Y407523D01*
X195384Y407255D01*
Y406296D01*
G01Y407255D02*
X193886Y407830D01*
G01Y410163D02*
X193938Y410431D01*
X194093Y410738D01*
X194351Y410930D01*
X194713Y411006D01*
X195074Y410930D01*
X195384Y410700D01*
X195539Y410355D01*
Y409971D01*
X195643Y409741D01*
X195901Y409550D01*
X196263Y409473D01*
X196624Y409588D01*
X196883Y409856D01*
X196986Y410163D01*
X196883Y410470D01*
X196624Y410738D01*
X196263Y410853D01*
X195901Y410776D01*
X195643Y410585D01*
X195539Y410355D01*
Y409971D01*
X195384Y409626D01*
X195074Y409396D01*
X194713Y409320D01*
X194351Y409396D01*
X194093Y409588D01*
X193938Y409895D01*
X193886Y410163D01*
G01Y413263D02*
X196986D01*
X196366Y412803D01*
G01X193886D02*
Y413723D01*
G01X196239Y455690D02*
Y458790D01*
X195319D01*
X195012Y458635D01*
X194782Y458273D01*
X194705Y457860D01*
X194782Y457447D01*
X194974Y457137D01*
X195319Y456982D01*
X196239D01*
G01X191529Y458532D02*
X191759Y458687D01*
X192027Y458790D01*
X192334D01*
X192679Y458635D01*
X192947Y458377D01*
X193139Y458067D01*
X193292Y457550D01*
X193330Y457085D01*
X193254Y456620D01*
X193139Y456310D01*
X192909Y456000D01*
X192640Y455793D01*
X192372Y455690D01*
X192104D01*
X191835Y455793D01*
X191605Y455948D01*
X191414Y456155D01*
G01X189272Y455690D02*
Y458790D01*
X189732Y458170D01*
G01Y455690D02*
X188812D01*
G01X187015Y456310D02*
X186785Y455948D01*
X186479Y455742D01*
X186134Y455690D01*
X185827Y455742D01*
X185520Y456000D01*
X185329Y456310D01*
X185290Y456620D01*
X185367Y456982D01*
X185635Y457240D01*
X185904Y457343D01*
X186249D01*
G01X185904D02*
X185674Y457498D01*
X185482Y457757D01*
X185405Y458067D01*
X185482Y458377D01*
X185674Y458635D01*
X186019Y458790D01*
X186364Y458738D01*
X186709Y458532D01*
G01X181289Y446813D02*
X198689D01*
G01X189989Y454213D02*
Y446813D01*
G01X181289Y454213D02*
Y446813D01*
G01X198689Y454213D02*
X181289D01*
G01X198257Y520035D02*
X198487Y520190D01*
X198755Y520293D01*
X199062D01*
X199407Y520138D01*
X199675Y519880D01*
X199867Y519570D01*
X200020Y519053D01*
X200058Y518588D01*
X199982Y518123D01*
X199867Y517813D01*
X199637Y517503D01*
X199368Y517296D01*
X199100Y517193D01*
X198832D01*
X198563Y517296D01*
X198333Y517451D01*
X198142Y517658D01*
G01X196728Y519776D02*
X196498Y520086D01*
X196230Y520241D01*
X195923Y520293D01*
X195540Y520190D01*
X195272Y519931D01*
X195195Y519621D01*
X195233Y519311D01*
X195387Y519053D01*
X196153Y518536D01*
X196498Y518175D01*
X196728Y517658D01*
X196805Y517193D01*
X195195D01*
G01X193628Y519776D02*
X193398Y520086D01*
X193130Y520241D01*
X192823Y520293D01*
X192440Y520190D01*
X192172Y519931D01*
X192095Y519621D01*
X192133Y519311D01*
X192287Y519053D01*
X193053Y518536D01*
X193398Y518175D01*
X193628Y517658D01*
X193705Y517193D01*
X192095D01*
G01X190643Y517813D02*
X190413Y517451D01*
X190107Y517245D01*
X189762Y517193D01*
X189455Y517245D01*
X189148Y517503D01*
X188957Y517813D01*
X188918Y518123D01*
X188995Y518485D01*
X189263Y518743D01*
X189532Y518846D01*
X189877D01*
G01X189532D02*
X189302Y519001D01*
X189110Y519260D01*
X189033Y519570D01*
X189110Y519880D01*
X189302Y520138D01*
X189647Y520293D01*
X189992Y520241D01*
X190337Y520035D01*
G01X199750Y506867D02*
X199980Y507022D01*
X200248Y507125D01*
X200555D01*
X200900Y506970D01*
X201168Y506712D01*
X201360Y506402D01*
X201513Y505885D01*
X201551Y505420D01*
X201475Y504955D01*
X201360Y504645D01*
X201130Y504335D01*
X200861Y504128D01*
X200593Y504025D01*
X200325D01*
X200056Y504128D01*
X199826Y504283D01*
X199635Y504490D01*
G01X198221Y506608D02*
X197991Y506918D01*
X197723Y507073D01*
X197416Y507125D01*
X197033Y507022D01*
X196765Y506763D01*
X196688Y506453D01*
X196726Y506143D01*
X196880Y505885D01*
X197646Y505368D01*
X197991Y505007D01*
X198221Y504490D01*
X198298Y504025D01*
X196688D01*
G01X195236Y504645D02*
X195006Y504283D01*
X194700Y504077D01*
X194355Y504025D01*
X194048Y504077D01*
X193741Y504335D01*
X193550Y504645D01*
X193511Y504955D01*
X193588Y505317D01*
X193856Y505575D01*
X194125Y505678D01*
X194470D01*
G01X194125D02*
X193895Y505833D01*
X193703Y506092D01*
X193626Y506402D01*
X193703Y506712D01*
X193895Y506970D01*
X194240Y507125D01*
X194585Y507073D01*
X194930Y506867D01*
G01X192021Y506608D02*
X191791Y506918D01*
X191523Y507073D01*
X191216Y507125D01*
X190833Y507022D01*
X190565Y506763D01*
X190488Y506453D01*
X190526Y506143D01*
X190680Y505885D01*
X191446Y505368D01*
X191791Y505007D01*
X192021Y504490D01*
X192098Y504025D01*
X190488D01*
G01X186209Y506853D02*
Y503853D01*
G01X183109Y506953D02*
Y503753D01*
G01X189309Y506953D02*
X183109D01*
G01X189309Y503753D02*
Y506953D01*
G01X183109Y503753D02*
X189309D01*
G01X199934Y512530D02*
X200164Y512685D01*
X200432Y512788D01*
X200739D01*
X201084Y512633D01*
X201352Y512375D01*
X201544Y512065D01*
X201697Y511548D01*
X201735Y511083D01*
X201659Y510618D01*
X201544Y510308D01*
X201314Y509998D01*
X201045Y509791D01*
X200777Y509688D01*
X200509D01*
X200240Y509791D01*
X200010Y509946D01*
X199819Y510153D01*
G01X198405Y512271D02*
X198175Y512581D01*
X197907Y512736D01*
X197600Y512788D01*
X197217Y512685D01*
X196949Y512426D01*
X196872Y512116D01*
X196910Y511806D01*
X197064Y511548D01*
X197830Y511031D01*
X198175Y510670D01*
X198405Y510153D01*
X198482Y509688D01*
X196872D01*
G01X195420Y510308D02*
X195190Y509946D01*
X194884Y509740D01*
X194539Y509688D01*
X194232Y509740D01*
X193925Y509998D01*
X193734Y510308D01*
X193695Y510618D01*
X193772Y510980D01*
X194040Y511238D01*
X194309Y511341D01*
X194654D01*
G01X194309D02*
X194079Y511496D01*
X193887Y511755D01*
X193810Y512065D01*
X193887Y512375D01*
X194079Y512633D01*
X194424Y512788D01*
X194769Y512736D01*
X195114Y512530D01*
G01X192320Y510153D02*
X192090Y509895D01*
X191822Y509740D01*
X191477Y509688D01*
X191132Y509791D01*
X190864Y509998D01*
X190672Y510360D01*
X190634Y510773D01*
X190710Y511186D01*
X190902Y511445D01*
X191170Y511651D01*
X191439Y511703D01*
X191707Y511651D01*
X192052Y511445D01*
X191937Y512788D01*
X190902D01*
G01X186709Y512853D02*
Y509853D01*
G01X183609Y512953D02*
Y509753D01*
G01X189809Y512953D02*
X183609D01*
G01X189809Y509753D02*
Y512953D01*
G01X183609Y509753D02*
X189809D01*
G01X182209Y521553D02*
Y518553D01*
G01X185309Y518453D02*
Y521653D01*
G01X198355Y521223D02*
Y524323D01*
X197396D01*
X197090Y524168D01*
X196898Y523961D01*
X196821Y523548D01*
X196898Y523135D01*
X197128Y522876D01*
X197396Y522721D01*
X198355D01*
G01X197396D02*
X196821Y521223D01*
G01X195216Y523806D02*
X194986Y524116D01*
X194718Y524271D01*
X194411Y524323D01*
X194028Y524220D01*
X193760Y523961D01*
X193683Y523651D01*
X193721Y523341D01*
X193875Y523083D01*
X194641Y522566D01*
X194986Y522205D01*
X195216Y521688D01*
X195293Y521223D01*
X193683D01*
G01X192116Y522515D02*
X191848Y522876D01*
X191618Y523083D01*
X191311Y523186D01*
X191043Y523083D01*
X190851Y522876D01*
X190698Y522566D01*
X190660Y522205D01*
X190698Y521895D01*
X190851Y521585D01*
X191081Y521326D01*
X191350Y521223D01*
X191656Y521326D01*
X191925Y521636D01*
X192078Y522101D01*
X192116Y522618D01*
X192040Y523290D01*
X191925Y523651D01*
X191733Y524013D01*
X191465Y524271D01*
X191196Y524323D01*
X190928Y524220D01*
X190736Y523961D01*
G01X188288Y524323D02*
X188595Y524220D01*
X188825Y523961D01*
X188978Y523651D01*
X189093Y523238D01*
X189131Y522773D01*
X189093Y522308D01*
X188978Y521895D01*
X188825Y521585D01*
X188595Y521326D01*
X188288Y521223D01*
X187981Y521326D01*
X187751Y521585D01*
X187598Y521895D01*
X187483Y522308D01*
X187445Y522773D01*
X187483Y523238D01*
X187598Y523651D01*
X187751Y523961D01*
X187981Y524220D01*
X188288Y524323D01*
G01X183071Y522537D02*
Y525737D01*
G01X190486Y549245D02*
Y555445D01*
G01X187286Y549245D02*
X190486D01*
G01X187286Y555445D02*
Y549245D01*
G01X200387Y544712D02*
X200617Y544867D01*
X200885Y544970D01*
X201192D01*
X201537Y544815D01*
X201805Y544557D01*
X201997Y544247D01*
X202150Y543730D01*
X202188Y543265D01*
X202112Y542800D01*
X201997Y542490D01*
X201767Y542180D01*
X201498Y541973D01*
X201230Y541870D01*
X200962D01*
X200693Y541973D01*
X200463Y542128D01*
X200272Y542335D01*
G01X198858Y544453D02*
X198628Y544763D01*
X198360Y544918D01*
X198053Y544970D01*
X197670Y544867D01*
X197402Y544608D01*
X197325Y544298D01*
X197363Y543988D01*
X197517Y543730D01*
X198283Y543213D01*
X198628Y542852D01*
X198858Y542335D01*
X198935Y541870D01*
X197325D01*
G01X195873Y542490D02*
X195643Y542128D01*
X195337Y541922D01*
X194992Y541870D01*
X194685Y541922D01*
X194378Y542180D01*
X194187Y542490D01*
X194148Y542800D01*
X194225Y543162D01*
X194493Y543420D01*
X194762Y543523D01*
X195107D01*
G01X194762D02*
X194532Y543678D01*
X194340Y543937D01*
X194263Y544247D01*
X194340Y544557D01*
X194532Y544815D01*
X194877Y544970D01*
X195222Y544918D01*
X195567Y544712D01*
G01X192773Y542490D02*
X192543Y542128D01*
X192237Y541922D01*
X191892Y541870D01*
X191585Y541922D01*
X191278Y542180D01*
X191087Y542490D01*
X191048Y542800D01*
X191125Y543162D01*
X191393Y543420D01*
X191662Y543523D01*
X192007D01*
G01X191662D02*
X191432Y543678D01*
X191240Y543937D01*
X191163Y544247D01*
X191240Y544557D01*
X191432Y544815D01*
X191777Y544970D01*
X192122Y544918D01*
X192467Y544712D01*
G01X187209Y542353D02*
Y539353D01*
G01X184109Y542453D02*
Y539253D01*
G01X190309Y542453D02*
X184109D01*
G01X190309Y539253D02*
Y542453D01*
G01X184109Y539253D02*
X190309D01*
G01X192707Y558734D02*
X192862Y558504D01*
X192965Y558236D01*
Y557929D01*
X192810Y557584D01*
X192552Y557316D01*
X192242Y557124D01*
X191725Y556971D01*
X191260Y556933D01*
X190795Y557009D01*
X190485Y557124D01*
X190175Y557354D01*
X189968Y557623D01*
X189865Y557891D01*
Y558159D01*
X189968Y558428D01*
X190123Y558658D01*
X190330Y558849D01*
G01X192448Y560263D02*
X192758Y560493D01*
X192913Y560761D01*
X192965Y561068D01*
X192862Y561451D01*
X192603Y561719D01*
X192293Y561796D01*
X191983Y561758D01*
X191725Y561604D01*
X191208Y560838D01*
X190847Y560493D01*
X190330Y560263D01*
X189865Y560186D01*
Y561796D01*
G01X190485Y563248D02*
X190123Y563478D01*
X189917Y563784D01*
X189865Y564129D01*
X189917Y564436D01*
X190175Y564743D01*
X190485Y564934D01*
X190795Y564973D01*
X191157Y564896D01*
X191415Y564628D01*
X191518Y564359D01*
Y564014D01*
G01Y564359D02*
X191673Y564589D01*
X191932Y564781D01*
X192242Y564858D01*
X192552Y564781D01*
X192810Y564589D01*
X192965Y564244D01*
X192913Y563899D01*
X192707Y563554D01*
G01X191157Y566463D02*
X191518Y566731D01*
X191725Y566961D01*
X191828Y567268D01*
X191725Y567536D01*
X191518Y567728D01*
X191208Y567881D01*
X190847Y567919D01*
X190537Y567881D01*
X190227Y567728D01*
X189968Y567498D01*
X189865Y567229D01*
X189968Y566923D01*
X190278Y566654D01*
X190743Y566501D01*
X191260Y566463D01*
X191932Y566539D01*
X192293Y566654D01*
X192655Y566846D01*
X192913Y567114D01*
X192965Y567383D01*
X192862Y567651D01*
X192603Y567843D01*
G01X190386Y552345D02*
X187386D01*
G01X190486Y555445D02*
X187286D01*
G01X191419Y576860D02*
X191574Y576630D01*
X191677Y576362D01*
Y576055D01*
X191522Y575710D01*
X191264Y575442D01*
X190954Y575250D01*
X190437Y575097D01*
X189972Y575059D01*
X189507Y575135D01*
X189197Y575250D01*
X188887Y575480D01*
X188680Y575749D01*
X188577Y576017D01*
Y576285D01*
X188680Y576554D01*
X188835Y576784D01*
X189042Y576975D01*
G01X188577Y579577D02*
X191677D01*
X189455Y578159D01*
Y580075D01*
G01X191160Y581489D02*
X191470Y581719D01*
X191625Y581987D01*
X191677Y582294D01*
X191574Y582677D01*
X191315Y582945D01*
X191005Y583022D01*
X190695Y582984D01*
X190437Y582830D01*
X189920Y582064D01*
X189559Y581719D01*
X189042Y581489D01*
X188577Y581412D01*
Y583022D01*
G01Y585777D02*
X191677D01*
X189455Y584359D01*
Y586275D01*
G01X181090Y577135D02*
X187690D01*
G01X180990Y584635D02*
Y569635D01*
G01D02*
X187790D01*
G01D02*
Y584635D01*
G01X184930Y594735D02*
X181730D01*
G01D02*
Y588535D01*
G01D02*
X184930D01*
G01D02*
Y594735D01*
G01X184830Y591635D02*
X181830D01*
G01X195030Y596335D02*
X188830D01*
G01Y593135D02*
X195030D01*
G01D02*
Y596335D01*
G01X188830D02*
Y593135D01*
G01X191930Y596235D02*
Y593235D01*
G01X187790Y584635D02*
X180990D01*
G01X188863Y602233D02*
X195063D01*
G01D02*
Y605433D01*
G01D02*
X188863D01*
G01D02*
Y602233D01*
G01X191963Y605333D02*
Y602333D01*
G01X188830Y606235D02*
X195030D01*
G01D02*
Y609435D01*
G01D02*
X188830D01*
G01D02*
Y606235D01*
G01X191930Y609335D02*
Y606335D01*
G01X188863Y597333D02*
X195063D01*
G01D02*
Y600533D01*
G01D02*
X188863D01*
G01D02*
Y597333D01*
G01X191963Y600433D02*
Y597433D01*
G01X180930Y626835D02*
X183930D01*
G01X180830Y629935D02*
Y623735D01*
G01X184030D02*
Y629935D01*
G01X180830Y623735D02*
X184030D01*
G01X188830Y613135D02*
X195030D01*
G01D02*
Y616335D01*
G01D02*
X188830D01*
G01D02*
Y613135D01*
G01X191930Y616235D02*
Y613235D01*
G01X188863Y621433D02*
X195063D01*
G01D02*
Y624633D01*
G01D02*
X188863D01*
G01D02*
Y621433D01*
G01X191963Y624533D02*
Y621533D01*
G01X188830Y625535D02*
X195030D01*
G01D02*
Y628735D01*
G01X188830D02*
Y625535D01*
G01X191930Y628635D02*
Y625635D01*
G01X184030Y629935D02*
X180830D01*
G01X195030Y628735D02*
X188830D01*
G01X195440Y706656D02*
Y709656D01*
G01X192340Y706556D02*
X198540D01*
G01X192340Y709756D02*
Y706556D01*
G01X195003Y696608D02*
Y699708D01*
X194044D01*
X193738Y699553D01*
X193546Y699346D01*
X193469Y698933D01*
X193546Y698520D01*
X193776Y698261D01*
X194044Y698106D01*
X195003D01*
G01X194044D02*
X193469Y696608D01*
G01X191864Y697900D02*
X191596Y698261D01*
X191366Y698468D01*
X191059Y698571D01*
X190791Y698468D01*
X190599Y698261D01*
X190446Y697951D01*
X190408Y697590D01*
X190446Y697280D01*
X190599Y696970D01*
X190829Y696711D01*
X191098Y696608D01*
X191404Y696711D01*
X191673Y697021D01*
X191826Y697486D01*
X191864Y698003D01*
X191788Y698675D01*
X191673Y699036D01*
X191481Y699398D01*
X191213Y699656D01*
X190944Y699708D01*
X190676Y699605D01*
X190484Y699346D01*
G01X188036Y696608D02*
X187768Y696660D01*
X187461Y696815D01*
X187269Y697073D01*
X187193Y697435D01*
X187269Y697796D01*
X187499Y698106D01*
X187844Y698261D01*
X188228D01*
X188458Y698365D01*
X188649Y698623D01*
X188726Y698985D01*
X188611Y699346D01*
X188343Y699605D01*
X188036Y699708D01*
X187729Y699605D01*
X187461Y699346D01*
X187346Y698985D01*
X187423Y698623D01*
X187614Y698365D01*
X187844Y698261D01*
X188228D01*
X188573Y698106D01*
X188803Y697796D01*
X188879Y697435D01*
X188803Y697073D01*
X188611Y696815D01*
X188304Y696660D01*
X188036Y696608D01*
G01X184936D02*
X184668Y696660D01*
X184361Y696815D01*
X184169Y697073D01*
X184093Y697435D01*
X184169Y697796D01*
X184399Y698106D01*
X184744Y698261D01*
X185128D01*
X185358Y698365D01*
X185549Y698623D01*
X185626Y698985D01*
X185511Y699346D01*
X185243Y699605D01*
X184936Y699708D01*
X184629Y699605D01*
X184361Y699346D01*
X184246Y698985D01*
X184323Y698623D01*
X184514Y698365D01*
X184744Y698261D01*
X185128D01*
X185473Y698106D01*
X185703Y697796D01*
X185779Y697435D01*
X185703Y697073D01*
X185511Y696815D01*
X185204Y696660D01*
X184936Y696608D01*
G01X187270Y703536D02*
Y700336D01*
G01X193470Y703536D02*
X187270D01*
G01X193470Y700336D02*
Y703536D01*
G01X187270Y700336D02*
X193470D01*
G01X188340Y713406D02*
X191540D01*
G01X188340Y719606D02*
Y713406D01*
G01X191540Y719606D02*
X188340D01*
G01X188440Y716506D02*
X191440D01*
G01X191540Y713406D02*
Y719606D01*
G01X183840Y713406D02*
X187040D01*
G01X183840Y719606D02*
Y713406D01*
G01X187040Y719606D02*
X183840D01*
G01X187040Y713406D02*
Y719606D01*
G01X183940Y716506D02*
X186940D01*
G01X192840Y713373D02*
X196040D01*
G01X192840Y719573D02*
Y713373D01*
G01X196040Y719573D02*
X192840D01*
G01X192940Y716473D02*
X195940D01*
G01X198540Y709756D02*
X192340D01*
G01X181293Y724942D02*
Y731142D01*
G01X192840Y737556D02*
X196040D01*
G01X192840Y743756D02*
Y737556D01*
G01Y726056D02*
X196040D01*
G01X192840Y732256D02*
Y726056D01*
G01X196040Y732256D02*
X192840D01*
G01X183840Y726056D02*
X187040D01*
G01X183840Y732256D02*
Y726056D01*
G01X187040Y732256D02*
X183840D01*
G01X187040Y726056D02*
Y732256D01*
G01X188340Y726056D02*
X191540D01*
G01X188340Y732256D02*
Y726056D01*
G01X191540Y732256D02*
X188340D01*
G01X191540Y726056D02*
Y732256D01*
G01X188340Y737556D02*
X191540D01*
G01X188340Y743756D02*
Y737556D01*
G01X191540D02*
Y743756D01*
G01X183840Y737556D02*
X187040D01*
G01X183840Y743756D02*
Y737556D01*
G01X187040D02*
Y743756D01*
G01X196040D02*
X192840D01*
G01X193687Y745884D02*
X196787D01*
Y746843D01*
X196632Y747149D01*
X196425Y747341D01*
X196012Y747418D01*
X195599Y747341D01*
X195340Y747111D01*
X195185Y746843D01*
Y745884D01*
G01Y746843D02*
X193687Y747418D01*
G01Y749751D02*
X193739Y750019D01*
X193894Y750326D01*
X194152Y750518D01*
X194514Y750594D01*
X194875Y750518D01*
X195185Y750288D01*
X195340Y749943D01*
Y749559D01*
X195444Y749329D01*
X195702Y749138D01*
X196064Y749061D01*
X196425Y749176D01*
X196684Y749444D01*
X196787Y749751D01*
X196684Y750058D01*
X196425Y750326D01*
X196064Y750441D01*
X195702Y750364D01*
X195444Y750173D01*
X195340Y749943D01*
Y749559D01*
X195185Y749214D01*
X194875Y748984D01*
X194514Y748908D01*
X194152Y748984D01*
X193894Y749176D01*
X193739Y749483D01*
X193687Y749751D01*
G01Y753311D02*
X196787D01*
X194565Y751893D01*
Y753809D01*
G01X196787Y755951D02*
X196684Y755644D01*
X196425Y755414D01*
X196115Y755261D01*
X195702Y755146D01*
X195237Y755108D01*
X194772Y755146D01*
X194359Y755261D01*
X194049Y755414D01*
X193790Y755644D01*
X193687Y755951D01*
X193790Y756258D01*
X194049Y756488D01*
X194359Y756641D01*
X194772Y756756D01*
X195237Y756794D01*
X195702Y756756D01*
X196115Y756641D01*
X196425Y756488D01*
X196684Y756258D01*
X196787Y755951D01*
G01X184687Y745884D02*
X187787D01*
Y746843D01*
X187632Y747149D01*
X187425Y747341D01*
X187012Y747418D01*
X186599Y747341D01*
X186340Y747111D01*
X186185Y746843D01*
Y745884D01*
G01Y746843D02*
X184687Y747418D01*
G01Y749751D02*
X184739Y750019D01*
X184894Y750326D01*
X185152Y750518D01*
X185514Y750594D01*
X185875Y750518D01*
X186185Y750288D01*
X186340Y749943D01*
Y749559D01*
X186444Y749329D01*
X186702Y749138D01*
X187064Y749061D01*
X187425Y749176D01*
X187684Y749444D01*
X187787Y749751D01*
X187684Y750058D01*
X187425Y750326D01*
X187064Y750441D01*
X186702Y750364D01*
X186444Y750173D01*
X186340Y749943D01*
Y749559D01*
X186185Y749214D01*
X185875Y748984D01*
X185514Y748908D01*
X185152Y748984D01*
X184894Y749176D01*
X184739Y749483D01*
X184687Y749751D01*
G01Y753311D02*
X187787D01*
X185565Y751893D01*
Y753809D01*
G01X184687Y755874D02*
X185359Y755951D01*
X185927Y756066D01*
X186444Y756219D01*
X187012Y756411D01*
X187787Y756718D01*
Y755184D01*
G01X189187Y745884D02*
X192287D01*
Y746843D01*
X192132Y747149D01*
X191925Y747341D01*
X191512Y747418D01*
X191099Y747341D01*
X190840Y747111D01*
X190685Y746843D01*
Y745884D01*
G01Y746843D02*
X189187Y747418D01*
G01Y749751D02*
X189239Y750019D01*
X189394Y750326D01*
X189652Y750518D01*
X190014Y750594D01*
X190375Y750518D01*
X190685Y750288D01*
X190840Y749943D01*
Y749559D01*
X190944Y749329D01*
X191202Y749138D01*
X191564Y749061D01*
X191925Y749176D01*
X192184Y749444D01*
X192287Y749751D01*
X192184Y750058D01*
X191925Y750326D01*
X191564Y750441D01*
X191202Y750364D01*
X190944Y750173D01*
X190840Y749943D01*
Y749559D01*
X190685Y749214D01*
X190375Y748984D01*
X190014Y748908D01*
X189652Y748984D01*
X189394Y749176D01*
X189239Y749483D01*
X189187Y749751D01*
G01Y753311D02*
X192287D01*
X190065Y751893D01*
Y753809D01*
G01X189807Y755108D02*
X189445Y755338D01*
X189239Y755644D01*
X189187Y755989D01*
X189239Y756296D01*
X189497Y756603D01*
X189807Y756794D01*
X190117Y756833D01*
X190479Y756756D01*
X190737Y756488D01*
X190840Y756219D01*
Y755874D01*
G01Y756219D02*
X190995Y756449D01*
X191254Y756641D01*
X191564Y756718D01*
X191874Y756641D01*
X192132Y756449D01*
X192287Y756104D01*
X192235Y755759D01*
X192029Y755414D01*
G01X191540Y743756D02*
X188340D01*
G01X187040D02*
X183840D01*
G01X190947Y758040D02*
X194047D01*
Y758999D01*
X193892Y759305D01*
X193685Y759497D01*
X193272Y759574D01*
X192859Y759497D01*
X192600Y759267D01*
X192445Y758999D01*
Y758040D01*
G01Y758999D02*
X190947Y759574D01*
G01Y761907D02*
X190999Y762175D01*
X191154Y762482D01*
X191412Y762674D01*
X191774Y762750D01*
X192135Y762674D01*
X192445Y762444D01*
X192600Y762099D01*
Y761715D01*
X192704Y761485D01*
X192962Y761294D01*
X193324Y761217D01*
X193685Y761332D01*
X193944Y761600D01*
X194047Y761907D01*
X193944Y762214D01*
X193685Y762482D01*
X193324Y762597D01*
X192962Y762520D01*
X192704Y762329D01*
X192600Y762099D01*
Y761715D01*
X192445Y761370D01*
X192135Y761140D01*
X191774Y761064D01*
X191412Y761140D01*
X191154Y761332D01*
X190999Y761639D01*
X190947Y761907D01*
G01X191412Y764164D02*
X191154Y764394D01*
X190999Y764662D01*
X190947Y765007D01*
X191050Y765352D01*
X191257Y765620D01*
X191619Y765812D01*
X192032Y765850D01*
X192445Y765774D01*
X192704Y765582D01*
X192910Y765314D01*
X192962Y765045D01*
X192910Y764777D01*
X192704Y764432D01*
X194047Y764547D01*
Y765582D01*
G01X192239Y767379D02*
X192600Y767647D01*
X192807Y767877D01*
X192910Y768184D01*
X192807Y768452D01*
X192600Y768644D01*
X192290Y768797D01*
X191929Y768835D01*
X191619Y768797D01*
X191309Y768644D01*
X191050Y768414D01*
X190947Y768145D01*
X191050Y767839D01*
X191360Y767570D01*
X191825Y767417D01*
X192342Y767379D01*
X193014Y767455D01*
X193375Y767570D01*
X193737Y767762D01*
X193995Y768030D01*
X194047Y768299D01*
X193944Y768567D01*
X193685Y768759D01*
G01X186937Y758040D02*
X190037D01*
Y758999D01*
X189882Y759305D01*
X189675Y759497D01*
X189262Y759574D01*
X188849Y759497D01*
X188590Y759267D01*
X188435Y758999D01*
Y758040D01*
G01Y758999D02*
X186937Y759574D01*
G01Y761907D02*
X186989Y762175D01*
X187144Y762482D01*
X187402Y762674D01*
X187764Y762750D01*
X188125Y762674D01*
X188435Y762444D01*
X188590Y762099D01*
Y761715D01*
X188694Y761485D01*
X188952Y761294D01*
X189314Y761217D01*
X189675Y761332D01*
X189934Y761600D01*
X190037Y761907D01*
X189934Y762214D01*
X189675Y762482D01*
X189314Y762597D01*
X188952Y762520D01*
X188694Y762329D01*
X188590Y762099D01*
Y761715D01*
X188435Y761370D01*
X188125Y761140D01*
X187764Y761064D01*
X187402Y761140D01*
X187144Y761332D01*
X186989Y761639D01*
X186937Y761907D01*
G01X187402Y764164D02*
X187144Y764394D01*
X186989Y764662D01*
X186937Y765007D01*
X187040Y765352D01*
X187247Y765620D01*
X187609Y765812D01*
X188022Y765850D01*
X188435Y765774D01*
X188694Y765582D01*
X188900Y765314D01*
X188952Y765045D01*
X188900Y764777D01*
X188694Y764432D01*
X190037Y764547D01*
Y765582D01*
G01X186937Y768030D02*
X187609Y768107D01*
X188177Y768222D01*
X188694Y768375D01*
X189262Y768567D01*
X190037Y768874D01*
Y767340D01*
G01X182437Y758040D02*
X185537D01*
Y758999D01*
X185382Y759305D01*
X185175Y759497D01*
X184762Y759574D01*
X184349Y759497D01*
X184090Y759267D01*
X183935Y758999D01*
Y758040D01*
G01Y758999D02*
X182437Y759574D01*
G01Y761907D02*
X182489Y762175D01*
X182644Y762482D01*
X182902Y762674D01*
X183264Y762750D01*
X183625Y762674D01*
X183935Y762444D01*
X184090Y762099D01*
Y761715D01*
X184194Y761485D01*
X184452Y761294D01*
X184814Y761217D01*
X185175Y761332D01*
X185434Y761600D01*
X185537Y761907D01*
X185434Y762214D01*
X185175Y762482D01*
X184814Y762597D01*
X184452Y762520D01*
X184194Y762329D01*
X184090Y762099D01*
Y761715D01*
X183935Y761370D01*
X183625Y761140D01*
X183264Y761064D01*
X182902Y761140D01*
X182644Y761332D01*
X182489Y761639D01*
X182437Y761907D01*
G01X182902Y764164D02*
X182644Y764394D01*
X182489Y764662D01*
X182437Y765007D01*
X182540Y765352D01*
X182747Y765620D01*
X183109Y765812D01*
X183522Y765850D01*
X183935Y765774D01*
X184194Y765582D01*
X184400Y765314D01*
X184452Y765045D01*
X184400Y764777D01*
X184194Y764432D01*
X185537Y764547D01*
Y765582D01*
G01X182437Y768107D02*
X182489Y768375D01*
X182644Y768682D01*
X182902Y768874D01*
X183264Y768950D01*
X183625Y768874D01*
X183935Y768644D01*
X184090Y768299D01*
Y767915D01*
X184194Y767685D01*
X184452Y767494D01*
X184814Y767417D01*
X185175Y767532D01*
X185434Y767800D01*
X185537Y768107D01*
X185434Y768414D01*
X185175Y768682D01*
X184814Y768797D01*
X184452Y768720D01*
X184194Y768529D01*
X184090Y768299D01*
Y767915D01*
X183935Y767570D01*
X183625Y767340D01*
X183264Y767264D01*
X182902Y767340D01*
X182644Y767532D01*
X182489Y767839D01*
X182437Y768107D01*
G01X194901Y758040D02*
X198001D01*
Y758999D01*
X197846Y759305D01*
X197639Y759497D01*
X197226Y759574D01*
X196813Y759497D01*
X196554Y759267D01*
X196399Y758999D01*
Y758040D01*
G01Y758999D02*
X194901Y759574D01*
G01Y761907D02*
X194953Y762175D01*
X195108Y762482D01*
X195366Y762674D01*
X195728Y762750D01*
X196089Y762674D01*
X196399Y762444D01*
X196554Y762099D01*
Y761715D01*
X196658Y761485D01*
X196916Y761294D01*
X197278Y761217D01*
X197639Y761332D01*
X197898Y761600D01*
X198001Y761907D01*
X197898Y762214D01*
X197639Y762482D01*
X197278Y762597D01*
X196916Y762520D01*
X196658Y762329D01*
X196554Y762099D01*
Y761715D01*
X196399Y761370D01*
X196089Y761140D01*
X195728Y761064D01*
X195366Y761140D01*
X195108Y761332D01*
X194953Y761639D01*
X194901Y761907D01*
G01X195366Y764164D02*
X195108Y764394D01*
X194953Y764662D01*
X194901Y765007D01*
X195004Y765352D01*
X195211Y765620D01*
X195573Y765812D01*
X195986Y765850D01*
X196399Y765774D01*
X196658Y765582D01*
X196864Y765314D01*
X196916Y765045D01*
X196864Y764777D01*
X196658Y764432D01*
X198001Y764547D01*
Y765582D01*
G01X195366Y767264D02*
X195108Y767494D01*
X194953Y767762D01*
X194901Y768107D01*
X195004Y768452D01*
X195211Y768720D01*
X195573Y768912D01*
X195986Y768950D01*
X196399Y768874D01*
X196658Y768682D01*
X196864Y768414D01*
X196916Y768145D01*
X196864Y767877D01*
X196658Y767532D01*
X198001Y767647D01*
Y768682D01*
G01X198790Y126010D02*
Y118710D01*
G01X206323Y116557D02*
Y113357D01*
G01X212523Y116557D02*
X206323D01*
G01Y113357D02*
X212523D01*
G01X213790Y126010D02*
X198790D01*
G01X209532Y139502D02*
X209687Y139272D01*
X209790Y139004D01*
Y138697D01*
X209635Y138352D01*
X209377Y138084D01*
X209067Y137892D01*
X208550Y137739D01*
X208085Y137701D01*
X207620Y137777D01*
X207310Y137892D01*
X207000Y138122D01*
X206793Y138391D01*
X206690Y138659D01*
Y138927D01*
X206793Y139196D01*
X206948Y139426D01*
X207155Y139617D01*
G01X206690Y141759D02*
X209790D01*
X209170Y141299D01*
G01X206690D02*
Y142219D01*
G01Y144859D02*
X209790D01*
X209170Y144399D01*
G01X206690D02*
Y145319D01*
G01X207155Y147116D02*
X206897Y147346D01*
X206742Y147614D01*
X206690Y147959D01*
X206793Y148304D01*
X207000Y148572D01*
X207362Y148764D01*
X207775Y148802D01*
X208188Y148726D01*
X208447Y148534D01*
X208653Y148266D01*
X208705Y147997D01*
X208653Y147729D01*
X208447Y147384D01*
X209790Y147499D01*
Y148534D01*
G01X209437Y152936D02*
X209667Y153091D01*
X209935Y153194D01*
X210242D01*
X210587Y153039D01*
X210855Y152781D01*
X211047Y152471D01*
X211200Y151954D01*
X211238Y151489D01*
X211162Y151024D01*
X211047Y150714D01*
X210817Y150404D01*
X210548Y150197D01*
X210280Y150094D01*
X210012D01*
X209743Y150197D01*
X209513Y150352D01*
X209322Y150559D01*
G01X207180Y150094D02*
Y153194D01*
X207640Y152574D01*
G01Y150094D02*
X206720D01*
G01X204080Y153194D02*
X204387Y153091D01*
X204617Y152832D01*
X204770Y152522D01*
X204885Y152109D01*
X204923Y151644D01*
X204885Y151179D01*
X204770Y150766D01*
X204617Y150456D01*
X204387Y150197D01*
X204080Y150094D01*
X203773Y150197D01*
X203543Y150456D01*
X203390Y150766D01*
X203275Y151179D01*
X203237Y151644D01*
X203275Y152109D01*
X203390Y152522D01*
X203543Y152832D01*
X203773Y153091D01*
X204080Y153194D01*
G01X201823Y150559D02*
X201593Y150301D01*
X201325Y150146D01*
X200980Y150094D01*
X200635Y150197D01*
X200367Y150404D01*
X200175Y150766D01*
X200137Y151179D01*
X200213Y151592D01*
X200405Y151851D01*
X200673Y152057D01*
X200942Y152109D01*
X201210Y152057D01*
X201555Y151851D01*
X201440Y153194D01*
X200405D01*
G01X200912Y166147D02*
X201067Y165917D01*
X201170Y165649D01*
Y165342D01*
X201015Y164997D01*
X200757Y164729D01*
X200447Y164537D01*
X199930Y164384D01*
X199465Y164346D01*
X199000Y164422D01*
X198690Y164537D01*
X198380Y164767D01*
X198173Y165036D01*
X198070Y165304D01*
Y165572D01*
X198173Y165841D01*
X198328Y166071D01*
X198535Y166262D01*
G01X198070Y168404D02*
X201170D01*
X200550Y167944D01*
G01X198070D02*
Y168864D01*
G01X201170Y171504D02*
X201067Y171197D01*
X200808Y170967D01*
X200498Y170814D01*
X200085Y170699D01*
X199620Y170661D01*
X199155Y170699D01*
X198742Y170814D01*
X198432Y170967D01*
X198173Y171197D01*
X198070Y171504D01*
X198173Y171811D01*
X198432Y172041D01*
X198742Y172194D01*
X199155Y172309D01*
X199620Y172347D01*
X200085Y172309D01*
X200498Y172194D01*
X200808Y172041D01*
X201067Y171811D01*
X201170Y171504D01*
G01X199362Y173876D02*
X199723Y174144D01*
X199930Y174374D01*
X200033Y174681D01*
X199930Y174949D01*
X199723Y175141D01*
X199413Y175294D01*
X199052Y175332D01*
X198742Y175294D01*
X198432Y175141D01*
X198173Y174911D01*
X198070Y174642D01*
X198173Y174336D01*
X198483Y174067D01*
X198948Y173914D01*
X199465Y173876D01*
X200137Y173952D01*
X200498Y174067D01*
X200860Y174259D01*
X201118Y174527D01*
X201170Y174796D01*
X201067Y175064D01*
X200808Y175256D01*
G01X209517Y182411D02*
Y185511D01*
X208558D01*
X208252Y185356D01*
X208060Y185149D01*
X207983Y184736D01*
X208060Y184323D01*
X208290Y184064D01*
X208558Y183909D01*
X209517D01*
G01X208558D02*
X207983Y182411D01*
G01X205650D02*
Y185511D01*
X206110Y184891D01*
G01Y182411D02*
X205190D01*
G01X202550Y185511D02*
X202857Y185408D01*
X203087Y185149D01*
X203240Y184839D01*
X203355Y184426D01*
X203393Y183961D01*
X203355Y183496D01*
X203240Y183083D01*
X203087Y182773D01*
X202857Y182514D01*
X202550Y182411D01*
X202243Y182514D01*
X202013Y182773D01*
X201860Y183083D01*
X201745Y183496D01*
X201707Y183961D01*
X201745Y184426D01*
X201860Y184839D01*
X202013Y185149D01*
X202243Y185408D01*
X202550Y185511D01*
G01X199450Y182411D02*
Y185511D01*
X199910Y184891D01*
G01Y182411D02*
X198990D01*
G01X200380Y192371D02*
X200535Y192141D01*
X200638Y191873D01*
Y191566D01*
X200483Y191221D01*
X200225Y190953D01*
X199915Y190761D01*
X199398Y190608D01*
X198933Y190570D01*
X198468Y190646D01*
X198158Y190761D01*
X197848Y190991D01*
X197641Y191260D01*
X197538Y191528D01*
Y191796D01*
X197641Y192065D01*
X197796Y192295D01*
X198003Y192486D01*
G01X198830Y193900D02*
X199191Y194168D01*
X199398Y194398D01*
X199501Y194705D01*
X199398Y194973D01*
X199191Y195165D01*
X198881Y195318D01*
X198520Y195356D01*
X198210Y195318D01*
X197900Y195165D01*
X197641Y194935D01*
X197538Y194666D01*
X197641Y194360D01*
X197951Y194091D01*
X198416Y193938D01*
X198933Y193900D01*
X199605Y193976D01*
X199966Y194091D01*
X200328Y194283D01*
X200586Y194551D01*
X200638Y194820D01*
X200535Y195088D01*
X200276Y195280D01*
G01X198830Y197000D02*
X199191Y197268D01*
X199398Y197498D01*
X199501Y197805D01*
X199398Y198073D01*
X199191Y198265D01*
X198881Y198418D01*
X198520Y198456D01*
X198210Y198418D01*
X197900Y198265D01*
X197641Y198035D01*
X197538Y197766D01*
X197641Y197460D01*
X197951Y197191D01*
X198416Y197038D01*
X198933Y197000D01*
X199605Y197076D01*
X199966Y197191D01*
X200328Y197383D01*
X200586Y197651D01*
X200638Y197920D01*
X200535Y198188D01*
X200276Y198380D01*
G01X208442Y192605D02*
X208597Y192375D01*
X208700Y192107D01*
Y191800D01*
X208545Y191455D01*
X208287Y191187D01*
X207977Y190995D01*
X207460Y190842D01*
X206995Y190804D01*
X206530Y190880D01*
X206220Y190995D01*
X205910Y191225D01*
X205703Y191494D01*
X205600Y191762D01*
Y192030D01*
X205703Y192299D01*
X205858Y192529D01*
X206065Y192720D01*
G01X206892Y194134D02*
X207253Y194402D01*
X207460Y194632D01*
X207563Y194939D01*
X207460Y195207D01*
X207253Y195399D01*
X206943Y195552D01*
X206582Y195590D01*
X206272Y195552D01*
X205962Y195399D01*
X205703Y195169D01*
X205600Y194900D01*
X205703Y194594D01*
X206013Y194325D01*
X206478Y194172D01*
X206995Y194134D01*
X207667Y194210D01*
X208028Y194325D01*
X208390Y194517D01*
X208648Y194785D01*
X208700Y195054D01*
X208597Y195322D01*
X208338Y195514D01*
G01X206065Y197119D02*
X205807Y197349D01*
X205652Y197617D01*
X205600Y197962D01*
X205703Y198307D01*
X205910Y198575D01*
X206272Y198767D01*
X206685Y198805D01*
X207098Y198729D01*
X207357Y198537D01*
X207563Y198269D01*
X207615Y198000D01*
X207563Y197732D01*
X207357Y197387D01*
X208700Y197502D01*
Y198537D01*
G01X204380Y192371D02*
X204535Y192141D01*
X204638Y191873D01*
Y191566D01*
X204483Y191221D01*
X204225Y190953D01*
X203915Y190761D01*
X203398Y190608D01*
X202933Y190570D01*
X202468Y190646D01*
X202158Y190761D01*
X201848Y190991D01*
X201641Y191260D01*
X201538Y191528D01*
Y191796D01*
X201641Y192065D01*
X201796Y192295D01*
X202003Y192486D01*
G01X202830Y193900D02*
X203191Y194168D01*
X203398Y194398D01*
X203501Y194705D01*
X203398Y194973D01*
X203191Y195165D01*
X202881Y195318D01*
X202520Y195356D01*
X202210Y195318D01*
X201900Y195165D01*
X201641Y194935D01*
X201538Y194666D01*
X201641Y194360D01*
X201951Y194091D01*
X202416Y193938D01*
X202933Y193900D01*
X203605Y193976D01*
X203966Y194091D01*
X204328Y194283D01*
X204586Y194551D01*
X204638Y194820D01*
X204535Y195088D01*
X204276Y195280D01*
G01X201538Y198188D02*
X204638D01*
X202416Y196770D01*
Y198686D01*
G01X212380Y192371D02*
X212535Y192141D01*
X212638Y191873D01*
Y191566D01*
X212483Y191221D01*
X212225Y190953D01*
X211915Y190761D01*
X211398Y190608D01*
X210933Y190570D01*
X210468Y190646D01*
X210158Y190761D01*
X209848Y190991D01*
X209641Y191260D01*
X209538Y191528D01*
Y191796D01*
X209641Y192065D01*
X209796Y192295D01*
X210003Y192486D01*
G01X209538Y194628D02*
X209590Y194896D01*
X209745Y195203D01*
X210003Y195395D01*
X210365Y195471D01*
X210726Y195395D01*
X211036Y195165D01*
X211191Y194820D01*
Y194436D01*
X211295Y194206D01*
X211553Y194015D01*
X211915Y193938D01*
X212276Y194053D01*
X212535Y194321D01*
X212638Y194628D01*
X212535Y194935D01*
X212276Y195203D01*
X211915Y195318D01*
X211553Y195241D01*
X211295Y195050D01*
X211191Y194820D01*
Y194436D01*
X211036Y194091D01*
X210726Y193861D01*
X210365Y193785D01*
X210003Y193861D01*
X209745Y194053D01*
X209590Y194360D01*
X209538Y194628D01*
G01Y198188D02*
X212638D01*
X210416Y196770D01*
Y198686D01*
G01X210708Y217685D02*
X210938Y217840D01*
X211206Y217943D01*
X211513D01*
X211858Y217788D01*
X212126Y217530D01*
X212318Y217220D01*
X212471Y216703D01*
X212509Y216238D01*
X212433Y215773D01*
X212318Y215463D01*
X212088Y215153D01*
X211819Y214946D01*
X211551Y214843D01*
X211283D01*
X211014Y214946D01*
X210784Y215101D01*
X210593Y215308D01*
G01X208451Y214843D02*
Y217943D01*
X208911Y217323D01*
G01Y214843D02*
X207991D01*
G01X205351D02*
Y217943D01*
X205811Y217323D01*
G01Y214843D02*
X204891D01*
G01X203094Y215463D02*
X202864Y215101D01*
X202558Y214895D01*
X202213Y214843D01*
X201906Y214895D01*
X201599Y215153D01*
X201408Y215463D01*
X201369Y215773D01*
X201446Y216135D01*
X201714Y216393D01*
X201983Y216496D01*
X202328D01*
G01X201983D02*
X201753Y216651D01*
X201561Y216910D01*
X201484Y217220D01*
X201561Y217530D01*
X201753Y217788D01*
X202098Y217943D01*
X202443Y217891D01*
X202788Y217685D01*
G01X198447Y225517D02*
Y218717D01*
G01D02*
X213447D01*
G01X205947Y225417D02*
Y218817D01*
G01X213447Y225517D02*
X198447D01*
G01X200641Y264200D02*
X198038D01*
G01X206503D02*
X203824D01*
G01X197053Y286321D02*
Y280121D01*
G01D02*
X200253D01*
G01D02*
Y286321D01*
G01X207233Y279209D02*
X201033D01*
G01D02*
Y276009D01*
G01D02*
X207233D01*
G01D02*
Y279209D01*
G01X210947Y295117D02*
X207947D01*
G01X207847Y298217D02*
Y292017D01*
G01D02*
X211047D01*
G01D02*
Y298217D01*
G01X210347Y283017D02*
X216547D01*
G01Y286217D02*
X210347D01*
G01D02*
Y283017D01*
G01X209547D02*
Y286217D01*
G01X206447Y283117D02*
Y286117D01*
G01X209547Y286217D02*
X203347D01*
G01D02*
Y283017D01*
G01D02*
X209547D01*
G01X196247Y302406D02*
Y296206D01*
G01D02*
X199447D01*
G01D02*
Y302406D01*
G01X200253Y286321D02*
X197053D01*
G01X197947Y315117D02*
Y312117D01*
G01X201047Y312017D02*
Y315217D01*
G01X210618Y303017D02*
Y309217D01*
G01D02*
X207418D01*
G01X207518Y306117D02*
X210518D01*
G01X207418Y309217D02*
Y303017D01*
G01D02*
X210618D01*
G01X205047Y309417D02*
X201847D01*
G01X201947Y306317D02*
X204947D01*
G01X205047Y303217D02*
Y309417D01*
G01X201847D02*
Y303217D01*
G01D02*
X205047D01*
G01X201047Y309417D02*
X197847D01*
G01X197947Y306317D02*
X200947D01*
G01X201047Y303217D02*
Y309417D01*
G01X197847D02*
Y303217D01*
G01D02*
X201047D01*
G01X211047Y298217D02*
X207847D01*
G01X211347Y314717D02*
Y311517D01*
G01D02*
X217547D01*
G01Y310717D02*
X211347D01*
G01D02*
Y307517D01*
G01D02*
X217547D01*
G01X210690Y298844D02*
Y302044D01*
G01D02*
X204490D01*
G01D02*
Y298844D01*
G01D02*
X210690D01*
G01X199447Y302406D02*
X196247D01*
G01X210992Y321740D02*
X210918D01*
G01X206880Y325498D02*
Y325479D01*
G01Y328414D02*
Y328378D01*
G01Y325594D02*
Y325848D01*
G01Y328826D02*
Y328887D01*
G01X210992Y321740D02*
X216618D01*
G01X206880Y325594D02*
Y325498D01*
G01Y328826D02*
Y328414D01*
G01X210947Y328617D02*
X213947D01*
G01X210847Y331717D02*
Y325517D01*
G01D02*
X214047D01*
G01X217547Y314717D02*
X211347D01*
G01X201920Y329494D02*
Y323294D01*
G01D02*
X205120D01*
G01D02*
Y329494D01*
G01X198487Y321947D02*
Y328147D01*
G01X208205Y322400D02*
X202005D01*
Y319200D01*
X208205D01*
Y322400D01*
G01X206880Y331442D02*
Y331380D01*
G01Y331442D02*
Y332922D01*
G01X205082Y333690D02*
X205131D01*
G01X205082D02*
X202540D01*
G01X199037D02*
X199258D01*
G01X213632Y334222D02*
X213787Y333992D01*
X213890Y333724D01*
Y333417D01*
X213735Y333072D01*
X213477Y332804D01*
X213167Y332612D01*
X212650Y332459D01*
X212185Y332421D01*
X211720Y332497D01*
X211410Y332612D01*
X211100Y332842D01*
X210893Y333111D01*
X210790Y333379D01*
Y333647D01*
X210893Y333916D01*
X211048Y334146D01*
X211255Y334337D01*
G01X211410Y335636D02*
X211048Y335866D01*
X210842Y336172D01*
X210790Y336517D01*
X210842Y336824D01*
X211100Y337131D01*
X211410Y337322D01*
X211720Y337361D01*
X212082Y337284D01*
X212340Y337016D01*
X212443Y336747D01*
Y336402D01*
G01Y336747D02*
X212598Y336977D01*
X212857Y337169D01*
X213167Y337246D01*
X213477Y337169D01*
X213735Y336977D01*
X213890Y336632D01*
X213838Y336287D01*
X213632Y335942D01*
G01X210790Y339502D02*
X211462Y339579D01*
X212030Y339694D01*
X212547Y339847D01*
X213115Y340039D01*
X213890Y340346D01*
Y338812D01*
G01X214047Y331717D02*
X210847D01*
G01X211247Y341517D02*
Y351717D01*
G01X206647D02*
Y341517D01*
G01D02*
X211247D01*
G01X201029Y329414D02*
Y332614D01*
G01X205120Y329494D02*
X201920D01*
G01X204832Y353753D02*
X204987Y353523D01*
X205090Y353255D01*
Y352948D01*
X204935Y352603D01*
X204677Y352335D01*
X204367Y352143D01*
X203850Y351990D01*
X203385Y351952D01*
X202920Y352028D01*
X202610Y352143D01*
X202300Y352373D01*
X202093Y352642D01*
X201990Y352910D01*
Y353178D01*
X202093Y353447D01*
X202248Y353677D01*
X202455Y353868D01*
G01X202352Y355358D02*
X202093Y355627D01*
X201990Y355933D01*
X202093Y356240D01*
X202403Y356508D01*
X202868Y356700D01*
X203333Y356777D01*
X203902D01*
X204367Y356700D01*
X204780Y356508D01*
X204987Y356278D01*
X205090Y356010D01*
X204987Y355703D01*
X204780Y355473D01*
X204470Y355320D01*
X204057Y355243D01*
X203695Y355320D01*
X203333Y355512D01*
X203127Y355742D01*
X203075Y356010D01*
X203178Y356317D01*
X203437Y356547D01*
X203902Y356777D01*
G01X204573Y358382D02*
X204883Y358612D01*
X205038Y358880D01*
X205090Y359187D01*
X204987Y359570D01*
X204728Y359838D01*
X204418Y359915D01*
X204108Y359877D01*
X203850Y359723D01*
X203333Y358957D01*
X202972Y358612D01*
X202455Y358382D01*
X201990Y358305D01*
Y359915D01*
G01X211247Y351717D02*
X206647D01*
G01Y346617D02*
X211247D01*
G01X195785Y345309D02*
Y351509D01*
G01X228636Y376230D02*
X197543D01*
Y385445D01*
X227947D01*
G01X210287Y377596D02*
Y383796D01*
G01X207087D02*
Y377596D01*
G01D02*
X210287D01*
G01Y383796D02*
X207087D01*
G01X202287Y377596D02*
Y383796D01*
G01D02*
X199087D01*
G01D02*
Y377596D01*
G01D02*
X202287D01*
G01X203087Y383796D02*
Y377596D01*
G01D02*
X206287D01*
G01D02*
Y383796D01*
G01D02*
X203087D01*
G01X214287D02*
X211087D01*
G01D02*
Y377596D01*
G01D02*
X214287D01*
G01X202110Y406296D02*
X205210D01*
Y407255D01*
X205055Y407561D01*
X204848Y407753D01*
X204435Y407830D01*
X204022Y407753D01*
X203763Y407523D01*
X203608Y407255D01*
Y406296D01*
G01Y407255D02*
X202110Y407830D01*
G01X202575Y409320D02*
X202317Y409550D01*
X202162Y409818D01*
X202110Y410163D01*
X202213Y410508D01*
X202420Y410776D01*
X202782Y410968D01*
X203195Y411006D01*
X203608Y410930D01*
X203867Y410738D01*
X204073Y410470D01*
X204125Y410201D01*
X204073Y409933D01*
X203867Y409588D01*
X205210Y409703D01*
Y410738D01*
G01X202110Y413723D02*
X205210D01*
X202988Y412305D01*
Y414221D01*
G01X198110Y406296D02*
X201210D01*
Y407255D01*
X201055Y407561D01*
X200848Y407753D01*
X200435Y407830D01*
X200022Y407753D01*
X199763Y407523D01*
X199608Y407255D01*
Y406296D01*
G01Y407255D02*
X198110Y407830D01*
G01X198575Y409320D02*
X198317Y409550D01*
X198162Y409818D01*
X198110Y410163D01*
X198213Y410508D01*
X198420Y410776D01*
X198782Y410968D01*
X199195Y411006D01*
X199608Y410930D01*
X199867Y410738D01*
X200073Y410470D01*
X200125Y410201D01*
X200073Y409933D01*
X199867Y409588D01*
X201210Y409703D01*
Y410738D01*
G01X198730Y412420D02*
X198368Y412650D01*
X198162Y412956D01*
X198110Y413301D01*
X198162Y413608D01*
X198420Y413915D01*
X198730Y414106D01*
X199040Y414145D01*
X199402Y414068D01*
X199660Y413800D01*
X199763Y413531D01*
Y413186D01*
G01Y413531D02*
X199918Y413761D01*
X200177Y413953D01*
X200487Y414030D01*
X200797Y413953D01*
X201055Y413761D01*
X201210Y413416D01*
X201158Y413071D01*
X200952Y412726D01*
G01X206110Y406296D02*
X209210D01*
Y407255D01*
X209055Y407561D01*
X208848Y407753D01*
X208435Y407830D01*
X208022Y407753D01*
X207763Y407523D01*
X207608Y407255D01*
Y406296D01*
G01Y407255D02*
X206110Y407830D01*
G01Y410163D02*
X209210D01*
X208590Y409703D01*
G01X206110D02*
Y410623D01*
G01Y413723D02*
X209210D01*
X206988Y412305D01*
Y414221D01*
G01X209210Y416363D02*
X209107Y416056D01*
X208848Y415826D01*
X208538Y415673D01*
X208125Y415558D01*
X207660Y415520D01*
X207195Y415558D01*
X206782Y415673D01*
X206472Y415826D01*
X206213Y416056D01*
X206110Y416363D01*
X206213Y416670D01*
X206472Y416900D01*
X206782Y417053D01*
X207195Y417168D01*
X207660Y417206D01*
X208125Y417168D01*
X208538Y417053D01*
X208848Y416900D01*
X209107Y416670D01*
X209210Y416363D01*
G01X209976Y404629D02*
X213076D01*
Y405588D01*
X212921Y405894D01*
X212714Y406086D01*
X212301Y406163D01*
X211888Y406086D01*
X211629Y405856D01*
X211474Y405588D01*
Y404629D01*
G01Y405588D02*
X209976Y406163D01*
G01X211268Y407768D02*
X211629Y408036D01*
X211836Y408266D01*
X211939Y408573D01*
X211836Y408841D01*
X211629Y409033D01*
X211319Y409186D01*
X210958Y409224D01*
X210648Y409186D01*
X210338Y409033D01*
X210079Y408803D01*
X209976Y408534D01*
X210079Y408228D01*
X210389Y407959D01*
X210854Y407806D01*
X211371Y407768D01*
X212043Y407844D01*
X212404Y407959D01*
X212766Y408151D01*
X213024Y408419D01*
X213076Y408688D01*
X212973Y408956D01*
X212714Y409148D01*
G01X213076Y411596D02*
X212973Y411289D01*
X212714Y411059D01*
X212404Y410906D01*
X211991Y410791D01*
X211526Y410753D01*
X211061Y410791D01*
X210648Y410906D01*
X210338Y411059D01*
X210079Y411289D01*
X209976Y411596D01*
X210079Y411903D01*
X210338Y412133D01*
X210648Y412286D01*
X211061Y412401D01*
X211526Y412439D01*
X211991Y412401D01*
X212404Y412286D01*
X212714Y412133D01*
X212973Y411903D01*
X213076Y411596D01*
G01X198689Y446813D02*
Y454213D01*
G01X220650Y480680D02*
X209820D01*
G01X201640Y476520D02*
X197210D01*
G01X209820D02*
X205860D01*
G01X197210D02*
Y488020D01*
G01X209820Y480680D02*
Y476520D01*
G01X206609Y481753D02*
X209809D01*
G01X206609Y487953D02*
Y481753D01*
G01X209709Y484853D02*
X206709D01*
G01X209809Y481753D02*
Y487953D01*
G01X211109Y481753D02*
X214309D01*
G01X211109Y487953D02*
Y481753D01*
G01X214209Y484853D02*
X211209D01*
G01X201009Y489453D02*
Y479253D01*
G01X206009D02*
Y489453D01*
G01X201009Y479253D02*
X206009D01*
G01X201209Y484853D02*
X205809D01*
G01X201209Y483853D02*
X205809D01*
G01X197210Y491800D02*
Y498870D01*
G01D02*
X211630D01*
G01X209809Y487953D02*
X206609D01*
G01X214309D02*
X211109D01*
G01X200812Y490351D02*
X211012D01*
G01X200812Y494951D02*
Y490351D01*
G01X211012Y494951D02*
X200812D01*
G01X205912D02*
Y490351D01*
G01X211012D02*
Y494951D01*
G01X201009Y489453D02*
X206009D01*
G01X212767Y526662D02*
X212997Y526817D01*
X213265Y526920D01*
X213572D01*
X213917Y526765D01*
X214185Y526507D01*
X214377Y526197D01*
X214530Y525680D01*
X214568Y525215D01*
X214492Y524750D01*
X214377Y524440D01*
X214147Y524130D01*
X213878Y523923D01*
X213610Y523820D01*
X213342D01*
X213073Y523923D01*
X212843Y524078D01*
X212652Y524285D01*
G01X211238Y526403D02*
X211008Y526713D01*
X210740Y526868D01*
X210433Y526920D01*
X210050Y526817D01*
X209782Y526558D01*
X209705Y526248D01*
X209743Y525938D01*
X209897Y525680D01*
X210663Y525163D01*
X211008Y524802D01*
X211238Y524285D01*
X211315Y523820D01*
X209705D01*
G01X207410Y526920D02*
X207717Y526817D01*
X207947Y526558D01*
X208100Y526248D01*
X208215Y525835D01*
X208253Y525370D01*
X208215Y524905D01*
X208100Y524492D01*
X207947Y524182D01*
X207717Y523923D01*
X207410Y523820D01*
X207103Y523923D01*
X206873Y524182D01*
X206720Y524492D01*
X206605Y524905D01*
X206567Y525370D01*
X206605Y525835D01*
X206720Y526248D01*
X206873Y526558D01*
X207103Y526817D01*
X207410Y526920D01*
G01X203850Y523820D02*
Y526920D01*
X205268Y524698D01*
X203352D01*
G01X209898Y523067D02*
Y519867D01*
G01X216098Y523067D02*
X209898D01*
G01Y519867D02*
X216098D01*
G01X217001Y561759D02*
Y564859D01*
X216042D01*
X215736Y564704D01*
X215544Y564497D01*
X215467Y564084D01*
X215544Y563671D01*
X215774Y563412D01*
X216042Y563257D01*
X217001D01*
G01X216042D02*
X215467Y561759D01*
G01X213862Y563051D02*
X213594Y563412D01*
X213364Y563619D01*
X213057Y563722D01*
X212789Y563619D01*
X212597Y563412D01*
X212444Y563102D01*
X212406Y562741D01*
X212444Y562431D01*
X212597Y562121D01*
X212827Y561862D01*
X213096Y561759D01*
X213402Y561862D01*
X213671Y562172D01*
X213824Y562637D01*
X213862Y563154D01*
X213786Y563826D01*
X213671Y564187D01*
X213479Y564549D01*
X213211Y564807D01*
X212942Y564859D01*
X212674Y564756D01*
X212482Y564497D01*
G01X210111Y561759D02*
X210034Y562431D01*
X209919Y562999D01*
X209766Y563516D01*
X209574Y564084D01*
X209267Y564859D01*
X210801D01*
G01X207777Y562224D02*
X207547Y561966D01*
X207279Y561811D01*
X206934Y561759D01*
X206589Y561862D01*
X206321Y562069D01*
X206129Y562431D01*
X206091Y562844D01*
X206167Y563257D01*
X206359Y563516D01*
X206627Y563722D01*
X206896Y563774D01*
X207164Y563722D01*
X207509Y563516D01*
X207394Y564859D01*
X206359D01*
G01X217048Y557800D02*
Y560900D01*
X216089D01*
X215783Y560745D01*
X215591Y560538D01*
X215514Y560125D01*
X215591Y559712D01*
X215821Y559453D01*
X216089Y559298D01*
X217048D01*
G01X216089D02*
X215514Y557800D01*
G01X213909Y559092D02*
X213641Y559453D01*
X213411Y559660D01*
X213104Y559763D01*
X212836Y559660D01*
X212644Y559453D01*
X212491Y559143D01*
X212453Y558782D01*
X212491Y558472D01*
X212644Y558162D01*
X212874Y557903D01*
X213143Y557800D01*
X213449Y557903D01*
X213718Y558213D01*
X213871Y558678D01*
X213909Y559195D01*
X213833Y559867D01*
X213718Y560228D01*
X213526Y560590D01*
X213258Y560848D01*
X212989Y560900D01*
X212721Y560797D01*
X212529Y560538D01*
G01X210158Y557800D02*
X210081Y558472D01*
X209966Y559040D01*
X209813Y559557D01*
X209621Y560125D01*
X209314Y560900D01*
X210848D01*
G01X206981D02*
X207288Y560797D01*
X207518Y560538D01*
X207671Y560228D01*
X207786Y559815D01*
X207824Y559350D01*
X207786Y558885D01*
X207671Y558472D01*
X207518Y558162D01*
X207288Y557903D01*
X206981Y557800D01*
X206674Y557903D01*
X206444Y558162D01*
X206291Y558472D01*
X206176Y558885D01*
X206138Y559350D01*
X206176Y559815D01*
X206291Y560228D01*
X206444Y560538D01*
X206674Y560797D01*
X206981Y560900D01*
G01X209540Y678556D02*
X225340D01*
G01X209540Y709756D02*
Y678556D01*
G01X198540Y706556D02*
Y709756D01*
G01X215140D02*
X209540D01*
G01X196040Y713373D02*
Y719573D01*
G01X206340Y713406D02*
X209540D01*
G01X206340Y719606D02*
Y713406D01*
G01X209540Y719606D02*
X206340D01*
G01X206440Y716506D02*
X209440D01*
G01X209540Y713406D02*
Y719606D01*
G01X201840Y713373D02*
X205040D01*
G01X201840Y719573D02*
Y713373D01*
G01X205040Y719573D02*
X201840D01*
G01X205040Y713373D02*
Y719573D01*
G01X201940Y716473D02*
X204940D01*
G01X197340Y713406D02*
X200540D01*
G01X197340Y719606D02*
Y713406D01*
G01X200540Y719606D02*
X197340D01*
G01X200540Y713406D02*
Y719606D01*
G01X197440Y716506D02*
X200440D01*
G01X210840Y737556D02*
X214040D01*
G01X210840Y743756D02*
Y737556D01*
G01X196040D02*
Y743756D01*
G01Y726056D02*
Y732256D01*
G01X206340Y737556D02*
X209540D01*
G01X206340Y743756D02*
Y737556D01*
G01X209540D02*
Y743756D01*
G01X201840Y737556D02*
X205040D01*
G01X201840Y743756D02*
Y737556D01*
G01X205040D02*
Y743756D01*
G01X197340Y737556D02*
X200540D01*
G01X197340Y743756D02*
Y737556D01*
G01X200540D02*
Y743756D01*
G01X206340Y726056D02*
X209540D01*
G01X206340Y732256D02*
Y726056D01*
G01X209540Y732256D02*
X206340D01*
G01X209540Y726056D02*
Y732256D01*
G01X201840Y726056D02*
X205040D01*
G01X201840Y732256D02*
Y726056D01*
G01X205040Y732256D02*
X201840D01*
G01X205040Y726056D02*
Y732256D01*
G01X197340Y726056D02*
X200540D01*
G01X197340Y732256D02*
Y726056D01*
G01X200540Y732256D02*
X197340D01*
G01X200540Y726056D02*
Y732256D01*
G01X214040D02*
X210840D01*
G01Y726056D02*
X214040D01*
G01X210840Y732256D02*
Y726056D01*
G01X214040Y743756D02*
X210840D01*
G01X210940Y740656D02*
X213940D01*
G01X209540Y743756D02*
X206340D01*
G01X205040D02*
X201840D01*
G01X200540D02*
X197340D01*
G01X207187Y745884D02*
X210287D01*
Y746843D01*
X210132Y747149D01*
X209925Y747341D01*
X209512Y747418D01*
X209099Y747341D01*
X208840Y747111D01*
X208685Y746843D01*
Y745884D01*
G01Y746843D02*
X207187Y747418D01*
G01Y749751D02*
X207239Y750019D01*
X207394Y750326D01*
X207652Y750518D01*
X208014Y750594D01*
X208375Y750518D01*
X208685Y750288D01*
X208840Y749943D01*
Y749559D01*
X208944Y749329D01*
X209202Y749138D01*
X209564Y749061D01*
X209925Y749176D01*
X210184Y749444D01*
X210287Y749751D01*
X210184Y750058D01*
X209925Y750326D01*
X209564Y750441D01*
X209202Y750364D01*
X208944Y750173D01*
X208840Y749943D01*
Y749559D01*
X208685Y749214D01*
X208375Y748984D01*
X208014Y748908D01*
X207652Y748984D01*
X207394Y749176D01*
X207239Y749483D01*
X207187Y749751D01*
G01X207807Y752008D02*
X207445Y752238D01*
X207239Y752544D01*
X207187Y752889D01*
X207239Y753196D01*
X207497Y753503D01*
X207807Y753694D01*
X208117Y753733D01*
X208479Y753656D01*
X208737Y753388D01*
X208840Y753119D01*
Y752774D01*
G01Y753119D02*
X208995Y753349D01*
X209254Y753541D01*
X209564Y753618D01*
X209874Y753541D01*
X210132Y753349D01*
X210287Y753004D01*
X210235Y752659D01*
X210029Y752314D01*
G01X209770Y755223D02*
X210080Y755453D01*
X210235Y755721D01*
X210287Y756028D01*
X210184Y756411D01*
X209925Y756679D01*
X209615Y756756D01*
X209305Y756718D01*
X209047Y756564D01*
X208530Y755798D01*
X208169Y755453D01*
X207652Y755223D01*
X207187Y755146D01*
Y756756D01*
G01X202871Y745884D02*
X205971D01*
Y746843D01*
X205816Y747149D01*
X205609Y747341D01*
X205196Y747418D01*
X204783Y747341D01*
X204524Y747111D01*
X204369Y746843D01*
Y745884D01*
G01Y746843D02*
X202871Y747418D01*
G01Y749751D02*
X202923Y750019D01*
X203078Y750326D01*
X203336Y750518D01*
X203698Y750594D01*
X204059Y750518D01*
X204369Y750288D01*
X204524Y749943D01*
Y749559D01*
X204628Y749329D01*
X204886Y749138D01*
X205248Y749061D01*
X205609Y749176D01*
X205868Y749444D01*
X205971Y749751D01*
X205868Y750058D01*
X205609Y750326D01*
X205248Y750441D01*
X204886Y750364D01*
X204628Y750173D01*
X204524Y749943D01*
Y749559D01*
X204369Y749214D01*
X204059Y748984D01*
X203698Y748908D01*
X203336Y748984D01*
X203078Y749176D01*
X202923Y749483D01*
X202871Y749751D01*
G01X203491Y752008D02*
X203129Y752238D01*
X202923Y752544D01*
X202871Y752889D01*
X202923Y753196D01*
X203181Y753503D01*
X203491Y753694D01*
X203801Y753733D01*
X204163Y753656D01*
X204421Y753388D01*
X204524Y753119D01*
Y752774D01*
G01Y753119D02*
X204679Y753349D01*
X204938Y753541D01*
X205248Y753618D01*
X205558Y753541D01*
X205816Y753349D01*
X205971Y753004D01*
X205919Y752659D01*
X205713Y752314D01*
G01X202871Y756411D02*
X205971D01*
X203749Y754993D01*
Y756909D01*
G01X198187Y745884D02*
X201287D01*
Y746843D01*
X201132Y747149D01*
X200925Y747341D01*
X200512Y747418D01*
X200099Y747341D01*
X199840Y747111D01*
X199685Y746843D01*
Y745884D01*
G01Y746843D02*
X198187Y747418D01*
G01Y749751D02*
X198239Y750019D01*
X198394Y750326D01*
X198652Y750518D01*
X199014Y750594D01*
X199375Y750518D01*
X199685Y750288D01*
X199840Y749943D01*
Y749559D01*
X199944Y749329D01*
X200202Y749138D01*
X200564Y749061D01*
X200925Y749176D01*
X201184Y749444D01*
X201287Y749751D01*
X201184Y750058D01*
X200925Y750326D01*
X200564Y750441D01*
X200202Y750364D01*
X199944Y750173D01*
X199840Y749943D01*
Y749559D01*
X199685Y749214D01*
X199375Y748984D01*
X199014Y748908D01*
X198652Y748984D01*
X198394Y749176D01*
X198239Y749483D01*
X198187Y749751D01*
G01X198807Y752008D02*
X198445Y752238D01*
X198239Y752544D01*
X198187Y752889D01*
X198239Y753196D01*
X198497Y753503D01*
X198807Y753694D01*
X199117Y753733D01*
X199479Y753656D01*
X199737Y753388D01*
X199840Y753119D01*
Y752774D01*
G01Y753119D02*
X199995Y753349D01*
X200254Y753541D01*
X200564Y753618D01*
X200874Y753541D01*
X201132Y753349D01*
X201287Y753004D01*
X201235Y752659D01*
X201029Y752314D01*
G01X198187Y755874D02*
X198859Y755951D01*
X199427Y756066D01*
X199944Y756219D01*
X200512Y756411D01*
X201287Y756718D01*
Y755184D01*
G01X211521Y745884D02*
X214621D01*
Y746843D01*
X214466Y747149D01*
X214259Y747341D01*
X213846Y747418D01*
X213433Y747341D01*
X213174Y747111D01*
X213019Y746843D01*
Y745884D01*
G01Y746843D02*
X211521Y747418D01*
G01X211883Y749099D02*
X211624Y749368D01*
X211521Y749674D01*
X211624Y749981D01*
X211934Y750249D01*
X212399Y750441D01*
X212864Y750518D01*
X213433D01*
X213898Y750441D01*
X214311Y750249D01*
X214518Y750019D01*
X214621Y749751D01*
X214518Y749444D01*
X214311Y749214D01*
X214001Y749061D01*
X213588Y748984D01*
X213226Y749061D01*
X212864Y749253D01*
X212658Y749483D01*
X212606Y749751D01*
X212709Y750058D01*
X212968Y750288D01*
X213433Y750518D01*
G01X211521Y752851D02*
X214621D01*
X214001Y752391D01*
G01X211521D02*
Y753311D01*
G01X214621Y755951D02*
X214518Y755644D01*
X214259Y755414D01*
X213949Y755261D01*
X213536Y755146D01*
X213071Y755108D01*
X212606Y755146D01*
X212193Y755261D01*
X211883Y755414D01*
X211624Y755644D01*
X211521Y755951D01*
X211624Y756258D01*
X211883Y756488D01*
X212193Y756641D01*
X212606Y756756D01*
X213071Y756794D01*
X213536Y756756D01*
X213949Y756641D01*
X214259Y756488D01*
X214518Y756258D01*
X214621Y755951D01*
G01X214293Y759486D02*
X214448Y759256D01*
X214551Y758988D01*
Y758681D01*
X214396Y758336D01*
X214138Y758068D01*
X213828Y757876D01*
X213311Y757723D01*
X212846Y757685D01*
X212381Y757761D01*
X212071Y757876D01*
X211761Y758106D01*
X211554Y758375D01*
X211451Y758643D01*
Y758911D01*
X211554Y759180D01*
X211709Y759410D01*
X211916Y759601D01*
G01X212743Y761015D02*
X213104Y761283D01*
X213311Y761513D01*
X213414Y761820D01*
X213311Y762088D01*
X213104Y762280D01*
X212794Y762433D01*
X212433Y762471D01*
X212123Y762433D01*
X211813Y762280D01*
X211554Y762050D01*
X211451Y761781D01*
X211554Y761475D01*
X211864Y761206D01*
X212329Y761053D01*
X212846Y761015D01*
X213518Y761091D01*
X213879Y761206D01*
X214241Y761398D01*
X214499Y761666D01*
X214551Y761935D01*
X214448Y762203D01*
X214189Y762395D01*
G01X211451Y764766D02*
X212123Y764843D01*
X212691Y764958D01*
X213208Y765111D01*
X213776Y765303D01*
X214551Y765610D01*
Y764076D01*
G01X212071Y767100D02*
X211709Y767330D01*
X211503Y767636D01*
X211451Y767981D01*
X211503Y768288D01*
X211761Y768595D01*
X212071Y768786D01*
X212381Y768825D01*
X212743Y768748D01*
X213001Y768480D01*
X213104Y768211D01*
Y767866D01*
G01Y768211D02*
X213259Y768441D01*
X213518Y768633D01*
X213828Y768710D01*
X214138Y768633D01*
X214396Y768441D01*
X214551Y768096D01*
X214499Y767751D01*
X214293Y767406D01*
G01X207641Y758122D02*
X210741D01*
Y759081D01*
X210586Y759387D01*
X210379Y759579D01*
X209966Y759656D01*
X209553Y759579D01*
X209294Y759349D01*
X209139Y759081D01*
Y758122D01*
G01Y759081D02*
X207641Y759656D01*
G01Y761989D02*
X207693Y762257D01*
X207848Y762564D01*
X208106Y762756D01*
X208468Y762832D01*
X208829Y762756D01*
X209139Y762526D01*
X209294Y762181D01*
Y761797D01*
X209398Y761567D01*
X209656Y761376D01*
X210018Y761299D01*
X210379Y761414D01*
X210638Y761682D01*
X210741Y761989D01*
X210638Y762296D01*
X210379Y762564D01*
X210018Y762679D01*
X209656Y762602D01*
X209398Y762411D01*
X209294Y762181D01*
Y761797D01*
X209139Y761452D01*
X208829Y761222D01*
X208468Y761146D01*
X208106Y761222D01*
X207848Y761414D01*
X207693Y761721D01*
X207641Y761989D01*
G01X208106Y764246D02*
X207848Y764476D01*
X207693Y764744D01*
X207641Y765089D01*
X207744Y765434D01*
X207951Y765702D01*
X208313Y765894D01*
X208726Y765932D01*
X209139Y765856D01*
X209398Y765664D01*
X209604Y765396D01*
X209656Y765127D01*
X209604Y764859D01*
X209398Y764514D01*
X210741Y764629D01*
Y765664D01*
G01X208261Y767346D02*
X207899Y767576D01*
X207693Y767882D01*
X207641Y768227D01*
X207693Y768534D01*
X207951Y768841D01*
X208261Y769032D01*
X208571Y769071D01*
X208933Y768994D01*
X209191Y768726D01*
X209294Y768457D01*
Y768112D01*
G01Y768457D02*
X209449Y768687D01*
X209708Y768879D01*
X210018Y768956D01*
X210328Y768879D01*
X210586Y768687D01*
X210741Y768342D01*
X210689Y767997D01*
X210483Y767652D01*
G01X203221Y758122D02*
X206321D01*
Y759081D01*
X206166Y759387D01*
X205959Y759579D01*
X205546Y759656D01*
X205133Y759579D01*
X204874Y759349D01*
X204719Y759081D01*
Y758122D01*
G01Y759081D02*
X203221Y759656D01*
G01Y761989D02*
X203273Y762257D01*
X203428Y762564D01*
X203686Y762756D01*
X204048Y762832D01*
X204409Y762756D01*
X204719Y762526D01*
X204874Y762181D01*
Y761797D01*
X204978Y761567D01*
X205236Y761376D01*
X205598Y761299D01*
X205959Y761414D01*
X206218Y761682D01*
X206321Y761989D01*
X206218Y762296D01*
X205959Y762564D01*
X205598Y762679D01*
X205236Y762602D01*
X204978Y762411D01*
X204874Y762181D01*
Y761797D01*
X204719Y761452D01*
X204409Y761222D01*
X204048Y761146D01*
X203686Y761222D01*
X203428Y761414D01*
X203273Y761721D01*
X203221Y761989D01*
G01X203686Y764246D02*
X203428Y764476D01*
X203273Y764744D01*
X203221Y765089D01*
X203324Y765434D01*
X203531Y765702D01*
X203893Y765894D01*
X204306Y765932D01*
X204719Y765856D01*
X204978Y765664D01*
X205184Y765396D01*
X205236Y765127D01*
X205184Y764859D01*
X204978Y764514D01*
X206321Y764629D01*
Y765664D01*
G01X203221Y768649D02*
X206321D01*
X204099Y767231D01*
Y769147D01*
G01X226265Y83029D02*
Y86229D01*
G01D02*
X220065D01*
G01D02*
Y83029D01*
G01D02*
X226265D01*
G01X225087Y113850D02*
Y116950D01*
X224128D01*
X223822Y116795D01*
X223630Y116588D01*
X223553Y116175D01*
X223630Y115762D01*
X223860Y115503D01*
X224128Y115348D01*
X225087D01*
G01X224128D02*
X223553Y113850D01*
G01X221948Y116433D02*
X221718Y116743D01*
X221450Y116898D01*
X221143Y116950D01*
X220760Y116847D01*
X220492Y116588D01*
X220415Y116278D01*
X220453Y115968D01*
X220607Y115710D01*
X221373Y115193D01*
X221718Y114832D01*
X221948Y114315D01*
X222025Y113850D01*
X220415D01*
G01X218120D02*
Y116950D01*
X218580Y116330D01*
G01Y113850D02*
X217660D01*
G01X215020Y116950D02*
X215327Y116847D01*
X215557Y116588D01*
X215710Y116278D01*
X215825Y115865D01*
X215863Y115400D01*
X215825Y114935D01*
X215710Y114522D01*
X215557Y114212D01*
X215327Y113953D01*
X215020Y113850D01*
X214713Y113953D01*
X214483Y114212D01*
X214330Y114522D01*
X214215Y114935D01*
X214177Y115400D01*
X214215Y115865D01*
X214330Y116278D01*
X214483Y116588D01*
X214713Y116847D01*
X215020Y116950D01*
G01X212523Y113357D02*
Y116557D01*
G01X213790Y182080D02*
Y126010D01*
G01X262360Y182080D02*
X213790D01*
G01X216380Y192371D02*
X216535Y192141D01*
X216638Y191873D01*
Y191566D01*
X216483Y191221D01*
X216225Y190953D01*
X215915Y190761D01*
X215398Y190608D01*
X214933Y190570D01*
X214468Y190646D01*
X214158Y190761D01*
X213848Y190991D01*
X213641Y191260D01*
X213538Y191528D01*
Y191796D01*
X213641Y192065D01*
X213796Y192295D01*
X214003Y192486D01*
G01X214830Y193900D02*
X215191Y194168D01*
X215398Y194398D01*
X215501Y194705D01*
X215398Y194973D01*
X215191Y195165D01*
X214881Y195318D01*
X214520Y195356D01*
X214210Y195318D01*
X213900Y195165D01*
X213641Y194935D01*
X213538Y194666D01*
X213641Y194360D01*
X213951Y194091D01*
X214416Y193938D01*
X214933Y193900D01*
X215605Y193976D01*
X215966Y194091D01*
X216328Y194283D01*
X216586Y194551D01*
X216638Y194820D01*
X216535Y195088D01*
X216276Y195280D01*
G01X213538Y197651D02*
X214210Y197728D01*
X214778Y197843D01*
X215295Y197996D01*
X215863Y198188D01*
X216638Y198495D01*
Y196961D01*
G01X220380Y192371D02*
X220535Y192141D01*
X220638Y191873D01*
Y191566D01*
X220483Y191221D01*
X220225Y190953D01*
X219915Y190761D01*
X219398Y190608D01*
X218933Y190570D01*
X218468Y190646D01*
X218158Y190761D01*
X217848Y190991D01*
X217641Y191260D01*
X217538Y191528D01*
Y191796D01*
X217641Y192065D01*
X217796Y192295D01*
X218003Y192486D01*
G01X217538Y194551D02*
X218210Y194628D01*
X218778Y194743D01*
X219295Y194896D01*
X219863Y195088D01*
X220638Y195395D01*
Y193861D01*
G01X217538Y197728D02*
X220638D01*
X220018Y197268D01*
G01X217538D02*
Y198188D01*
G01X228380Y192371D02*
X228535Y192141D01*
X228638Y191873D01*
Y191566D01*
X228483Y191221D01*
X228225Y190953D01*
X227915Y190761D01*
X227398Y190608D01*
X226933Y190570D01*
X226468Y190646D01*
X226158Y190761D01*
X225848Y190991D01*
X225641Y191260D01*
X225538Y191528D01*
Y191796D01*
X225641Y192065D01*
X225796Y192295D01*
X226003Y192486D01*
G01X225538Y194551D02*
X226210Y194628D01*
X226778Y194743D01*
X227295Y194896D01*
X227863Y195088D01*
X228638Y195395D01*
Y193861D01*
G01X226158Y196885D02*
X225796Y197115D01*
X225590Y197421D01*
X225538Y197766D01*
X225590Y198073D01*
X225848Y198380D01*
X226158Y198571D01*
X226468Y198610D01*
X226830Y198533D01*
X227088Y198265D01*
X227191Y197996D01*
Y197651D01*
G01Y197996D02*
X227346Y198226D01*
X227605Y198418D01*
X227915Y198495D01*
X228225Y198418D01*
X228483Y198226D01*
X228638Y197881D01*
X228586Y197536D01*
X228380Y197191D01*
G01X224380Y192371D02*
X224535Y192141D01*
X224638Y191873D01*
Y191566D01*
X224483Y191221D01*
X224225Y190953D01*
X223915Y190761D01*
X223398Y190608D01*
X222933Y190570D01*
X222468Y190646D01*
X222158Y190761D01*
X221848Y190991D01*
X221641Y191260D01*
X221538Y191528D01*
Y191796D01*
X221641Y192065D01*
X221796Y192295D01*
X222003Y192486D01*
G01X221538Y194551D02*
X222210Y194628D01*
X222778Y194743D01*
X223295Y194896D01*
X223863Y195088D01*
X224638Y195395D01*
Y193861D01*
G01X224121Y197000D02*
X224431Y197230D01*
X224586Y197498D01*
X224638Y197805D01*
X224535Y198188D01*
X224276Y198456D01*
X223966Y198533D01*
X223656Y198495D01*
X223398Y198341D01*
X222881Y197575D01*
X222520Y197230D01*
X222003Y197000D01*
X221538Y196923D01*
Y198533D01*
G01X213447Y218717D02*
Y225517D01*
G01X231522Y218501D02*
X225322D01*
G01D02*
Y215301D01*
G01D02*
X231522D01*
G01X222792Y222135D02*
X222947Y221905D01*
X223050Y221637D01*
Y221330D01*
X222895Y220985D01*
X222637Y220717D01*
X222327Y220525D01*
X221810Y220372D01*
X221345Y220334D01*
X220880Y220410D01*
X220570Y220525D01*
X220260Y220755D01*
X220053Y221024D01*
X219950Y221292D01*
Y221560D01*
X220053Y221829D01*
X220208Y222059D01*
X220415Y222250D01*
G01X219950Y224392D02*
X223050D01*
X222430Y223932D01*
G01X219950D02*
Y224852D01*
G01Y227492D02*
X223050D01*
X222430Y227032D01*
G01X219950D02*
Y227952D01*
G01Y230515D02*
X220622Y230592D01*
X221190Y230707D01*
X221707Y230860D01*
X222275Y231052D01*
X223050Y231359D01*
Y229825D01*
G01X223021Y232446D02*
Y238646D01*
G01X219821Y232446D02*
X223021D01*
G01X219821Y238646D02*
Y232446D01*
G01X231522Y222501D02*
X225322D01*
G01D02*
Y219301D01*
G01D02*
X231522D01*
G01X211430Y246122D02*
Y254204D01*
G01Y242346D02*
Y242827D01*
G01X215398Y239920D02*
X213460D01*
G01X224083D02*
X218655D01*
G01X226547Y242017D02*
Y245217D01*
G01D02*
X220347D01*
G01X223447Y245117D02*
Y242117D01*
G01X220347Y242017D02*
X226547D01*
G01X220347Y245217D02*
Y242017D01*
G01X222921Y235546D02*
X219921D01*
G01X223021Y238646D02*
X219821D01*
G01X226970Y249919D02*
Y253119D01*
G01X220770Y249919D02*
X226970D01*
G01X220770Y253119D02*
Y249919D01*
G01X226970Y245919D02*
Y249119D01*
G01D02*
X220770D01*
G01D02*
Y245919D01*
G01D02*
X226970D01*
G01X219164Y245279D02*
Y251479D01*
G01X215964D02*
Y245279D01*
G01D02*
X219164D01*
G01X211430Y260978D02*
Y261335D01*
G01Y263482D02*
Y263742D01*
G01Y257017D02*
Y257992D01*
G01X222518Y264487D02*
Y274687D01*
G01X217918D02*
Y264487D01*
G01D02*
X222518D01*
G01X226970Y253119D02*
X220770D01*
G01X219164Y251479D02*
X215964D01*
G01X225618Y275387D02*
Y278587D01*
G01X222518Y275487D02*
Y278487D01*
G01X225618Y278587D02*
X219418D01*
G01D02*
Y275387D01*
G01D02*
X225618D01*
G01X211765Y269705D02*
X214765D01*
G01X214865Y266605D02*
Y272805D01*
G01D02*
X211665D01*
G01D02*
Y266605D01*
G01D02*
X214865D01*
G01X225495Y270582D02*
X228495D01*
G01X228595Y273682D02*
X225395D01*
G01D02*
Y267482D01*
G01D02*
X228595D01*
G01X222518Y274687D02*
X217918D01*
G01X222518Y269587D02*
X217918D01*
G01X223618Y279387D02*
Y285587D01*
G01X220418D02*
Y279387D01*
G01D02*
X223618D01*
G01X215147Y275967D02*
Y279167D01*
G01X215847Y275967D02*
Y279167D01*
G01X218597D02*
X212397D01*
G01D02*
Y275967D01*
G01D02*
X218597D01*
G01D02*
Y279167D01*
G01X213447Y286117D02*
Y283117D01*
G01X216547Y283017D02*
Y286217D01*
G01X219750Y298531D02*
Y295531D01*
G01X216650Y295431D02*
X222850D01*
G01D02*
Y298631D01*
G01X216650D02*
Y295431D01*
G01X219725Y294588D02*
Y291588D01*
G01X216625Y291488D02*
X222825D01*
G01D02*
Y294688D01*
G01D02*
X216625D01*
G01D02*
Y291488D01*
G01X226908Y292803D02*
X229908D01*
G01X230008Y295903D02*
X226808D01*
G01D02*
Y289703D01*
G01D02*
X230008D01*
G01X229939Y285838D02*
X226939D01*
G01X226839Y288938D02*
Y282738D01*
G01D02*
X230039D01*
G01Y288938D02*
X226839D01*
G01X220418Y282837D02*
X223618D01*
G01X220418Y282137D02*
X223618D01*
G01Y285587D02*
X220418D01*
G01X214447Y311617D02*
Y314617D01*
G01X217547Y311517D02*
Y314717D01*
G01X214447Y307617D02*
Y310617D01*
G01X217547Y307517D02*
Y310717D01*
G01X214018Y303617D02*
X217018D01*
G01X217118Y300517D02*
Y306717D01*
G01D02*
X213918D01*
G01D02*
Y300517D01*
G01D02*
X217118D01*
G01X226447Y311117D02*
X229447D01*
G01X226347Y314217D02*
Y308017D01*
G01D02*
X229547D01*
G01X229212Y301195D02*
X226212D01*
G01X226112Y304295D02*
Y298095D01*
G01D02*
X229312D01*
G01Y304295D02*
X226112D01*
G01X222850Y298631D02*
X216650D01*
G01X223130Y321740D02*
X223800D01*
G01X225630D02*
X226766D01*
G01X217432D02*
X217075D01*
G01X216618D02*
X217001D01*
G01X214047Y325517D02*
Y331717D01*
G01X221437Y330934D02*
X221592Y330704D01*
X221695Y330436D01*
Y330129D01*
X221540Y329784D01*
X221282Y329516D01*
X220972Y329324D01*
X220455Y329171D01*
X219990Y329133D01*
X219525Y329209D01*
X219215Y329324D01*
X218905Y329554D01*
X218698Y329823D01*
X218595Y330091D01*
Y330359D01*
X218698Y330628D01*
X218853Y330858D01*
X219060Y331049D01*
G01X219215Y332348D02*
X218853Y332578D01*
X218647Y332884D01*
X218595Y333229D01*
X218647Y333536D01*
X218905Y333843D01*
X219215Y334034D01*
X219525Y334073D01*
X219887Y333996D01*
X220145Y333728D01*
X220248Y333459D01*
Y333114D01*
G01Y333459D02*
X220403Y333689D01*
X220662Y333881D01*
X220972Y333958D01*
X221282Y333881D01*
X221540Y333689D01*
X221695Y333344D01*
X221643Y332999D01*
X221437Y332654D01*
G01X218595Y336291D02*
X218647Y336559D01*
X218802Y336866D01*
X219060Y337058D01*
X219422Y337134D01*
X219783Y337058D01*
X220093Y336828D01*
X220248Y336483D01*
Y336099D01*
X220352Y335869D01*
X220610Y335678D01*
X220972Y335601D01*
X221333Y335716D01*
X221592Y335984D01*
X221695Y336291D01*
X221592Y336598D01*
X221333Y336866D01*
X220972Y336981D01*
X220610Y336904D01*
X220352Y336713D01*
X220248Y336483D01*
Y336099D01*
X220093Y335754D01*
X219783Y335524D01*
X219422Y335448D01*
X219060Y335524D01*
X218802Y335716D01*
X218647Y336023D01*
X218595Y336291D01*
G01X218947Y325117D02*
X221947D01*
G01X222047Y328217D02*
X218847D01*
G01X222047Y322017D02*
Y328217D01*
G01X218847D02*
Y322017D01*
G01D02*
X222047D01*
G01X224247Y318017D02*
Y321217D01*
G01X221147Y321117D02*
Y318117D01*
G01X218047Y318017D02*
X224247D01*
G01Y321217D02*
X218047D01*
G01D02*
Y318017D01*
G01X224247Y314017D02*
Y317217D01*
G01X221147Y317117D02*
Y314117D01*
G01X218047Y314017D02*
X224247D01*
G01Y317217D02*
X218047D01*
G01D02*
Y314017D01*
G01X232547Y318217D02*
X226347D01*
G01D02*
Y315017D01*
G01D02*
X232547D01*
G01X229547Y314217D02*
X226347D01*
G01X212147Y351717D02*
Y341517D01*
G01D02*
X216747D01*
G01D02*
Y351717D01*
G01X226284Y338948D02*
X229384D01*
Y339907D01*
X229229Y340213D01*
X229022Y340405D01*
X228609Y340482D01*
X228196Y340405D01*
X227937Y340175D01*
X227782Y339907D01*
Y338948D01*
G01Y339907D02*
X226284Y340482D01*
G01Y342815D02*
X229384D01*
X228764Y342355D01*
G01X226284D02*
Y343275D01*
G01X229384Y345915D02*
X229281Y345608D01*
X229022Y345378D01*
X228712Y345225D01*
X228299Y345110D01*
X227834Y345072D01*
X227369Y345110D01*
X226956Y345225D01*
X226646Y345378D01*
X226387Y345608D01*
X226284Y345915D01*
X226387Y346222D01*
X226646Y346452D01*
X226956Y346605D01*
X227369Y346720D01*
X227834Y346758D01*
X228299Y346720D01*
X228712Y346605D01*
X229022Y346452D01*
X229281Y346222D01*
X229384Y345915D01*
G01Y349015D02*
X229281Y348708D01*
X229022Y348478D01*
X228712Y348325D01*
X228299Y348210D01*
X227834Y348172D01*
X227369Y348210D01*
X226956Y348325D01*
X226646Y348478D01*
X226387Y348708D01*
X226284Y349015D01*
X226387Y349322D01*
X226646Y349552D01*
X226956Y349705D01*
X227369Y349820D01*
X227834Y349858D01*
X228299Y349820D01*
X228712Y349705D01*
X229022Y349552D01*
X229281Y349322D01*
X229384Y349015D01*
G01X226167Y337847D02*
Y331647D01*
G01D02*
X229367D01*
G01Y337847D02*
X226167D01*
G01X219532Y354353D02*
X219687Y354123D01*
X219790Y353855D01*
Y353548D01*
X219635Y353203D01*
X219377Y352935D01*
X219067Y352743D01*
X218550Y352590D01*
X218085Y352552D01*
X217620Y352628D01*
X217310Y352743D01*
X217000Y352973D01*
X216793Y353242D01*
X216690Y353510D01*
Y353778D01*
X216793Y354047D01*
X216948Y354277D01*
X217155Y354468D01*
G01X217052Y355958D02*
X216793Y356227D01*
X216690Y356533D01*
X216793Y356840D01*
X217103Y357108D01*
X217568Y357300D01*
X218033Y357377D01*
X218602D01*
X219067Y357300D01*
X219480Y357108D01*
X219687Y356878D01*
X219790Y356610D01*
X219687Y356303D01*
X219480Y356073D01*
X219170Y355920D01*
X218757Y355843D01*
X218395Y355920D01*
X218033Y356112D01*
X217827Y356342D01*
X217775Y356610D01*
X217878Y356917D01*
X218137Y357147D01*
X218602Y357377D01*
G01X216690Y359710D02*
X219790D01*
X219170Y359250D01*
G01X216690D02*
Y360170D01*
G01X216747Y351717D02*
X212147D01*
G01Y346617D02*
X216747D01*
G01X219087Y383796D02*
Y377596D01*
G01D02*
X222287D01*
G01D02*
Y383796D01*
G01D02*
X219087D01*
G01X215087D02*
Y377596D01*
G01D02*
X218287D01*
G01D02*
Y383796D01*
G01D02*
X215087D01*
G01X214287Y377596D02*
Y383796D01*
G01X226287Y377596D02*
Y383796D01*
G01X223087D02*
Y377596D01*
G01D02*
X226287D01*
G01Y383796D02*
X223087D01*
G01X213976Y406129D02*
X217076D01*
Y407088D01*
X216921Y407394D01*
X216714Y407586D01*
X216301Y407663D01*
X215888Y407586D01*
X215629Y407356D01*
X215474Y407088D01*
Y406129D01*
G01Y407088D02*
X213976Y407663D01*
G01X215268Y409268D02*
X215629Y409536D01*
X215836Y409766D01*
X215939Y410073D01*
X215836Y410341D01*
X215629Y410533D01*
X215319Y410686D01*
X214958Y410724D01*
X214648Y410686D01*
X214338Y410533D01*
X214079Y410303D01*
X213976Y410034D01*
X214079Y409728D01*
X214389Y409459D01*
X214854Y409306D01*
X215371Y409268D01*
X216043Y409344D01*
X216404Y409459D01*
X216766Y409651D01*
X217024Y409919D01*
X217076Y410188D01*
X216973Y410456D01*
X216714Y410648D01*
G01X216559Y412368D02*
X216869Y412598D01*
X217024Y412866D01*
X217076Y413173D01*
X216973Y413556D01*
X216714Y413824D01*
X216404Y413901D01*
X216094Y413863D01*
X215836Y413709D01*
X215319Y412943D01*
X214958Y412598D01*
X214441Y412368D01*
X213976Y412291D01*
Y413901D01*
G01X226781Y405843D02*
Y408943D01*
X225822D01*
X225516Y408788D01*
X225324Y408581D01*
X225247Y408168D01*
X225324Y407755D01*
X225554Y407496D01*
X225822Y407341D01*
X226781D01*
G01X225822D02*
X225247Y405843D01*
G01X223642Y407135D02*
X223374Y407496D01*
X223144Y407703D01*
X222837Y407806D01*
X222569Y407703D01*
X222377Y407496D01*
X222224Y407186D01*
X222186Y406825D01*
X222224Y406515D01*
X222377Y406205D01*
X222607Y405946D01*
X222876Y405843D01*
X223182Y405946D01*
X223451Y406256D01*
X223604Y406721D01*
X223642Y407238D01*
X223566Y407910D01*
X223451Y408271D01*
X223259Y408633D01*
X222991Y408891D01*
X222722Y408943D01*
X222454Y408840D01*
X222262Y408581D01*
G01X219814Y405843D02*
Y408943D01*
X220274Y408323D01*
G01Y405843D02*
X219354D01*
G01X227476Y405941D02*
X230576D01*
Y406900D01*
X230421Y407206D01*
X230214Y407398D01*
X229801Y407475D01*
X229388Y407398D01*
X229129Y407168D01*
X228974Y406900D01*
Y405941D01*
G01Y406900D02*
X227476Y407475D01*
G01X228768Y409080D02*
X229129Y409348D01*
X229336Y409578D01*
X229439Y409885D01*
X229336Y410153D01*
X229129Y410345D01*
X228819Y410498D01*
X228458Y410536D01*
X228148Y410498D01*
X227838Y410345D01*
X227579Y410115D01*
X227476Y409846D01*
X227579Y409540D01*
X227889Y409271D01*
X228354Y409118D01*
X228871Y409080D01*
X229543Y409156D01*
X229904Y409271D01*
X230266Y409463D01*
X230524Y409731D01*
X230576Y410000D01*
X230473Y410268D01*
X230214Y410460D01*
G01X228768Y412180D02*
X229129Y412448D01*
X229336Y412678D01*
X229439Y412985D01*
X229336Y413253D01*
X229129Y413445D01*
X228819Y413598D01*
X228458Y413636D01*
X228148Y413598D01*
X227838Y413445D01*
X227579Y413215D01*
X227476Y412946D01*
X227579Y412640D01*
X227889Y412371D01*
X228354Y412218D01*
X228871Y412180D01*
X229543Y412256D01*
X229904Y412371D01*
X230266Y412563D01*
X230524Y412831D01*
X230576Y413100D01*
X230473Y413368D01*
X230214Y413560D01*
G01X226781Y409890D02*
Y412990D01*
X225822D01*
X225516Y412835D01*
X225324Y412628D01*
X225247Y412215D01*
X225324Y411802D01*
X225554Y411543D01*
X225822Y411388D01*
X226781D01*
G01X225822D02*
X225247Y409890D01*
G01X223642Y411182D02*
X223374Y411543D01*
X223144Y411750D01*
X222837Y411853D01*
X222569Y411750D01*
X222377Y411543D01*
X222224Y411233D01*
X222186Y410872D01*
X222224Y410562D01*
X222377Y410252D01*
X222607Y409993D01*
X222876Y409890D01*
X223182Y409993D01*
X223451Y410303D01*
X223604Y410768D01*
X223642Y411285D01*
X223566Y411957D01*
X223451Y412318D01*
X223259Y412680D01*
X222991Y412938D01*
X222722Y412990D01*
X222454Y412887D01*
X222262Y412628D01*
G01X220657Y410510D02*
X220427Y410148D01*
X220121Y409942D01*
X219776Y409890D01*
X219469Y409942D01*
X219162Y410200D01*
X218971Y410510D01*
X218932Y410820D01*
X219009Y411182D01*
X219277Y411440D01*
X219546Y411543D01*
X219891D01*
G01X219546D02*
X219316Y411698D01*
X219124Y411957D01*
X219047Y412267D01*
X219124Y412577D01*
X219316Y412835D01*
X219661Y412990D01*
X220006Y412938D01*
X220351Y412732D01*
G01X227060Y480680D02*
X224000D01*
G01X214309Y481753D02*
Y487953D01*
G01X218309Y481753D02*
Y487953D01*
G01X215109Y481753D02*
X218309D01*
G01X215109Y487953D02*
Y481753D01*
G01X218209Y484853D02*
X215209D01*
G01X219734Y483664D02*
X229934D01*
G01X219734D02*
Y488664D01*
G01X224334Y483864D02*
Y488464D01*
G01X225334Y483864D02*
Y488464D01*
G01X213980Y500080D02*
Y514520D01*
G01X218709Y504353D02*
Y501353D01*
G01X215609Y504453D02*
Y501253D01*
G01X221809D02*
Y504453D01*
G01X215609Y501253D02*
X221809D01*
G01X218309Y487953D02*
X215109D01*
G01X230289Y495706D02*
X227089D01*
G01Y489506D02*
X230289D01*
G01X227089Y495706D02*
Y489506D01*
G01X221009Y495853D02*
X216409D01*
G01X221209Y490253D02*
X216209D01*
G01Y500453D02*
Y490253D01*
G01X221209D02*
Y500453D01*
G01X221009Y494853D02*
X216409D01*
G01X221209Y500453D02*
X216209D01*
G01X229934Y488664D02*
X219734D01*
G01X222668Y499703D02*
Y496503D01*
G01D02*
X228868D01*
G01Y499703D02*
X222668D01*
G01X221130Y514520D02*
Y519930D01*
G01X213980Y514520D02*
X221130D01*
G01X218709Y508353D02*
Y505353D01*
G01X215609Y508453D02*
Y505253D01*
G01X221809Y508453D02*
X215609D01*
G01X221809Y505253D02*
Y508453D01*
G01X215609Y505253D02*
X221809D01*
G01X218709Y512353D02*
Y509353D01*
G01X215609Y512453D02*
Y509253D01*
G01X221809Y512453D02*
X215609D01*
G01X221809Y509253D02*
Y512453D01*
G01X215609Y509253D02*
X221809D01*
G01X223004Y513465D02*
Y510265D01*
G01D02*
X229204D01*
G01Y513465D02*
X223004D01*
G01X226104Y513365D02*
Y510365D01*
G01X221809Y504453D02*
X215609D01*
G01X223109Y514253D02*
X229309D01*
G01X223109Y517453D02*
Y514253D01*
G01X229309Y517453D02*
X223109D01*
G01X221130Y519930D02*
X238160D01*
G01X212998Y522967D02*
Y519967D01*
G01X216098Y519867D02*
Y523067D01*
G01X220282Y532463D02*
X220437Y532233D01*
X220540Y531965D01*
Y531658D01*
X220385Y531313D01*
X220127Y531045D01*
X219817Y530853D01*
X219300Y530700D01*
X218835Y530662D01*
X218370Y530738D01*
X218060Y530853D01*
X217750Y531083D01*
X217543Y531352D01*
X217440Y531620D01*
Y531888D01*
X217543Y532157D01*
X217698Y532387D01*
X217905Y532578D01*
G01X220023Y533992D02*
X220333Y534222D01*
X220488Y534490D01*
X220540Y534797D01*
X220437Y535180D01*
X220178Y535448D01*
X219868Y535525D01*
X219558Y535487D01*
X219300Y535333D01*
X218783Y534567D01*
X218422Y534222D01*
X217905Y533992D01*
X217440Y533915D01*
Y535525D01*
G01X220540Y537820D02*
X220437Y537513D01*
X220178Y537283D01*
X219868Y537130D01*
X219455Y537015D01*
X218990Y536977D01*
X218525Y537015D01*
X218112Y537130D01*
X217802Y537283D01*
X217543Y537513D01*
X217440Y537820D01*
X217543Y538127D01*
X217802Y538357D01*
X218112Y538510D01*
X218525Y538625D01*
X218990Y538663D01*
X219455Y538625D01*
X219868Y538510D01*
X220178Y538357D01*
X220437Y538127D01*
X220540Y537820D01*
G01X217905Y540077D02*
X217647Y540307D01*
X217492Y540575D01*
X217440Y540920D01*
X217543Y541265D01*
X217750Y541533D01*
X218112Y541725D01*
X218525Y541763D01*
X218938Y541687D01*
X219197Y541495D01*
X219403Y541227D01*
X219455Y540958D01*
X219403Y540690D01*
X219197Y540345D01*
X220540Y540460D01*
Y541495D01*
G01X217367Y522663D02*
X220367D01*
G01X217267Y519563D02*
X220467D01*
G01X217267Y525763D02*
Y519563D01*
G01X220467Y525763D02*
X217267D01*
G01X220467Y519563D02*
Y525763D01*
G01X221760Y547092D02*
X221915Y546862D01*
X222018Y546594D01*
Y546287D01*
X221863Y545942D01*
X221605Y545674D01*
X221295Y545482D01*
X220778Y545329D01*
X220313Y545291D01*
X219848Y545367D01*
X219538Y545482D01*
X219228Y545712D01*
X219021Y545981D01*
X218918Y546249D01*
Y546517D01*
X219021Y546786D01*
X219176Y547016D01*
X219383Y547207D01*
G01X221501Y548621D02*
X221811Y548851D01*
X221966Y549119D01*
X222018Y549426D01*
X221915Y549809D01*
X221656Y550077D01*
X221346Y550154D01*
X221036Y550116D01*
X220778Y549962D01*
X220261Y549196D01*
X219900Y548851D01*
X219383Y548621D01*
X218918Y548544D01*
Y550154D01*
G01Y552372D02*
X219590Y552449D01*
X220158Y552564D01*
X220675Y552717D01*
X221243Y552909D01*
X222018Y553216D01*
Y551682D01*
G01X218918Y555549D02*
X222018D01*
X221398Y555089D01*
G01X218918D02*
Y556009D01*
G01X222734Y538849D02*
X227334D01*
G01X222734Y549049D02*
Y538849D01*
G01Y543949D02*
X227334D01*
G01Y549049D02*
X222734D01*
G01X218160Y575831D02*
Y572631D01*
G01X224360Y575831D02*
X218160D01*
G01Y572631D02*
X224360D01*
G01D02*
Y575831D01*
G01X218169Y571716D02*
Y568516D01*
G01X224369Y571716D02*
X218169D01*
G01Y568516D02*
X224369D01*
G01D02*
Y571716D01*
G01X224907Y582825D02*
X228007D01*
Y583784D01*
X227852Y584090D01*
X227645Y584282D01*
X227232Y584359D01*
X226819Y584282D01*
X226560Y584052D01*
X226405Y583784D01*
Y582825D01*
G01Y583784D02*
X224907Y584359D01*
G01X227490Y585964D02*
X227800Y586194D01*
X227955Y586462D01*
X228007Y586769D01*
X227904Y587152D01*
X227645Y587420D01*
X227335Y587497D01*
X227025Y587459D01*
X226767Y587305D01*
X226250Y586539D01*
X225889Y586194D01*
X225372Y585964D01*
X224907Y585887D01*
Y587497D01*
G01X225269Y589140D02*
X225010Y589409D01*
X224907Y589715D01*
X225010Y590022D01*
X225320Y590290D01*
X225785Y590482D01*
X226250Y590559D01*
X226819D01*
X227284Y590482D01*
X227697Y590290D01*
X227904Y590060D01*
X228007Y589792D01*
X227904Y589485D01*
X227697Y589255D01*
X227387Y589102D01*
X226974Y589025D01*
X226612Y589102D01*
X226250Y589294D01*
X226044Y589524D01*
X225992Y589792D01*
X226095Y590099D01*
X226354Y590329D01*
X226819Y590559D01*
G01X228007Y592892D02*
X227904Y592585D01*
X227645Y592355D01*
X227335Y592202D01*
X226922Y592087D01*
X226457Y592049D01*
X225992Y592087D01*
X225579Y592202D01*
X225269Y592355D01*
X225010Y592585D01*
X224907Y592892D01*
X225010Y593199D01*
X225269Y593429D01*
X225579Y593582D01*
X225992Y593697D01*
X226457Y593735D01*
X226922Y593697D01*
X227335Y593582D01*
X227645Y593429D01*
X227904Y593199D01*
X228007Y592892D01*
G01X234021Y677423D02*
Y675201D01*
X233868Y674736D01*
X233561Y674426D01*
X233178Y674323D01*
X232795Y674426D01*
X232488Y674736D01*
X232335Y675201D01*
Y677423D01*
G01X230806Y675615D02*
X230538Y675976D01*
X230308Y676183D01*
X230001Y676286D01*
X229733Y676183D01*
X229541Y675976D01*
X229388Y675666D01*
X229350Y675305D01*
X229388Y674995D01*
X229541Y674685D01*
X229771Y674426D01*
X230040Y674323D01*
X230346Y674426D01*
X230615Y674736D01*
X230768Y675201D01*
X230806Y675718D01*
X230730Y676390D01*
X230615Y676751D01*
X230423Y677113D01*
X230155Y677371D01*
X229886Y677423D01*
X229618Y677320D01*
X229426Y677061D01*
G01X227821Y674943D02*
X227591Y674581D01*
X227285Y674375D01*
X226940Y674323D01*
X226633Y674375D01*
X226326Y674633D01*
X226135Y674943D01*
X226096Y675253D01*
X226173Y675615D01*
X226441Y675873D01*
X226710Y675976D01*
X227055D01*
G01X226710D02*
X226480Y676131D01*
X226288Y676390D01*
X226211Y676700D01*
X226288Y677010D01*
X226480Y677268D01*
X226825Y677423D01*
X227170Y677371D01*
X227515Y677165D01*
G01X225340Y678556D02*
Y709756D01*
G01X224440Y707656D02*
G02I-1000J0D01*
G01X217440Y707456D02*
X215140Y709756D01*
G01X219740D02*
X217440Y707456D01*
G01X225340Y709756D02*
X219740D01*
G01X224340Y726056D02*
X227540D01*
G01X224340Y732256D02*
Y726056D01*
G01X227540Y732256D02*
X224340D01*
G01X224440Y729156D02*
X227440D01*
G01X214040Y737556D02*
Y743756D01*
G01X219840Y737556D02*
X223040D01*
G01X219840Y743756D02*
Y737556D01*
G01X223040D02*
Y743756D01*
G01X218540Y732256D02*
X215340D01*
G01X218540Y726056D02*
Y732256D01*
G01X215340Y726056D02*
X218540D01*
G01X215340Y732256D02*
Y726056D01*
G01X218440Y729156D02*
X215440D01*
G01X224340Y737556D02*
X227540D01*
G01X224340Y743756D02*
Y737556D01*
G01X218540D02*
Y743756D01*
G01X215340Y737556D02*
X218540D01*
G01X215340Y743756D02*
Y737556D01*
G01X214040Y726056D02*
Y732256D01*
G01X223040D02*
X219840D01*
G01Y726056D02*
X223040D01*
G01X219840Y732256D02*
Y726056D01*
G01X223040D02*
Y732256D01*
G01X227965Y747494D02*
X228120Y747264D01*
X228223Y746996D01*
Y746689D01*
X228068Y746344D01*
X227810Y746076D01*
X227500Y745884D01*
X226983Y745731D01*
X226518Y745693D01*
X226053Y745769D01*
X225743Y745884D01*
X225433Y746114D01*
X225226Y746383D01*
X225123Y746651D01*
Y746919D01*
X225226Y747188D01*
X225381Y747418D01*
X225588Y747609D01*
G01X226415Y749023D02*
X226776Y749291D01*
X226983Y749521D01*
X227086Y749828D01*
X226983Y750096D01*
X226776Y750288D01*
X226466Y750441D01*
X226105Y750479D01*
X225795Y750441D01*
X225485Y750288D01*
X225226Y750058D01*
X225123Y749789D01*
X225226Y749483D01*
X225536Y749214D01*
X226001Y749061D01*
X226518Y749023D01*
X227190Y749099D01*
X227551Y749214D01*
X227913Y749406D01*
X228171Y749674D01*
X228223Y749943D01*
X228120Y750211D01*
X227861Y750403D01*
G01X225123Y752851D02*
X225175Y753119D01*
X225330Y753426D01*
X225588Y753618D01*
X225950Y753694D01*
X226311Y753618D01*
X226621Y753388D01*
X226776Y753043D01*
Y752659D01*
X226880Y752429D01*
X227138Y752238D01*
X227500Y752161D01*
X227861Y752276D01*
X228120Y752544D01*
X228223Y752851D01*
X228120Y753158D01*
X227861Y753426D01*
X227500Y753541D01*
X227138Y753464D01*
X226880Y753273D01*
X226776Y753043D01*
Y752659D01*
X226621Y752314D01*
X226311Y752084D01*
X225950Y752008D01*
X225588Y752084D01*
X225330Y752276D01*
X225175Y752583D01*
X225123Y752851D01*
G01Y755951D02*
X225175Y756219D01*
X225330Y756526D01*
X225588Y756718D01*
X225950Y756794D01*
X226311Y756718D01*
X226621Y756488D01*
X226776Y756143D01*
Y755759D01*
X226880Y755529D01*
X227138Y755338D01*
X227500Y755261D01*
X227861Y755376D01*
X228120Y755644D01*
X228223Y755951D01*
X228120Y756258D01*
X227861Y756526D01*
X227500Y756641D01*
X227138Y756564D01*
X226880Y756373D01*
X226776Y756143D01*
Y755759D01*
X226621Y755414D01*
X226311Y755184D01*
X225950Y755108D01*
X225588Y755184D01*
X225330Y755376D01*
X225175Y755683D01*
X225123Y755951D01*
G01X223040Y743756D02*
X219840D01*
G01X219940Y740656D02*
X222940D01*
G01X219203Y747494D02*
X219358Y747264D01*
X219461Y746996D01*
Y746689D01*
X219306Y746344D01*
X219048Y746076D01*
X218738Y745884D01*
X218221Y745731D01*
X217756Y745693D01*
X217291Y745769D01*
X216981Y745884D01*
X216671Y746114D01*
X216464Y746383D01*
X216361Y746651D01*
Y746919D01*
X216464Y747188D01*
X216619Y747418D01*
X216826Y747609D01*
G01X217653Y749023D02*
X218014Y749291D01*
X218221Y749521D01*
X218324Y749828D01*
X218221Y750096D01*
X218014Y750288D01*
X217704Y750441D01*
X217343Y750479D01*
X217033Y750441D01*
X216723Y750288D01*
X216464Y750058D01*
X216361Y749789D01*
X216464Y749483D01*
X216774Y749214D01*
X217239Y749061D01*
X217756Y749023D01*
X218428Y749099D01*
X218789Y749214D01*
X219151Y749406D01*
X219409Y749674D01*
X219461Y749943D01*
X219358Y750211D01*
X219099Y750403D01*
G01X216361Y752774D02*
X217033Y752851D01*
X217601Y752966D01*
X218118Y753119D01*
X218686Y753311D01*
X219461Y753618D01*
Y752084D01*
G01Y755951D02*
X219358Y755644D01*
X219099Y755414D01*
X218789Y755261D01*
X218376Y755146D01*
X217911Y755108D01*
X217446Y755146D01*
X217033Y755261D01*
X216723Y755414D01*
X216464Y755644D01*
X216361Y755951D01*
X216464Y756258D01*
X216723Y756488D01*
X217033Y756641D01*
X217446Y756756D01*
X217911Y756794D01*
X218376Y756756D01*
X218789Y756641D01*
X219099Y756488D01*
X219358Y756258D01*
X219461Y755951D01*
G01X227540Y743756D02*
X224340D01*
G01X218540D02*
X215340D01*
G01X220848Y745884D02*
X223948D01*
Y746843D01*
X223793Y747149D01*
X223586Y747341D01*
X223173Y747418D01*
X222760Y747341D01*
X222501Y747111D01*
X222346Y746843D01*
Y745884D01*
G01Y746843D02*
X220848Y747418D01*
G01X221210Y749099D02*
X220951Y749368D01*
X220848Y749674D01*
X220951Y749981D01*
X221261Y750249D01*
X221726Y750441D01*
X222191Y750518D01*
X222760D01*
X223225Y750441D01*
X223638Y750249D01*
X223845Y750019D01*
X223948Y749751D01*
X223845Y749444D01*
X223638Y749214D01*
X223328Y749061D01*
X222915Y748984D01*
X222553Y749061D01*
X222191Y749253D01*
X221985Y749483D01*
X221933Y749751D01*
X222036Y750058D01*
X222295Y750288D01*
X222760Y750518D01*
G01X223431Y752123D02*
X223741Y752353D01*
X223896Y752621D01*
X223948Y752928D01*
X223845Y753311D01*
X223586Y753579D01*
X223276Y753656D01*
X222966Y753618D01*
X222708Y753464D01*
X222191Y752698D01*
X221830Y752353D01*
X221313Y752123D01*
X220848Y752046D01*
Y753656D01*
G01Y755951D02*
X220900Y756219D01*
X221055Y756526D01*
X221313Y756718D01*
X221675Y756794D01*
X222036Y756718D01*
X222346Y756488D01*
X222501Y756143D01*
Y755759D01*
X222605Y755529D01*
X222863Y755338D01*
X223225Y755261D01*
X223586Y755376D01*
X223845Y755644D01*
X223948Y755951D01*
X223845Y756258D01*
X223586Y756526D01*
X223225Y756641D01*
X222863Y756564D01*
X222605Y756373D01*
X222501Y756143D01*
Y755759D01*
X222346Y755414D01*
X222036Y755184D01*
X221675Y755108D01*
X221313Y755184D01*
X221055Y755376D01*
X220900Y755683D01*
X220848Y755951D01*
G01X223143Y759486D02*
X223298Y759256D01*
X223401Y758988D01*
Y758681D01*
X223246Y758336D01*
X222988Y758068D01*
X222678Y757876D01*
X222161Y757723D01*
X221696Y757685D01*
X221231Y757761D01*
X220921Y757876D01*
X220611Y758106D01*
X220404Y758375D01*
X220301Y758643D01*
Y758911D01*
X220404Y759180D01*
X220559Y759410D01*
X220766Y759601D01*
G01X221593Y761015D02*
X221954Y761283D01*
X222161Y761513D01*
X222264Y761820D01*
X222161Y762088D01*
X221954Y762280D01*
X221644Y762433D01*
X221283Y762471D01*
X220973Y762433D01*
X220663Y762280D01*
X220404Y762050D01*
X220301Y761781D01*
X220404Y761475D01*
X220714Y761206D01*
X221179Y761053D01*
X221696Y761015D01*
X222368Y761091D01*
X222729Y761206D01*
X223091Y761398D01*
X223349Y761666D01*
X223401Y761935D01*
X223298Y762203D01*
X223039Y762395D01*
G01X220663Y764191D02*
X220404Y764460D01*
X220301Y764766D01*
X220404Y765073D01*
X220714Y765341D01*
X221179Y765533D01*
X221644Y765610D01*
X222213D01*
X222678Y765533D01*
X223091Y765341D01*
X223298Y765111D01*
X223401Y764843D01*
X223298Y764536D01*
X223091Y764306D01*
X222781Y764153D01*
X222368Y764076D01*
X222006Y764153D01*
X221644Y764345D01*
X221438Y764575D01*
X221386Y764843D01*
X221489Y765150D01*
X221748Y765380D01*
X222213Y765610D01*
G01X220301Y767943D02*
X223401D01*
X222781Y767483D01*
G01X220301D02*
Y768403D01*
G01X224591Y757876D02*
X227691D01*
Y758835D01*
X227536Y759141D01*
X227329Y759333D01*
X226916Y759410D01*
X226503Y759333D01*
X226244Y759103D01*
X226089Y758835D01*
Y757876D01*
G01Y758835D02*
X224591Y759410D01*
G01X224953Y761091D02*
X224694Y761360D01*
X224591Y761666D01*
X224694Y761973D01*
X225004Y762241D01*
X225469Y762433D01*
X225934Y762510D01*
X226503D01*
X226968Y762433D01*
X227381Y762241D01*
X227588Y762011D01*
X227691Y761743D01*
X227588Y761436D01*
X227381Y761206D01*
X227071Y761053D01*
X226658Y760976D01*
X226296Y761053D01*
X225934Y761245D01*
X225728Y761475D01*
X225676Y761743D01*
X225779Y762050D01*
X226038Y762280D01*
X226503Y762510D01*
G01X227174Y764115D02*
X227484Y764345D01*
X227639Y764613D01*
X227691Y764920D01*
X227588Y765303D01*
X227329Y765571D01*
X227019Y765648D01*
X226709Y765610D01*
X226451Y765456D01*
X225934Y764690D01*
X225573Y764345D01*
X225056Y764115D01*
X224591Y764038D01*
Y765648D01*
G01X225056Y767100D02*
X224798Y767330D01*
X224643Y767598D01*
X224591Y767943D01*
X224694Y768288D01*
X224901Y768556D01*
X225263Y768748D01*
X225676Y768786D01*
X226089Y768710D01*
X226348Y768518D01*
X226554Y768250D01*
X226606Y767981D01*
X226554Y767713D01*
X226348Y767368D01*
X227691Y767483D01*
Y768518D01*
G01X216321Y757876D02*
X219421D01*
Y758835D01*
X219266Y759141D01*
X219059Y759333D01*
X218646Y759410D01*
X218233Y759333D01*
X217974Y759103D01*
X217819Y758835D01*
Y757876D01*
G01Y758835D02*
X216321Y759410D01*
G01X216683Y761091D02*
X216424Y761360D01*
X216321Y761666D01*
X216424Y761973D01*
X216734Y762241D01*
X217199Y762433D01*
X217664Y762510D01*
X218233D01*
X218698Y762433D01*
X219111Y762241D01*
X219318Y762011D01*
X219421Y761743D01*
X219318Y761436D01*
X219111Y761206D01*
X218801Y761053D01*
X218388Y760976D01*
X218026Y761053D01*
X217664Y761245D01*
X217458Y761475D01*
X217406Y761743D01*
X217509Y762050D01*
X217768Y762280D01*
X218233Y762510D01*
G01X219421Y764843D02*
X219318Y764536D01*
X219059Y764306D01*
X218749Y764153D01*
X218336Y764038D01*
X217871Y764000D01*
X217406Y764038D01*
X216993Y764153D01*
X216683Y764306D01*
X216424Y764536D01*
X216321Y764843D01*
X216424Y765150D01*
X216683Y765380D01*
X216993Y765533D01*
X217406Y765648D01*
X217871Y765686D01*
X218336Y765648D01*
X218749Y765533D01*
X219059Y765380D01*
X219318Y765150D01*
X219421Y764843D01*
G01X216321Y767866D02*
X216993Y767943D01*
X217561Y768058D01*
X218078Y768211D01*
X218646Y768403D01*
X219421Y768710D01*
Y767176D01*
G01X232493Y-186364D02*
Y-194364D01*
X236493D01*
G01X244293D02*
Y-189031D01*
G01Y-189964D02*
X243893Y-189431D01*
X243293Y-189164D01*
X242593Y-189031D01*
X241893Y-189297D01*
X241293Y-189831D01*
X240893Y-190631D01*
X240693Y-191697D01*
X240893Y-192764D01*
X241293Y-193564D01*
X241893Y-194097D01*
X242593Y-194364D01*
X243293Y-194231D01*
X243893Y-193831D01*
X244293Y-193298D01*
G01X248393Y-196764D02*
X248993Y-197031D01*
X249793Y-196764D01*
X250293Y-196231D01*
X250693Y-195564D01*
X251293Y-193431D01*
X252593Y-189031D01*
G01X249393D02*
X251293Y-193431D01*
G01X256993Y-190764D02*
X260193D01*
X259893Y-189831D01*
X259393Y-189297D01*
X258693Y-189031D01*
X257993Y-189164D01*
X257393Y-189564D01*
X256993Y-190497D01*
X256793Y-191298D01*
Y-192097D01*
X256993Y-192897D01*
X257493Y-193697D01*
X258093Y-194231D01*
X258793Y-194364D01*
X259493Y-194097D01*
X260193Y-193298D01*
G01X265093Y-194364D02*
Y-189031D01*
G01Y-190097D02*
X265593Y-189564D01*
X266093Y-189164D01*
X266793Y-189031D01*
X267293Y-189164D01*
X267893Y-189564D01*
G01X239127Y82630D02*
Y85730D01*
X238168D01*
X237862Y85575D01*
X237670Y85368D01*
X237593Y84955D01*
X237670Y84542D01*
X237900Y84283D01*
X238168Y84128D01*
X239127D01*
G01X238168D02*
X237593Y82630D01*
G01X235988Y85213D02*
X235758Y85523D01*
X235490Y85678D01*
X235183Y85730D01*
X234800Y85627D01*
X234532Y85368D01*
X234455Y85058D01*
X234493Y84748D01*
X234647Y84490D01*
X235413Y83973D01*
X235758Y83612D01*
X235988Y83095D01*
X236065Y82630D01*
X234455D01*
G01X232160Y85730D02*
X232467Y85627D01*
X232697Y85368D01*
X232850Y85058D01*
X232965Y84645D01*
X233003Y84180D01*
X232965Y83715D01*
X232850Y83302D01*
X232697Y82992D01*
X232467Y82733D01*
X232160Y82630D01*
X231853Y82733D01*
X231623Y82992D01*
X231470Y83302D01*
X231355Y83715D01*
X231317Y84180D01*
X231355Y84645D01*
X231470Y85058D01*
X231623Y85368D01*
X231853Y85627D01*
X232160Y85730D01*
G01X229712Y82992D02*
X229443Y82733D01*
X229137Y82630D01*
X228830Y82733D01*
X228562Y83043D01*
X228370Y83508D01*
X228293Y83973D01*
Y84542D01*
X228370Y85007D01*
X228562Y85420D01*
X228792Y85627D01*
X229060Y85730D01*
X229367Y85627D01*
X229597Y85420D01*
X229750Y85110D01*
X229827Y84697D01*
X229750Y84335D01*
X229558Y83973D01*
X229328Y83767D01*
X229060Y83715D01*
X228753Y83818D01*
X228523Y84077D01*
X228293Y84542D01*
G01X249257Y120161D02*
X249487Y120316D01*
X249755Y120419D01*
X250062D01*
X250407Y120264D01*
X250675Y120006D01*
X250867Y119696D01*
X251020Y119179D01*
X251058Y118714D01*
X250982Y118249D01*
X250867Y117939D01*
X250637Y117629D01*
X250368Y117422D01*
X250100Y117319D01*
X249832D01*
X249563Y117422D01*
X249333Y117577D01*
X249142Y117784D01*
G01X247000Y117319D02*
Y120419D01*
X247460Y119799D01*
G01Y117319D02*
X246540D01*
G01X243977D02*
X243900Y117991D01*
X243785Y118559D01*
X243632Y119076D01*
X243440Y119644D01*
X243133Y120419D01*
X244667D01*
G01X241528Y119902D02*
X241298Y120212D01*
X241030Y120367D01*
X240723Y120419D01*
X240340Y120316D01*
X240072Y120057D01*
X239995Y119747D01*
X240033Y119437D01*
X240187Y119179D01*
X240953Y118662D01*
X241298Y118301D01*
X241528Y117784D01*
X241605Y117319D01*
X239995D01*
G01X252557Y109567D02*
Y112667D01*
X251598D01*
X251292Y112512D01*
X251100Y112305D01*
X251023Y111892D01*
X251100Y111479D01*
X251330Y111220D01*
X251598Y111065D01*
X252557D01*
G01X251598D02*
X251023Y109567D01*
G01X249418Y112150D02*
X249188Y112460D01*
X248920Y112615D01*
X248613Y112667D01*
X248230Y112564D01*
X247962Y112305D01*
X247885Y111995D01*
X247923Y111685D01*
X248077Y111427D01*
X248843Y110910D01*
X249188Y110549D01*
X249418Y110032D01*
X249495Y109567D01*
X247885D01*
G01X245590Y112667D02*
X245897Y112564D01*
X246127Y112305D01*
X246280Y111995D01*
X246395Y111582D01*
X246433Y111117D01*
X246395Y110652D01*
X246280Y110239D01*
X246127Y109929D01*
X245897Y109670D01*
X245590Y109567D01*
X245283Y109670D01*
X245053Y109929D01*
X244900Y110239D01*
X244785Y110652D01*
X244747Y111117D01*
X244785Y111582D01*
X244900Y111995D01*
X245053Y112305D01*
X245283Y112564D01*
X245590Y112667D01*
G01X242030Y109567D02*
Y112667D01*
X243448Y110445D01*
X241532D01*
G01X241359Y147254D02*
X438209D01*
Y170876D01*
X241359D01*
Y147254D01*
G01X232142Y191909D02*
X232297Y191679D01*
X232400Y191411D01*
Y191104D01*
X232245Y190759D01*
X231987Y190491D01*
X231677Y190299D01*
X231160Y190146D01*
X230695Y190108D01*
X230230Y190184D01*
X229920Y190299D01*
X229610Y190529D01*
X229403Y190798D01*
X229300Y191066D01*
Y191334D01*
X229403Y191603D01*
X229558Y191833D01*
X229765Y192024D01*
G01X230592Y193438D02*
X230953Y193706D01*
X231160Y193936D01*
X231263Y194243D01*
X231160Y194511D01*
X230953Y194703D01*
X230643Y194856D01*
X230282Y194894D01*
X229972Y194856D01*
X229662Y194703D01*
X229403Y194473D01*
X229300Y194204D01*
X229403Y193898D01*
X229713Y193629D01*
X230178Y193476D01*
X230695Y193438D01*
X231367Y193514D01*
X231728Y193629D01*
X232090Y193821D01*
X232348Y194089D01*
X232400Y194358D01*
X232297Y194626D01*
X232038Y194818D01*
G01X229662Y196614D02*
X229403Y196883D01*
X229300Y197189D01*
X229403Y197496D01*
X229713Y197764D01*
X230178Y197956D01*
X230643Y198033D01*
X231212D01*
X231677Y197956D01*
X232090Y197764D01*
X232297Y197534D01*
X232400Y197266D01*
X232297Y196959D01*
X232090Y196729D01*
X231780Y196576D01*
X231367Y196499D01*
X231005Y196576D01*
X230643Y196768D01*
X230437Y196998D01*
X230385Y197266D01*
X230488Y197573D01*
X230747Y197803D01*
X231212Y198033D01*
G01X243782Y199142D02*
X243937Y198912D01*
X244040Y198644D01*
Y198337D01*
X243885Y197992D01*
X243627Y197724D01*
X243317Y197532D01*
X242800Y197379D01*
X242335Y197341D01*
X241870Y197417D01*
X241560Y197532D01*
X241250Y197762D01*
X241043Y198031D01*
X240940Y198299D01*
Y198567D01*
X241043Y198836D01*
X241198Y199066D01*
X241405Y199257D01*
G01X241560Y200556D02*
X241198Y200786D01*
X240992Y201092D01*
X240940Y201437D01*
X240992Y201744D01*
X241250Y202051D01*
X241560Y202242D01*
X241870Y202281D01*
X242232Y202204D01*
X242490Y201936D01*
X242593Y201667D01*
Y201322D01*
G01Y201667D02*
X242748Y201897D01*
X243007Y202089D01*
X243317Y202166D01*
X243627Y202089D01*
X243885Y201897D01*
X244040Y201552D01*
X243988Y201207D01*
X243782Y200862D01*
G01X243523Y203771D02*
X243833Y204001D01*
X243988Y204269D01*
X244040Y204576D01*
X243937Y204959D01*
X243678Y205227D01*
X243368Y205304D01*
X243058Y205266D01*
X242800Y205112D01*
X242283Y204346D01*
X241922Y204001D01*
X241405Y203771D01*
X240940Y203694D01*
Y205304D01*
G01X236380Y192371D02*
X236535Y192141D01*
X236638Y191873D01*
Y191566D01*
X236483Y191221D01*
X236225Y190953D01*
X235915Y190761D01*
X235398Y190608D01*
X234933Y190570D01*
X234468Y190646D01*
X234158Y190761D01*
X233848Y190991D01*
X233641Y191260D01*
X233538Y191528D01*
Y191796D01*
X233641Y192065D01*
X233796Y192295D01*
X234003Y192486D01*
G01X233538Y194628D02*
X233590Y194896D01*
X233745Y195203D01*
X234003Y195395D01*
X234365Y195471D01*
X234726Y195395D01*
X235036Y195165D01*
X235191Y194820D01*
Y194436D01*
X235295Y194206D01*
X235553Y194015D01*
X235915Y193938D01*
X236276Y194053D01*
X236535Y194321D01*
X236638Y194628D01*
X236535Y194935D01*
X236276Y195203D01*
X235915Y195318D01*
X235553Y195241D01*
X235295Y195050D01*
X235191Y194820D01*
Y194436D01*
X235036Y194091D01*
X234726Y193861D01*
X234365Y193785D01*
X234003Y193861D01*
X233745Y194053D01*
X233590Y194360D01*
X233538Y194628D01*
G01Y197651D02*
X234210Y197728D01*
X234778Y197843D01*
X235295Y197996D01*
X235863Y198188D01*
X236638Y198495D01*
Y196961D01*
G01X240380Y192371D02*
X240535Y192141D01*
X240638Y191873D01*
Y191566D01*
X240483Y191221D01*
X240225Y190953D01*
X239915Y190761D01*
X239398Y190608D01*
X238933Y190570D01*
X238468Y190646D01*
X238158Y190761D01*
X237848Y190991D01*
X237641Y191260D01*
X237538Y191528D01*
Y191796D01*
X237641Y192065D01*
X237796Y192295D01*
X238003Y192486D01*
G01X237538Y194628D02*
X237590Y194896D01*
X237745Y195203D01*
X238003Y195395D01*
X238365Y195471D01*
X238726Y195395D01*
X239036Y195165D01*
X239191Y194820D01*
Y194436D01*
X239295Y194206D01*
X239553Y194015D01*
X239915Y193938D01*
X240276Y194053D01*
X240535Y194321D01*
X240638Y194628D01*
X240535Y194935D01*
X240276Y195203D01*
X239915Y195318D01*
X239553Y195241D01*
X239295Y195050D01*
X239191Y194820D01*
Y194436D01*
X239036Y194091D01*
X238726Y193861D01*
X238365Y193785D01*
X238003Y193861D01*
X237745Y194053D01*
X237590Y194360D01*
X237538Y194628D01*
G01X238830Y197000D02*
X239191Y197268D01*
X239398Y197498D01*
X239501Y197805D01*
X239398Y198073D01*
X239191Y198265D01*
X238881Y198418D01*
X238520Y198456D01*
X238210Y198418D01*
X237900Y198265D01*
X237641Y198035D01*
X237538Y197766D01*
X237641Y197460D01*
X237951Y197191D01*
X238416Y197038D01*
X238933Y197000D01*
X239605Y197076D01*
X239966Y197191D01*
X240328Y197383D01*
X240586Y197651D01*
X240638Y197920D01*
X240535Y198188D01*
X240276Y198380D01*
G01X239060Y214060D02*
X262360D01*
G01X239060Y207340D02*
Y214060D01*
G01X240424Y219334D02*
Y222434D01*
X239465D01*
X239159Y222279D01*
X238967Y222072D01*
X238890Y221659D01*
X238967Y221246D01*
X239197Y220987D01*
X239465Y220832D01*
X240424D01*
G01X239465D02*
X238890Y219334D01*
G01X237400Y219954D02*
X237170Y219592D01*
X236864Y219386D01*
X236519Y219334D01*
X236212Y219386D01*
X235905Y219644D01*
X235714Y219954D01*
X235675Y220264D01*
X235752Y220626D01*
X236020Y220884D01*
X236289Y220987D01*
X236634D01*
G01X236289D02*
X236059Y221142D01*
X235867Y221401D01*
X235790Y221711D01*
X235867Y222021D01*
X236059Y222279D01*
X236404Y222434D01*
X236749Y222382D01*
X237094Y222176D01*
G01X234185Y221917D02*
X233955Y222227D01*
X233687Y222382D01*
X233380Y222434D01*
X232997Y222331D01*
X232729Y222072D01*
X232652Y221762D01*
X232690Y221452D01*
X232844Y221194D01*
X233610Y220677D01*
X233955Y220316D01*
X234185Y219799D01*
X234262Y219334D01*
X232652D01*
G01X240424Y215334D02*
Y218434D01*
X239465D01*
X239159Y218279D01*
X238967Y218072D01*
X238890Y217659D01*
X238967Y217246D01*
X239197Y216987D01*
X239465Y216832D01*
X240424D01*
G01X239465D02*
X238890Y215334D01*
G01X237400Y215954D02*
X237170Y215592D01*
X236864Y215386D01*
X236519Y215334D01*
X236212Y215386D01*
X235905Y215644D01*
X235714Y215954D01*
X235675Y216264D01*
X235752Y216626D01*
X236020Y216884D01*
X236289Y216987D01*
X236634D01*
G01X236289D02*
X236059Y217142D01*
X235867Y217401D01*
X235790Y217711D01*
X235867Y218021D01*
X236059Y218279D01*
X236404Y218434D01*
X236749Y218382D01*
X237094Y218176D01*
G01X234300Y215954D02*
X234070Y215592D01*
X233764Y215386D01*
X233419Y215334D01*
X233112Y215386D01*
X232805Y215644D01*
X232614Y215954D01*
X232575Y216264D01*
X232652Y216626D01*
X232920Y216884D01*
X233189Y216987D01*
X233534D01*
G01X233189D02*
X232959Y217142D01*
X232767Y217401D01*
X232690Y217711D01*
X232767Y218021D01*
X232959Y218279D01*
X233304Y218434D01*
X233649Y218382D01*
X233994Y218176D01*
G01X231522Y215301D02*
Y218501D01*
G01X253047Y209049D02*
Y212149D01*
X252088D01*
X251782Y211994D01*
X251590Y211787D01*
X251513Y211374D01*
X251590Y210961D01*
X251820Y210702D01*
X252088Y210547D01*
X253047D01*
G01X252088D02*
X251513Y209049D01*
G01X249180D02*
Y212149D01*
X249640Y211529D01*
G01Y209049D02*
X248720D01*
G01X245620D02*
Y212149D01*
X247038Y209927D01*
X245122D01*
G01X243823Y209669D02*
X243593Y209307D01*
X243287Y209101D01*
X242942Y209049D01*
X242635Y209101D01*
X242328Y209359D01*
X242137Y209669D01*
X242098Y209979D01*
X242175Y210341D01*
X242443Y210599D01*
X242712Y210702D01*
X243057D01*
G01X242712D02*
X242482Y210857D01*
X242290Y211116D01*
X242213Y211426D01*
X242290Y211736D01*
X242482Y211994D01*
X242827Y212149D01*
X243172Y212097D01*
X243517Y211891D01*
G01X231522Y219301D02*
Y222501D01*
G01X242385Y232570D02*
Y235670D01*
X241426D01*
X241120Y235515D01*
X240928Y235308D01*
X240851Y234895D01*
X240928Y234482D01*
X241158Y234223D01*
X241426Y234068D01*
X242385D01*
G01X241426D02*
X240851Y232570D01*
G01X239361Y233190D02*
X239131Y232828D01*
X238825Y232622D01*
X238480Y232570D01*
X238173Y232622D01*
X237866Y232880D01*
X237675Y233190D01*
X237636Y233500D01*
X237713Y233862D01*
X237981Y234120D01*
X238250Y234223D01*
X238595D01*
G01X238250D02*
X238020Y234378D01*
X237828Y234637D01*
X237751Y234947D01*
X237828Y235257D01*
X238020Y235515D01*
X238365Y235670D01*
X238710Y235618D01*
X239055Y235412D01*
G01X236261Y233035D02*
X236031Y232777D01*
X235763Y232622D01*
X235418Y232570D01*
X235073Y232673D01*
X234805Y232880D01*
X234613Y233242D01*
X234575Y233655D01*
X234651Y234068D01*
X234843Y234327D01*
X235111Y234533D01*
X235380Y234585D01*
X235648Y234533D01*
X235993Y234327D01*
X235878Y235670D01*
X234843D01*
G01X228990Y239920D02*
X228501D01*
G01X228990D02*
Y248307D01*
G01X246739Y243828D02*
X240539D01*
G01D02*
Y240628D01*
G01D02*
X246739D01*
G01X241740Y236530D02*
Y239630D01*
X240781D01*
X240475Y239475D01*
X240283Y239268D01*
X240206Y238855D01*
X240283Y238442D01*
X240513Y238183D01*
X240781Y238028D01*
X241740D01*
G01X240781D02*
X240206Y236530D01*
G01X238716Y237150D02*
X238486Y236788D01*
X238180Y236582D01*
X237835Y236530D01*
X237528Y236582D01*
X237221Y236840D01*
X237030Y237150D01*
X236991Y237460D01*
X237068Y237822D01*
X237336Y238080D01*
X237605Y238183D01*
X237950D01*
G01X237605D02*
X237375Y238338D01*
X237183Y238597D01*
X237106Y238907D01*
X237183Y239217D01*
X237375Y239475D01*
X237720Y239630D01*
X238065Y239578D01*
X238410Y239372D01*
G01X234313Y236530D02*
Y239630D01*
X235731Y237408D01*
X233815D01*
G01X246739Y247828D02*
X240539D01*
G01D02*
Y244628D01*
G01D02*
X246739D01*
G01X228990Y254427D02*
Y251021D01*
G01Y258670D02*
Y257980D01*
G01X235385Y258670D02*
X234773D01*
G01X228990D02*
X230306D01*
G01X240275D02*
X237371D01*
G01X227145Y267243D02*
Y261043D01*
G01D02*
X230345D01*
G01D02*
Y267243D01*
G01X228595Y267482D02*
Y273682D01*
G01X239410Y276117D02*
X236410D01*
G01X239510Y279217D02*
X236310D01*
G01D02*
Y273017D01*
G01D02*
X239510D01*
G01D02*
Y279217D01*
G01X240025Y279617D02*
X243025D01*
G01X239925Y282717D02*
Y276517D01*
G01D02*
X243125D01*
G01X232460Y276467D02*
X235660D01*
G01X232460Y275767D02*
X235660D01*
G01Y279217D02*
X232460D01*
G01X235660Y273017D02*
Y279217D01*
G01X232460D02*
Y273017D01*
G01D02*
X235660D01*
G01X230345Y267243D02*
X227145D01*
G01X236289Y285351D02*
X233289D01*
G01X233189Y288451D02*
Y282251D01*
G01D02*
X236389D01*
G01D02*
Y288451D01*
G01D02*
X233189D01*
G01X233507Y302109D02*
Y295909D01*
G01D02*
X236707D01*
G01D02*
Y302109D01*
G01X233289Y292250D02*
X236289D01*
G01X236389Y295350D02*
X233189D01*
G01X236389Y289150D02*
Y295350D01*
G01X233189D02*
Y289150D01*
G01D02*
X236389D01*
G01X230008Y289703D02*
Y295903D01*
G01X230039Y282738D02*
Y288938D01*
G01X243125Y282717D02*
X239925D01*
G01X229547Y308017D02*
Y314217D01*
G01X229312Y298095D02*
Y304295D01*
G01X233418Y317717D02*
Y311517D01*
G01D02*
X236618D01*
G01D02*
Y317717D01*
G01X241907Y310875D02*
Y317075D01*
G01X238707D02*
Y310875D01*
G01D02*
X241907D01*
G01X233200Y307832D02*
X230000D01*
G01X230100Y304732D02*
X233100D01*
G01X233200Y301632D02*
Y307832D01*
G01X230000D02*
Y301632D01*
G01D02*
X233200D01*
G01X236607Y299009D02*
X233607D01*
G01X236707Y302109D02*
X233507D01*
G01X242759Y317326D02*
Y311126D01*
G01D02*
X245959D01*
G01X236870Y326580D02*
X237340D01*
G01X240740Y327694D02*
Y326948D01*
G01X234168Y326580D02*
X236870D01*
G01X231460Y323172D02*
Y324380D01*
G01X229447Y315117D02*
Y318117D01*
G01X232547Y315017D02*
Y318217D01*
G01X239547Y325717D02*
X233347D01*
G01X236447Y322617D02*
Y325617D01*
G01X233347Y325717D02*
Y322517D01*
G01D02*
X239547D01*
G01D02*
Y325717D01*
G01X236447Y318617D02*
Y321617D01*
G01X239547Y321717D02*
X233347D01*
G01D02*
Y318517D01*
G01D02*
X239547D01*
G01D02*
Y321717D01*
G01X236518Y314617D02*
X233518D01*
G01X236618Y317717D02*
X233418D01*
G01X241807Y313975D02*
X238807D01*
G01X241907Y317075D02*
X238707D01*
G01X245959Y317326D02*
X242759D01*
G01X246501Y328396D02*
X241901D01*
G01X246501Y323296D02*
X241901D01*
G01Y328396D02*
Y318196D01*
G01D02*
X246501D01*
G01X233918Y334087D02*
Y327887D01*
G01D02*
X237118D01*
G01D02*
Y334087D01*
G01X242262Y329640D02*
X249562D01*
G01X245112Y334860D02*
X242112D01*
G01X242012Y337960D02*
Y331760D01*
G01D02*
X245212D01*
G01Y337960D02*
X242012D01*
G01X229367Y331647D02*
Y337847D01*
G01X234434Y334987D02*
X237534D01*
Y335946D01*
X237379Y336252D01*
X237172Y336444D01*
X236759Y336521D01*
X236346Y336444D01*
X236087Y336214D01*
X235932Y335946D01*
Y334987D01*
G01Y335946D02*
X234434Y336521D01*
G01X234796Y338202D02*
X234537Y338471D01*
X234434Y338777D01*
X234537Y339084D01*
X234847Y339352D01*
X235312Y339544D01*
X235777Y339621D01*
X236346D01*
X236811Y339544D01*
X237224Y339352D01*
X237431Y339122D01*
X237534Y338854D01*
X237431Y338547D01*
X237224Y338317D01*
X236914Y338164D01*
X236501Y338087D01*
X236139Y338164D01*
X235777Y338356D01*
X235571Y338586D01*
X235519Y338854D01*
X235622Y339161D01*
X235881Y339391D01*
X236346Y339621D01*
G01X234434Y341954D02*
X234486Y342222D01*
X234641Y342529D01*
X234899Y342721D01*
X235261Y342797D01*
X235622Y342721D01*
X235932Y342491D01*
X236087Y342146D01*
Y341762D01*
X236191Y341532D01*
X236449Y341341D01*
X236811Y341264D01*
X237172Y341379D01*
X237431Y341647D01*
X237534Y341954D01*
X237431Y342261D01*
X237172Y342529D01*
X236811Y342644D01*
X236449Y342567D01*
X236191Y342376D01*
X236087Y342146D01*
Y341762D01*
X235932Y341417D01*
X235622Y341187D01*
X235261Y341111D01*
X234899Y341187D01*
X234641Y341379D01*
X234486Y341686D01*
X234434Y341954D01*
G01X237118Y334087D02*
X233918D01*
G01X240243Y359271D02*
Y365471D01*
G01X237043D02*
Y359271D01*
G01D02*
X240243D01*
G01X227947Y403625D02*
Y385445D01*
X263115D01*
Y376481D01*
X246690D01*
Y374161D01*
X232523D01*
Y374224D01*
G01X234287Y376096D02*
Y382296D01*
G01X231087D02*
Y376096D01*
G01D02*
X234287D01*
G01X239388Y378750D02*
Y375550D01*
G01D02*
X245588D01*
G01X240243Y365471D02*
X237043D01*
G01X238287Y377596D02*
Y383796D01*
G01D02*
X235087D01*
G01D02*
Y377596D01*
G01D02*
X238287D01*
G01X234287Y382296D02*
X231087D01*
G01X245588Y378750D02*
X239388D01*
G01X246274Y382797D02*
X240074D01*
G01D02*
Y379597D01*
G01D02*
X246274D01*
G01X231476Y405941D02*
X234576D01*
Y406900D01*
X234421Y407206D01*
X234214Y407398D01*
X233801Y407475D01*
X233388Y407398D01*
X233129Y407168D01*
X232974Y406900D01*
Y405941D01*
G01Y406900D02*
X231476Y407475D01*
G01Y409808D02*
X231528Y410076D01*
X231683Y410383D01*
X231941Y410575D01*
X232303Y410651D01*
X232664Y410575D01*
X232974Y410345D01*
X233129Y410000D01*
Y409616D01*
X233233Y409386D01*
X233491Y409195D01*
X233853Y409118D01*
X234214Y409233D01*
X234473Y409501D01*
X234576Y409808D01*
X234473Y410115D01*
X234214Y410383D01*
X233853Y410498D01*
X233491Y410421D01*
X233233Y410230D01*
X233129Y410000D01*
Y409616D01*
X232974Y409271D01*
X232664Y409041D01*
X232303Y408965D01*
X231941Y409041D01*
X231683Y409233D01*
X231528Y409540D01*
X231476Y409808D01*
G01Y412908D02*
X231528Y413176D01*
X231683Y413483D01*
X231941Y413675D01*
X232303Y413751D01*
X232664Y413675D01*
X232974Y413445D01*
X233129Y413100D01*
Y412716D01*
X233233Y412486D01*
X233491Y412295D01*
X233853Y412218D01*
X234214Y412333D01*
X234473Y412601D01*
X234576Y412908D01*
X234473Y413215D01*
X234214Y413483D01*
X233853Y413598D01*
X233491Y413521D01*
X233233Y413330D01*
X233129Y413100D01*
Y412716D01*
X232974Y412371D01*
X232664Y412141D01*
X232303Y412065D01*
X231941Y412141D01*
X231683Y412333D01*
X231528Y412640D01*
X231476Y412908D01*
G01X235476Y405941D02*
X238576D01*
Y406900D01*
X238421Y407206D01*
X238214Y407398D01*
X237801Y407475D01*
X237388Y407398D01*
X237129Y407168D01*
X236974Y406900D01*
Y405941D01*
G01Y406900D02*
X235476Y407475D01*
G01Y409808D02*
X235528Y410076D01*
X235683Y410383D01*
X235941Y410575D01*
X236303Y410651D01*
X236664Y410575D01*
X236974Y410345D01*
X237129Y410000D01*
Y409616D01*
X237233Y409386D01*
X237491Y409195D01*
X237853Y409118D01*
X238214Y409233D01*
X238473Y409501D01*
X238576Y409808D01*
X238473Y410115D01*
X238214Y410383D01*
X237853Y410498D01*
X237491Y410421D01*
X237233Y410230D01*
X237129Y410000D01*
Y409616D01*
X236974Y409271D01*
X236664Y409041D01*
X236303Y408965D01*
X235941Y409041D01*
X235683Y409233D01*
X235528Y409540D01*
X235476Y409808D01*
G01X236768Y412180D02*
X237129Y412448D01*
X237336Y412678D01*
X237439Y412985D01*
X237336Y413253D01*
X237129Y413445D01*
X236819Y413598D01*
X236458Y413636D01*
X236148Y413598D01*
X235838Y413445D01*
X235579Y413215D01*
X235476Y412946D01*
X235579Y412640D01*
X235889Y412371D01*
X236354Y412218D01*
X236871Y412180D01*
X237543Y412256D01*
X237904Y412371D01*
X238266Y412563D01*
X238524Y412831D01*
X238576Y413100D01*
X238473Y413368D01*
X238214Y413560D01*
G01X239620Y405941D02*
X242720D01*
Y406900D01*
X242565Y407206D01*
X242358Y407398D01*
X241945Y407475D01*
X241532Y407398D01*
X241273Y407168D01*
X241118Y406900D01*
Y405941D01*
G01Y406900D02*
X239620Y407475D01*
G01Y409808D02*
X242720D01*
X242100Y409348D01*
G01X239620D02*
Y410268D01*
G01X240085Y412065D02*
X239827Y412295D01*
X239672Y412563D01*
X239620Y412908D01*
X239723Y413253D01*
X239930Y413521D01*
X240292Y413713D01*
X240705Y413751D01*
X241118Y413675D01*
X241377Y413483D01*
X241583Y413215D01*
X241635Y412946D01*
X241583Y412678D01*
X241377Y412333D01*
X242720Y412448D01*
Y413483D01*
G01X242203Y415280D02*
X242513Y415510D01*
X242668Y415778D01*
X242720Y416085D01*
X242617Y416468D01*
X242358Y416736D01*
X242048Y416813D01*
X241738Y416775D01*
X241480Y416621D01*
X240963Y415855D01*
X240602Y415510D01*
X240085Y415280D01*
X239620Y415203D01*
Y416813D01*
G01X232273Y458102D02*
X231709D01*
Y446691D01*
X324487D01*
Y461487D01*
X287625D01*
Y480732D01*
X238416D01*
Y472583D01*
X232336D01*
Y466377D01*
G01X234040Y447733D02*
X237140D01*
Y448692D01*
X236985Y448998D01*
X236778Y449190D01*
X236365Y449267D01*
X235952Y449190D01*
X235693Y448960D01*
X235538Y448692D01*
Y447733D01*
G01Y448692D02*
X234040Y449267D01*
G01X234660Y450757D02*
X234298Y450987D01*
X234092Y451293D01*
X234040Y451638D01*
X234092Y451945D01*
X234350Y452252D01*
X234660Y452443D01*
X234970Y452482D01*
X235332Y452405D01*
X235590Y452137D01*
X235693Y451868D01*
Y451523D01*
G01Y451868D02*
X235848Y452098D01*
X236107Y452290D01*
X236417Y452367D01*
X236727Y452290D01*
X236985Y452098D01*
X237140Y451753D01*
X237088Y451408D01*
X236882Y451063D01*
G01X234660Y453857D02*
X234298Y454087D01*
X234092Y454393D01*
X234040Y454738D01*
X234092Y455045D01*
X234350Y455352D01*
X234660Y455543D01*
X234970Y455582D01*
X235332Y455505D01*
X235590Y455237D01*
X235693Y454968D01*
Y454623D01*
G01Y454968D02*
X235848Y455198D01*
X236107Y455390D01*
X236417Y455467D01*
X236727Y455390D01*
X236985Y455198D01*
X237140Y454853D01*
X237088Y454508D01*
X236882Y454163D01*
G01X236623Y457072D02*
X236933Y457302D01*
X237088Y457570D01*
X237140Y457877D01*
X237037Y458260D01*
X236778Y458528D01*
X236468Y458605D01*
X236158Y458567D01*
X235900Y458413D01*
X235383Y457647D01*
X235022Y457302D01*
X234505Y457072D01*
X234040Y456995D01*
Y458605D01*
G01X240600Y448053D02*
X243700D01*
Y449012D01*
X243545Y449318D01*
X243338Y449510D01*
X242925Y449587D01*
X242512Y449510D01*
X242253Y449280D01*
X242098Y449012D01*
Y448053D01*
G01Y449012D02*
X240600Y449587D01*
G01X241220Y451077D02*
X240858Y451307D01*
X240652Y451613D01*
X240600Y451958D01*
X240652Y452265D01*
X240910Y452572D01*
X241220Y452763D01*
X241530Y452802D01*
X241892Y452725D01*
X242150Y452457D01*
X242253Y452188D01*
Y451843D01*
G01Y452188D02*
X242408Y452418D01*
X242667Y452610D01*
X242977Y452687D01*
X243287Y452610D01*
X243545Y452418D01*
X243700Y452073D01*
X243648Y451728D01*
X243442Y451383D01*
G01X240600Y455020D02*
X243700D01*
X243080Y454560D01*
G01X240600D02*
Y455480D01*
G01X240962Y457468D02*
X240703Y457737D01*
X240600Y458043D01*
X240703Y458350D01*
X241013Y458618D01*
X241478Y458810D01*
X241943Y458887D01*
X242512D01*
X242977Y458810D01*
X243390Y458618D01*
X243597Y458388D01*
X243700Y458120D01*
X243597Y457813D01*
X243390Y457583D01*
X243080Y457430D01*
X242667Y457353D01*
X242305Y457430D01*
X241943Y457622D01*
X241737Y457852D01*
X241685Y458120D01*
X241788Y458427D01*
X242047Y458657D01*
X242512Y458887D01*
G01X236919Y465593D02*
Y471793D01*
G01X233719Y465593D02*
X236919D01*
G01X233719Y471793D02*
Y465593D01*
G01X240379Y465053D02*
X243579D01*
G01X240379Y471253D02*
Y465053D01*
G01X233480Y488480D02*
Y482870D01*
G01X232430Y480680D02*
X230370D01*
G01X229934Y483664D02*
Y488664D01*
G01X243509Y479653D02*
X240309D01*
G01Y473453D02*
X243509D01*
G01X240309Y479653D02*
Y473453D01*
G01X236919Y471793D02*
X233719D01*
G01X243579Y471253D02*
X240379D01*
G01X233480Y500850D02*
Y491780D01*
G01X230189Y492606D02*
X227189D01*
G01X230289Y489506D02*
Y495706D01*
G01X228868Y496503D02*
Y499703D01*
G01X248320Y506670D02*
X233480D01*
G01D02*
Y504200D01*
G01X229204Y510265D02*
Y513465D01*
G01X238318Y509865D02*
X244518D01*
G01X238318Y513065D02*
Y509865D01*
G01X244518Y513065D02*
X238318D01*
G01X241418Y509965D02*
Y512965D01*
G01X238343Y513849D02*
X244543D01*
G01X238343Y517049D02*
Y513849D01*
G01X244543Y517049D02*
X238343D01*
G01X241443Y513949D02*
Y516949D01*
G01X229309Y514253D02*
Y517453D01*
G01X238160Y519930D02*
Y558210D01*
G01X241705Y526137D02*
X247905D01*
G01X241705Y529337D02*
Y526137D01*
G01X247905Y529337D02*
X241705D01*
G01X241715Y521314D02*
Y518114D01*
G01X247915Y521314D02*
X241715D01*
G01Y518114D02*
X247915D01*
G01X241705Y525332D02*
Y522132D01*
G01X247905Y525332D02*
X241705D01*
G01Y522132D02*
X247905D01*
G01X241755Y530181D02*
X247955D01*
G01X241755Y533381D02*
Y530181D01*
G01X247955Y533381D02*
X241755D01*
G01X241741Y534189D02*
X247941D01*
G01X241741Y537389D02*
Y534189D01*
G01X247941Y537389D02*
X241741D01*
G01X240859Y542362D02*
X247059D01*
G01X240859Y545562D02*
Y542362D01*
G01X247059Y545562D02*
X240859D01*
G01X241895Y538189D02*
X248095D01*
G01X241895Y541389D02*
Y538189D01*
G01X248095Y541389D02*
X241895D01*
G01X227334Y538849D02*
Y549049D01*
G01X238160Y558210D02*
X241930D01*
G01X240275Y562583D02*
X240505Y562738D01*
X240773Y562841D01*
X241080D01*
X241425Y562686D01*
X241693Y562428D01*
X241885Y562118D01*
X242038Y561601D01*
X242076Y561136D01*
X242000Y560671D01*
X241885Y560361D01*
X241655Y560051D01*
X241386Y559844D01*
X241118Y559741D01*
X240850D01*
X240581Y559844D01*
X240351Y559999D01*
X240160Y560206D01*
G01X238746Y562324D02*
X238516Y562634D01*
X238248Y562789D01*
X237941Y562841D01*
X237558Y562738D01*
X237290Y562479D01*
X237213Y562169D01*
X237251Y561859D01*
X237405Y561601D01*
X238171Y561084D01*
X238516Y560723D01*
X238746Y560206D01*
X238823Y559741D01*
X237213D01*
G01X235761Y560206D02*
X235531Y559948D01*
X235263Y559793D01*
X234918Y559741D01*
X234573Y559844D01*
X234305Y560051D01*
X234113Y560413D01*
X234075Y560826D01*
X234151Y561239D01*
X234343Y561498D01*
X234611Y561704D01*
X234880Y561756D01*
X235148Y561704D01*
X235493Y561498D01*
X235378Y562841D01*
X234343D01*
G01X231818Y559741D02*
X231550Y559793D01*
X231243Y559948D01*
X231051Y560206D01*
X230975Y560568D01*
X231051Y560929D01*
X231281Y561239D01*
X231626Y561394D01*
X232010D01*
X232240Y561498D01*
X232431Y561756D01*
X232508Y562118D01*
X232393Y562479D01*
X232125Y562738D01*
X231818Y562841D01*
X231511Y562738D01*
X231243Y562479D01*
X231128Y562118D01*
X231205Y561756D01*
X231396Y561498D01*
X231626Y561394D01*
X232010D01*
X232355Y561239D01*
X232585Y560929D01*
X232661Y560568D01*
X232585Y560206D01*
X232393Y559948D01*
X232086Y559793D01*
X231818Y559741D01*
G01X237659Y580520D02*
X240759D01*
Y581479D01*
X240604Y581785D01*
X240397Y581977D01*
X239984Y582054D01*
X239571Y581977D01*
X239312Y581747D01*
X239157Y581479D01*
Y580520D01*
G01Y581479D02*
X237659Y582054D01*
G01X240242Y583659D02*
X240552Y583889D01*
X240707Y584157D01*
X240759Y584464D01*
X240656Y584847D01*
X240397Y585115D01*
X240087Y585192D01*
X239777Y585154D01*
X239519Y585000D01*
X239002Y584234D01*
X238641Y583889D01*
X238124Y583659D01*
X237659Y583582D01*
Y585192D01*
G01X238021Y586835D02*
X237762Y587104D01*
X237659Y587410D01*
X237762Y587717D01*
X238072Y587985D01*
X238537Y588177D01*
X239002Y588254D01*
X239571D01*
X240036Y588177D01*
X240449Y587985D01*
X240656Y587755D01*
X240759Y587487D01*
X240656Y587180D01*
X240449Y586950D01*
X240139Y586797D01*
X239726Y586720D01*
X239364Y586797D01*
X239002Y586989D01*
X238796Y587219D01*
X238744Y587487D01*
X238847Y587794D01*
X239106Y588024D01*
X239571Y588254D01*
G01X240242Y589859D02*
X240552Y590089D01*
X240707Y590357D01*
X240759Y590664D01*
X240656Y591047D01*
X240397Y591315D01*
X240087Y591392D01*
X239777Y591354D01*
X239519Y591200D01*
X239002Y590434D01*
X238641Y590089D01*
X238124Y589859D01*
X237659Y589782D01*
Y591392D01*
G01X238909Y573353D02*
X242109D01*
G01X238909Y579553D02*
Y573353D01*
G01X242109Y579553D02*
X238909D01*
G01X242109Y573353D02*
Y579553D01*
G01X233675Y580566D02*
X236775D01*
Y581525D01*
X236620Y581831D01*
X236413Y582023D01*
X236000Y582100D01*
X235587Y582023D01*
X235328Y581793D01*
X235173Y581525D01*
Y580566D01*
G01Y581525D02*
X233675Y582100D01*
G01X236258Y583705D02*
X236568Y583935D01*
X236723Y584203D01*
X236775Y584510D01*
X236672Y584893D01*
X236413Y585161D01*
X236103Y585238D01*
X235793Y585200D01*
X235535Y585046D01*
X235018Y584280D01*
X234657Y583935D01*
X234140Y583705D01*
X233675Y583628D01*
Y585238D01*
G01X234037Y586881D02*
X233778Y587150D01*
X233675Y587456D01*
X233778Y587763D01*
X234088Y588031D01*
X234553Y588223D01*
X235018Y588300D01*
X235587D01*
X236052Y588223D01*
X236465Y588031D01*
X236672Y587801D01*
X236775Y587533D01*
X236672Y587226D01*
X236465Y586996D01*
X236155Y586843D01*
X235742Y586766D01*
X235380Y586843D01*
X235018Y587035D01*
X234812Y587265D01*
X234760Y587533D01*
X234863Y587840D01*
X235122Y588070D01*
X235587Y588300D01*
G01X233675Y590633D02*
X236775D01*
X236155Y590173D01*
G01X233675D02*
Y591093D01*
G01X237809Y573353D02*
Y579553D01*
G01X234609Y573353D02*
X237809D01*
G01X234609Y579553D02*
Y573353D01*
G01X237809Y579553D02*
X234609D01*
G01X233409Y573353D02*
Y579553D01*
G01X230209Y573353D02*
X233409D01*
G01X230209Y579553D02*
Y573353D01*
G01X233409Y579553D02*
X230209D01*
G01X248397Y706150D02*
Y709250D01*
X247438D01*
X247132Y709095D01*
X246940Y708888D01*
X246863Y708475D01*
X246940Y708062D01*
X247170Y707803D01*
X247438Y707648D01*
X248397D01*
G01X247438D02*
X246863Y706150D01*
G01X245258Y707442D02*
X244990Y707803D01*
X244760Y708010D01*
X244453Y708113D01*
X244185Y708010D01*
X243993Y707803D01*
X243840Y707493D01*
X243802Y707132D01*
X243840Y706822D01*
X243993Y706512D01*
X244223Y706253D01*
X244492Y706150D01*
X244798Y706253D01*
X245067Y706563D01*
X245220Y707028D01*
X245258Y707545D01*
X245182Y708217D01*
X245067Y708578D01*
X244875Y708940D01*
X244607Y709198D01*
X244338Y709250D01*
X244070Y709147D01*
X243878Y708888D01*
G01X241430Y706150D02*
X241162Y706202D01*
X240855Y706357D01*
X240663Y706615D01*
X240587Y706977D01*
X240663Y707338D01*
X240893Y707648D01*
X241238Y707803D01*
X241622D01*
X241852Y707907D01*
X242043Y708165D01*
X242120Y708527D01*
X242005Y708888D01*
X241737Y709147D01*
X241430Y709250D01*
X241123Y709147D01*
X240855Y708888D01*
X240740Y708527D01*
X240817Y708165D01*
X241008Y707907D01*
X241238Y707803D01*
X241622D01*
X241967Y707648D01*
X242197Y707338D01*
X242273Y706977D01*
X242197Y706615D01*
X242005Y706357D01*
X241698Y706202D01*
X241430Y706150D01*
G01X239058Y707442D02*
X238790Y707803D01*
X238560Y708010D01*
X238253Y708113D01*
X237985Y708010D01*
X237793Y707803D01*
X237640Y707493D01*
X237602Y707132D01*
X237640Y706822D01*
X237793Y706512D01*
X238023Y706253D01*
X238292Y706150D01*
X238598Y706253D01*
X238867Y706563D01*
X239020Y707028D01*
X239058Y707545D01*
X238982Y708217D01*
X238867Y708578D01*
X238675Y708940D01*
X238407Y709198D01*
X238138Y709250D01*
X237870Y709147D01*
X237678Y708888D01*
G01X239823Y704750D02*
Y701550D01*
G01X246023Y704750D02*
X239823D01*
G01Y701550D02*
X246023D01*
G01X227540Y726056D02*
Y732256D01*
G01X237840Y737556D02*
X241040D01*
G01X237840Y743756D02*
Y737556D01*
G01X241040D02*
Y743756D01*
G01X228840Y737556D02*
X232040D01*
G01X228840Y743756D02*
Y737556D01*
G01X232040D02*
Y743756D01*
G01X233340Y726056D02*
X236540D01*
G01X233340Y732256D02*
Y726056D01*
G01X236540Y732256D02*
X233340D01*
G01X233440Y729156D02*
X236440D01*
G01X236540Y726056D02*
Y732256D01*
G01X242340Y726056D02*
X245540D01*
G01X242340Y732256D02*
Y726056D01*
G01X245540Y732256D02*
X242340D01*
G01X242440Y729156D02*
X245440D01*
G01X227540Y737556D02*
Y743756D01*
G01X241040Y732256D02*
X237840D01*
G01X241040Y726056D02*
Y732256D01*
G01X237840Y726056D02*
X241040D01*
G01X237840Y732256D02*
Y726056D01*
G01X232040Y732256D02*
X228840D01*
G01X232040Y726056D02*
Y732256D01*
G01X228840Y726056D02*
X232040D01*
G01X228840Y732256D02*
Y726056D01*
G01X233340Y737556D02*
X236540D01*
G01X233340Y743756D02*
Y737556D01*
G01X236540D02*
Y743756D01*
G01X242340Y737556D02*
X245540D01*
G01X242340Y743756D02*
Y737556D01*
G01X241040Y743756D02*
X237840D01*
G01X237940Y740656D02*
X240940D01*
G01X232040Y743756D02*
X228840D01*
G01X228940Y740656D02*
X231940D01*
G01X237176Y747494D02*
X237331Y747264D01*
X237434Y746996D01*
Y746689D01*
X237279Y746344D01*
X237021Y746076D01*
X236711Y745884D01*
X236194Y745731D01*
X235729Y745693D01*
X235264Y745769D01*
X234954Y745884D01*
X234644Y746114D01*
X234437Y746383D01*
X234334Y746651D01*
Y746919D01*
X234437Y747188D01*
X234592Y747418D01*
X234799Y747609D01*
G01X235626Y749023D02*
X235987Y749291D01*
X236194Y749521D01*
X236297Y749828D01*
X236194Y750096D01*
X235987Y750288D01*
X235677Y750441D01*
X235316Y750479D01*
X235006Y750441D01*
X234696Y750288D01*
X234437Y750058D01*
X234334Y749789D01*
X234437Y749483D01*
X234747Y749214D01*
X235212Y749061D01*
X235729Y749023D01*
X236401Y749099D01*
X236762Y749214D01*
X237124Y749406D01*
X237382Y749674D01*
X237434Y749943D01*
X237331Y750211D01*
X237072Y750403D01*
G01X234334Y752851D02*
X234386Y753119D01*
X234541Y753426D01*
X234799Y753618D01*
X235161Y753694D01*
X235522Y753618D01*
X235832Y753388D01*
X235987Y753043D01*
Y752659D01*
X236091Y752429D01*
X236349Y752238D01*
X236711Y752161D01*
X237072Y752276D01*
X237331Y752544D01*
X237434Y752851D01*
X237331Y753158D01*
X237072Y753426D01*
X236711Y753541D01*
X236349Y753464D01*
X236091Y753273D01*
X235987Y753043D01*
Y752659D01*
X235832Y752314D01*
X235522Y752084D01*
X235161Y752008D01*
X234799Y752084D01*
X234541Y752276D01*
X234386Y752583D01*
X234334Y752851D01*
G01X236917Y755223D02*
X237227Y755453D01*
X237382Y755721D01*
X237434Y756028D01*
X237331Y756411D01*
X237072Y756679D01*
X236762Y756756D01*
X236452Y756718D01*
X236194Y756564D01*
X235677Y755798D01*
X235316Y755453D01*
X234799Y755223D01*
X234334Y755146D01*
Y756756D01*
G01X245378Y747494D02*
X245533Y747264D01*
X245636Y746996D01*
Y746689D01*
X245481Y746344D01*
X245223Y746076D01*
X244913Y745884D01*
X244396Y745731D01*
X243931Y745693D01*
X243466Y745769D01*
X243156Y745884D01*
X242846Y746114D01*
X242639Y746383D01*
X242536Y746651D01*
Y746919D01*
X242639Y747188D01*
X242794Y747418D01*
X243001Y747609D01*
G01X243828Y749023D02*
X244189Y749291D01*
X244396Y749521D01*
X244499Y749828D01*
X244396Y750096D01*
X244189Y750288D01*
X243879Y750441D01*
X243518Y750479D01*
X243208Y750441D01*
X242898Y750288D01*
X242639Y750058D01*
X242536Y749789D01*
X242639Y749483D01*
X242949Y749214D01*
X243414Y749061D01*
X243931Y749023D01*
X244603Y749099D01*
X244964Y749214D01*
X245326Y749406D01*
X245584Y749674D01*
X245636Y749943D01*
X245533Y750211D01*
X245274Y750403D01*
G01X242536Y752774D02*
X243208Y752851D01*
X243776Y752966D01*
X244293Y753119D01*
X244861Y753311D01*
X245636Y753618D01*
Y752084D01*
G01X243828Y755223D02*
X244189Y755491D01*
X244396Y755721D01*
X244499Y756028D01*
X244396Y756296D01*
X244189Y756488D01*
X243879Y756641D01*
X243518Y756679D01*
X243208Y756641D01*
X242898Y756488D01*
X242639Y756258D01*
X242536Y755989D01*
X242639Y755683D01*
X242949Y755414D01*
X243414Y755261D01*
X243931Y755223D01*
X244603Y755299D01*
X244964Y755414D01*
X245326Y755606D01*
X245584Y755874D01*
X245636Y756143D01*
X245533Y756411D01*
X245274Y756603D01*
G01X238611Y745884D02*
X241711D01*
Y746843D01*
X241556Y747149D01*
X241349Y747341D01*
X240936Y747418D01*
X240523Y747341D01*
X240264Y747111D01*
X240109Y746843D01*
Y745884D01*
G01Y746843D02*
X238611Y747418D01*
G01X238973Y749099D02*
X238714Y749368D01*
X238611Y749674D01*
X238714Y749981D01*
X239024Y750249D01*
X239489Y750441D01*
X239954Y750518D01*
X240523D01*
X240988Y750441D01*
X241401Y750249D01*
X241608Y750019D01*
X241711Y749751D01*
X241608Y749444D01*
X241401Y749214D01*
X241091Y749061D01*
X240678Y748984D01*
X240316Y749061D01*
X239954Y749253D01*
X239748Y749483D01*
X239696Y749751D01*
X239799Y750058D01*
X240058Y750288D01*
X240523Y750518D01*
G01X238611Y752851D02*
X241711D01*
X241091Y752391D01*
G01X238611D02*
Y753311D01*
G01X239903Y755223D02*
X240264Y755491D01*
X240471Y755721D01*
X240574Y756028D01*
X240471Y756296D01*
X240264Y756488D01*
X239954Y756641D01*
X239593Y756679D01*
X239283Y756641D01*
X238973Y756488D01*
X238714Y756258D01*
X238611Y755989D01*
X238714Y755683D01*
X239024Y755414D01*
X239489Y755261D01*
X240006Y755223D01*
X240678Y755299D01*
X241039Y755414D01*
X241401Y755606D01*
X241659Y755874D01*
X241711Y756143D01*
X241608Y756411D01*
X241349Y756603D01*
G01X230101Y745884D02*
X233201D01*
Y746843D01*
X233046Y747149D01*
X232839Y747341D01*
X232426Y747418D01*
X232013Y747341D01*
X231754Y747111D01*
X231599Y746843D01*
Y745884D01*
G01Y746843D02*
X230101Y747418D01*
G01X230463Y749099D02*
X230204Y749368D01*
X230101Y749674D01*
X230204Y749981D01*
X230514Y750249D01*
X230979Y750441D01*
X231444Y750518D01*
X232013D01*
X232478Y750441D01*
X232891Y750249D01*
X233098Y750019D01*
X233201Y749751D01*
X233098Y749444D01*
X232891Y749214D01*
X232581Y749061D01*
X232168Y748984D01*
X231806Y749061D01*
X231444Y749253D01*
X231238Y749483D01*
X231186Y749751D01*
X231289Y750058D01*
X231548Y750288D01*
X232013Y750518D01*
G01X232684Y752123D02*
X232994Y752353D01*
X233149Y752621D01*
X233201Y752928D01*
X233098Y753311D01*
X232839Y753579D01*
X232529Y753656D01*
X232219Y753618D01*
X231961Y753464D01*
X231444Y752698D01*
X231083Y752353D01*
X230566Y752123D01*
X230101Y752046D01*
Y753656D01*
G01X232684Y755223D02*
X232994Y755453D01*
X233149Y755721D01*
X233201Y756028D01*
X233098Y756411D01*
X232839Y756679D01*
X232529Y756756D01*
X232219Y756718D01*
X231961Y756564D01*
X231444Y755798D01*
X231083Y755453D01*
X230566Y755223D01*
X230101Y755146D01*
Y756756D01*
G01X236540Y743756D02*
X233340D01*
G01X245540D02*
X242340D01*
G01X240863Y759486D02*
X241018Y759256D01*
X241121Y758988D01*
Y758681D01*
X240966Y758336D01*
X240708Y758068D01*
X240398Y757876D01*
X239881Y757723D01*
X239416Y757685D01*
X238951Y757761D01*
X238641Y757876D01*
X238331Y758106D01*
X238124Y758375D01*
X238021Y758643D01*
Y758911D01*
X238124Y759180D01*
X238279Y759410D01*
X238486Y759601D01*
G01X239313Y761015D02*
X239674Y761283D01*
X239881Y761513D01*
X239984Y761820D01*
X239881Y762088D01*
X239674Y762280D01*
X239364Y762433D01*
X239003Y762471D01*
X238693Y762433D01*
X238383Y762280D01*
X238124Y762050D01*
X238021Y761781D01*
X238124Y761475D01*
X238434Y761206D01*
X238899Y761053D01*
X239416Y761015D01*
X240088Y761091D01*
X240449Y761206D01*
X240811Y761398D01*
X241069Y761666D01*
X241121Y761935D01*
X241018Y762203D01*
X240759Y762395D01*
G01X238021Y764766D02*
X238693Y764843D01*
X239261Y764958D01*
X239778Y765111D01*
X240346Y765303D01*
X241121Y765610D01*
Y764076D01*
G01X238383Y767291D02*
X238124Y767560D01*
X238021Y767866D01*
X238124Y768173D01*
X238434Y768441D01*
X238899Y768633D01*
X239364Y768710D01*
X239933D01*
X240398Y768633D01*
X240811Y768441D01*
X241018Y768211D01*
X241121Y767943D01*
X241018Y767636D01*
X240811Y767406D01*
X240501Y767253D01*
X240088Y767176D01*
X239726Y767253D01*
X239364Y767445D01*
X239158Y767675D01*
X239106Y767943D01*
X239209Y768250D01*
X239468Y768480D01*
X239933Y768710D01*
G01X232353Y759486D02*
X232508Y759256D01*
X232611Y758988D01*
Y758681D01*
X232456Y758336D01*
X232198Y758068D01*
X231888Y757876D01*
X231371Y757723D01*
X230906Y757685D01*
X230441Y757761D01*
X230131Y757876D01*
X229821Y758106D01*
X229614Y758375D01*
X229511Y758643D01*
Y758911D01*
X229614Y759180D01*
X229769Y759410D01*
X229976Y759601D01*
G01X230803Y761015D02*
X231164Y761283D01*
X231371Y761513D01*
X231474Y761820D01*
X231371Y762088D01*
X231164Y762280D01*
X230854Y762433D01*
X230493Y762471D01*
X230183Y762433D01*
X229873Y762280D01*
X229614Y762050D01*
X229511Y761781D01*
X229614Y761475D01*
X229924Y761206D01*
X230389Y761053D01*
X230906Y761015D01*
X231578Y761091D01*
X231939Y761206D01*
X232301Y761398D01*
X232559Y761666D01*
X232611Y761935D01*
X232508Y762203D01*
X232249Y762395D01*
G01X229511Y764843D02*
X229563Y765111D01*
X229718Y765418D01*
X229976Y765610D01*
X230338Y765686D01*
X230699Y765610D01*
X231009Y765380D01*
X231164Y765035D01*
Y764651D01*
X231268Y764421D01*
X231526Y764230D01*
X231888Y764153D01*
X232249Y764268D01*
X232508Y764536D01*
X232611Y764843D01*
X232508Y765150D01*
X232249Y765418D01*
X231888Y765533D01*
X231526Y765456D01*
X231268Y765265D01*
X231164Y765035D01*
Y764651D01*
X231009Y764306D01*
X230699Y764076D01*
X230338Y764000D01*
X229976Y764076D01*
X229718Y764268D01*
X229563Y764575D01*
X229511Y764843D01*
G01X229976Y767100D02*
X229718Y767330D01*
X229563Y767598D01*
X229511Y767943D01*
X229614Y768288D01*
X229821Y768556D01*
X230183Y768748D01*
X230596Y768786D01*
X231009Y768710D01*
X231268Y768518D01*
X231474Y768250D01*
X231526Y767981D01*
X231474Y767713D01*
X231268Y767368D01*
X232611Y767483D01*
Y768518D01*
G01X233744Y757876D02*
X236844D01*
Y758835D01*
X236689Y759141D01*
X236482Y759333D01*
X236069Y759410D01*
X235656Y759333D01*
X235397Y759103D01*
X235242Y758835D01*
Y757876D01*
G01Y758835D02*
X233744Y759410D01*
G01X234106Y761091D02*
X233847Y761360D01*
X233744Y761666D01*
X233847Y761973D01*
X234157Y762241D01*
X234622Y762433D01*
X235087Y762510D01*
X235656D01*
X236121Y762433D01*
X236534Y762241D01*
X236741Y762011D01*
X236844Y761743D01*
X236741Y761436D01*
X236534Y761206D01*
X236224Y761053D01*
X235811Y760976D01*
X235449Y761053D01*
X235087Y761245D01*
X234881Y761475D01*
X234829Y761743D01*
X234932Y762050D01*
X235191Y762280D01*
X235656Y762510D01*
G01X233744Y764843D02*
X236844D01*
X236224Y764383D01*
G01X233744D02*
Y765303D01*
G01X234106Y767291D02*
X233847Y767560D01*
X233744Y767866D01*
X233847Y768173D01*
X234157Y768441D01*
X234622Y768633D01*
X235087Y768710D01*
X235656D01*
X236121Y768633D01*
X236534Y768441D01*
X236741Y768211D01*
X236844Y767943D01*
X236741Y767636D01*
X236534Y767406D01*
X236224Y767253D01*
X235811Y767176D01*
X235449Y767253D01*
X235087Y767445D01*
X234881Y767675D01*
X234829Y767943D01*
X234932Y768250D01*
X235191Y768480D01*
X235656Y768710D01*
G01X242115Y757876D02*
X245215D01*
Y758835D01*
X245060Y759141D01*
X244853Y759333D01*
X244440Y759410D01*
X244027Y759333D01*
X243768Y759103D01*
X243613Y758835D01*
Y757876D01*
G01Y758835D02*
X242115Y759410D01*
G01X242477Y761091D02*
X242218Y761360D01*
X242115Y761666D01*
X242218Y761973D01*
X242528Y762241D01*
X242993Y762433D01*
X243458Y762510D01*
X244027D01*
X244492Y762433D01*
X244905Y762241D01*
X245112Y762011D01*
X245215Y761743D01*
X245112Y761436D01*
X244905Y761206D01*
X244595Y761053D01*
X244182Y760976D01*
X243820Y761053D01*
X243458Y761245D01*
X243252Y761475D01*
X243200Y761743D01*
X243303Y762050D01*
X243562Y762280D01*
X244027Y762510D01*
G01X242115Y764843D02*
X245215D01*
X244595Y764383D01*
G01X242115D02*
Y765303D01*
G01X242735Y767100D02*
X242373Y767330D01*
X242167Y767636D01*
X242115Y767981D01*
X242167Y768288D01*
X242425Y768595D01*
X242735Y768786D01*
X243045Y768825D01*
X243407Y768748D01*
X243665Y768480D01*
X243768Y768211D01*
Y767866D01*
G01Y768211D02*
X243923Y768441D01*
X244182Y768633D01*
X244492Y768710D01*
X244802Y768633D01*
X245060Y768441D01*
X245215Y768096D01*
X245163Y767751D01*
X244957Y767406D01*
G01X254793Y-236364D02*
X257193D01*
G01X255993D02*
Y-244364D01*
G01X254793D02*
X257193D01*
G01X262593D02*
Y-239031D01*
G01Y-240097D02*
X263093Y-239564D01*
X263593Y-239164D01*
X264293Y-239031D01*
X264793Y-239164D01*
X265393Y-239564D01*
G01X270493Y-240764D02*
X273693D01*
X273393Y-239831D01*
X272893Y-239297D01*
X272193Y-239031D01*
X271493Y-239164D01*
X270893Y-239564D01*
X270493Y-240497D01*
X270293Y-241298D01*
Y-242097D01*
X270493Y-242897D01*
X270993Y-243697D01*
X271593Y-244231D01*
X272293Y-244364D01*
X272993Y-244097D01*
X273693Y-243298D01*
G01X278293Y-244364D02*
Y-239031D01*
G01Y-240364D02*
X278693Y-239697D01*
X279293Y-239164D01*
X280093Y-239031D01*
X280793Y-239164D01*
X281393Y-239697D01*
X281693Y-240631D01*
Y-244364D01*
G01X286493Y-240764D02*
X289693D01*
X289393Y-239831D01*
X288893Y-239297D01*
X288193Y-239031D01*
X287493Y-239164D01*
X286893Y-239564D01*
X286493Y-240497D01*
X286293Y-241298D01*
Y-242097D01*
X286493Y-242897D01*
X286993Y-243697D01*
X287593Y-244231D01*
X288293Y-244364D01*
X288993Y-244097D01*
X289693Y-243298D01*
G01X243893Y-218298D02*
X244693Y-218964D01*
X245593Y-219364D01*
X246393D01*
X247193Y-218964D01*
X247793Y-218298D01*
X248093Y-217364D01*
X247893Y-216431D01*
X247393Y-215631D01*
X246493Y-215097D01*
X245293Y-214831D01*
X244593Y-214297D01*
X244293Y-213364D01*
X244493Y-212431D01*
X244993Y-211764D01*
X245693Y-211364D01*
X246393D01*
X247093Y-211631D01*
X247693Y-212297D01*
G01X252793Y-211364D02*
X255193D01*
G01X253993D02*
Y-219364D01*
G01X252793D02*
X255193D01*
G01X259993Y-211364D02*
Y-219364D01*
X263993D01*
G01X267793D02*
Y-211364D01*
G01X271593D02*
X267793Y-216298D01*
G01X272193Y-219364D02*
X269493Y-214031D01*
G01X276693Y-216697D02*
X279293D01*
G01X286793Y-215097D02*
X287193Y-214697D01*
X287493Y-214031D01*
X287693Y-213097D01*
X287493Y-212297D01*
X287093Y-211764D01*
X286393Y-211364D01*
X283693D01*
Y-219364D01*
X286993D01*
X287693Y-218831D01*
X288093Y-218031D01*
X288293Y-217097D01*
X288093Y-216164D01*
X287493Y-215364D01*
X286793Y-215097D01*
X283693D01*
G01X293993Y-219364D02*
X293193Y-219231D01*
X292493Y-218697D01*
X291893Y-217897D01*
X291493Y-216964D01*
X291293Y-215897D01*
Y-214831D01*
X291493Y-213764D01*
X291893Y-212831D01*
X292493Y-212031D01*
X293193Y-211497D01*
X293993Y-211364D01*
X294793Y-211497D01*
X295493Y-212031D01*
X296093Y-212831D01*
X296493Y-213764D01*
X296693Y-214831D01*
Y-215897D01*
X296493Y-216964D01*
X296093Y-217897D01*
X295493Y-218697D01*
X294793Y-219231D01*
X293993Y-219364D01*
G01X301993Y-211364D02*
Y-219364D01*
G01X299693Y-211364D02*
X304293D01*
G01X252213Y119882D02*
Y115282D01*
G01X257313Y119882D02*
Y115282D01*
G01X262413Y119882D02*
X252213D01*
G01Y115282D02*
X262413D01*
G01X253573Y108997D02*
X259773D01*
G01Y112197D02*
X253573D01*
G01D02*
Y108997D01*
G01X250762Y190300D02*
X250917Y190070D01*
X251020Y189802D01*
Y189495D01*
X250865Y189150D01*
X250607Y188882D01*
X250297Y188690D01*
X249780Y188537D01*
X249315Y188499D01*
X248850Y188575D01*
X248540Y188690D01*
X248230Y188920D01*
X248023Y189189D01*
X247920Y189457D01*
Y189725D01*
X248023Y189994D01*
X248178Y190224D01*
X248385Y190415D01*
G01X249212Y191829D02*
X249573Y192097D01*
X249780Y192327D01*
X249883Y192634D01*
X249780Y192902D01*
X249573Y193094D01*
X249263Y193247D01*
X248902Y193285D01*
X248592Y193247D01*
X248282Y193094D01*
X248023Y192864D01*
X247920Y192595D01*
X248023Y192289D01*
X248333Y192020D01*
X248798Y191867D01*
X249315Y191829D01*
X249987Y191905D01*
X250348Y192020D01*
X250710Y192212D01*
X250968Y192480D01*
X251020Y192749D01*
X250917Y193017D01*
X250658Y193209D01*
G01X248540Y194814D02*
X248178Y195044D01*
X247972Y195350D01*
X247920Y195695D01*
X247972Y196002D01*
X248230Y196309D01*
X248540Y196500D01*
X248850Y196539D01*
X249212Y196462D01*
X249470Y196194D01*
X249573Y195925D01*
Y195580D01*
G01Y195925D02*
X249728Y196155D01*
X249987Y196347D01*
X250297Y196424D01*
X250607Y196347D01*
X250865Y196155D01*
X251020Y195810D01*
X250968Y195465D01*
X250762Y195120D01*
G01X258697Y204307D02*
Y207407D01*
X257738D01*
X257432Y207252D01*
X257240Y207045D01*
X257163Y206632D01*
X257240Y206219D01*
X257470Y205960D01*
X257738Y205805D01*
X258697D01*
G01X257738D02*
X257163Y204307D01*
G01X254830D02*
Y207407D01*
X255290Y206787D01*
G01Y204307D02*
X254370D01*
G01X252458Y206890D02*
X252228Y207200D01*
X251960Y207355D01*
X251653Y207407D01*
X251270Y207304D01*
X251002Y207045D01*
X250925Y206735D01*
X250963Y206425D01*
X251117Y206167D01*
X251883Y205650D01*
X252228Y205289D01*
X252458Y204772D01*
X252535Y204307D01*
X250925D01*
G01X248630D02*
Y207407D01*
X249090Y206787D01*
G01Y204307D02*
X248170D01*
G01X246258Y205599D02*
X245990Y205960D01*
X245760Y206167D01*
X245453Y206270D01*
X245185Y206167D01*
X244993Y205960D01*
X244840Y205650D01*
X244802Y205289D01*
X244840Y204979D01*
X244993Y204669D01*
X245223Y204410D01*
X245492Y204307D01*
X245798Y204410D01*
X246067Y204720D01*
X246220Y205185D01*
X246258Y205702D01*
X246182Y206374D01*
X246067Y206735D01*
X245875Y207097D01*
X245607Y207355D01*
X245338Y207407D01*
X245070Y207304D01*
X244878Y207045D01*
G01X250489Y235765D02*
X250719Y235920D01*
X250987Y236023D01*
X251294D01*
X251639Y235868D01*
X251907Y235610D01*
X252099Y235300D01*
X252252Y234783D01*
X252290Y234318D01*
X252214Y233853D01*
X252099Y233543D01*
X251869Y233233D01*
X251600Y233026D01*
X251332Y232923D01*
X251064D01*
X250795Y233026D01*
X250565Y233181D01*
X250374Y233388D01*
G01X248232Y232923D02*
Y236023D01*
X248692Y235403D01*
G01Y232923D02*
X247772D01*
G01X244672D02*
Y236023D01*
X246090Y233801D01*
X244174D01*
G01X252099Y224721D02*
Y227821D01*
X251140D01*
X250834Y227666D01*
X250642Y227459D01*
X250565Y227046D01*
X250642Y226633D01*
X250872Y226374D01*
X251140Y226219D01*
X252099D01*
G01X251140D02*
X250565Y224721D01*
G01X248960Y227304D02*
X248730Y227614D01*
X248462Y227769D01*
X248155Y227821D01*
X247772Y227718D01*
X247504Y227459D01*
X247427Y227149D01*
X247465Y226839D01*
X247619Y226581D01*
X248385Y226064D01*
X248730Y225703D01*
X248960Y225186D01*
X249037Y224721D01*
X247427D01*
G01X245209D02*
X245132Y225393D01*
X245017Y225961D01*
X244864Y226478D01*
X244672Y227046D01*
X244365Y227821D01*
X245899D01*
G01X252099Y228952D02*
Y232052D01*
X251140D01*
X250834Y231897D01*
X250642Y231690D01*
X250565Y231277D01*
X250642Y230864D01*
X250872Y230605D01*
X251140Y230450D01*
X252099D01*
G01X251140D02*
X250565Y228952D01*
G01X249075Y229572D02*
X248845Y229210D01*
X248539Y229004D01*
X248194Y228952D01*
X247887Y229004D01*
X247580Y229262D01*
X247389Y229572D01*
X247350Y229882D01*
X247427Y230244D01*
X247695Y230502D01*
X247964Y230605D01*
X248309D01*
G01X247964D02*
X247734Y230760D01*
X247542Y231019D01*
X247465Y231329D01*
X247542Y231639D01*
X247734Y231897D01*
X248079Y232052D01*
X248424Y232000D01*
X248769Y231794D01*
G01X245132Y228952D02*
Y232052D01*
X245592Y231432D01*
G01Y228952D02*
X244672D01*
G01X256663Y244371D02*
X259863D01*
G01X256663Y250571D02*
Y244371D01*
G01X256763Y247471D02*
X259763D01*
G01X246739Y240628D02*
Y243828D01*
G01Y244628D02*
Y247828D01*
G01X249312Y245329D02*
X255512D01*
G01D02*
Y248529D01*
G01D02*
X249312D01*
G01D02*
Y245329D01*
G01X249347Y252717D02*
Y249517D01*
G01D02*
X255547D01*
G01D02*
Y252717D01*
G01X255940Y258670D02*
X250614D01*
G01X255940D02*
Y259459D01*
G01Y265012D02*
Y263691D01*
G01X250899Y263733D02*
X253899D01*
G01X253999Y260633D02*
Y266833D01*
G01X250799D02*
Y260633D01*
G01D02*
X253999D01*
G01X252447Y253617D02*
Y256617D01*
G01X255547Y256717D02*
X249347D01*
G01D02*
Y253517D01*
G01D02*
X255547D01*
G01D02*
Y256717D01*
G01X259863Y250571D02*
X256663D01*
G01X243034Y267727D02*
Y261527D01*
G01D02*
X246234D01*
G01D02*
Y267727D01*
G01X255547Y252717D02*
X249347D01*
G01X261740Y266960D02*
X258494D01*
G01X243125Y276517D02*
Y282717D01*
G01X245447Y279617D02*
X248447D01*
G01X248547Y276517D02*
Y282717D01*
G01X245347D02*
Y276517D01*
G01D02*
X248547D01*
G01X252518Y279487D02*
Y276487D01*
G01X249418Y276387D02*
X255618D01*
G01D02*
Y279587D01*
G01D02*
X249418D01*
G01D02*
Y276387D01*
G01X250225Y275542D02*
X247025D01*
G01X250125Y272442D02*
X247125D01*
G01X247025Y275542D02*
Y269342D01*
G01D02*
X250225D01*
G01D02*
Y275542D01*
G01X246080Y275401D02*
X242880D01*
G01X245980Y272301D02*
X242980D01*
G01X242880Y275401D02*
Y269201D01*
G01D02*
X246080D01*
G01D02*
Y275401D01*
G01X253999Y266833D02*
X250799D01*
G01X261743Y277146D02*
X258543D01*
G01D02*
Y270946D01*
G01D02*
X261743D01*
G01X253861Y270360D02*
X250661D01*
G01X253861Y271060D02*
X250661D01*
G01Y273810D02*
Y267610D01*
G01D02*
X253861D01*
G01D02*
Y273810D01*
G01D02*
X250661D01*
G01X246234Y267727D02*
X243034D01*
G01X248941Y292509D02*
Y295509D01*
G01X252041Y295609D02*
X245841D01*
G01D02*
Y292409D01*
G01D02*
X252041D01*
G01D02*
Y295609D01*
G01X257697Y287957D02*
Y294157D01*
G01D02*
X254497D01*
G01X257597Y291057D02*
X254597D01*
G01X254497Y294157D02*
Y287957D01*
G01D02*
X257697D01*
G01X257618Y282802D02*
Y286002D01*
G01X254518Y285902D02*
Y282902D01*
G01X251418Y282802D02*
X257618D01*
G01Y286002D02*
X251418D01*
G01D02*
Y282802D01*
G01X245518Y286487D02*
X248518D01*
G01X248618Y283387D02*
Y289587D01*
G01D02*
X245418D01*
G01D02*
Y283387D01*
G01D02*
X248618D01*
G01X248547Y282717D02*
X245347D01*
G01X246750Y311679D02*
X249750D01*
G01X249850Y308579D02*
Y314779D01*
G01X246650D02*
Y308579D01*
G01D02*
X249850D01*
G01X250750Y311679D02*
X253750D01*
G01X253850Y308579D02*
Y314779D01*
G01X250650D02*
Y308579D01*
G01D02*
X253850D01*
G01X245959Y311126D02*
Y317326D01*
G01X248879Y297848D02*
Y300848D01*
G01X251979Y300948D02*
X245779D01*
G01D02*
Y297748D01*
G01D02*
X251979D01*
G01D02*
Y300948D01*
G01X264618Y308587D02*
X258418D01*
G01D02*
Y305387D01*
G01D02*
X264618D01*
G01X257511Y321450D02*
X261135D01*
G01X255740Y326064D02*
Y325421D01*
G01X257818Y313887D02*
Y320087D01*
G01X257718Y316987D02*
X254718D01*
G01X254618Y320087D02*
Y313887D01*
G01D02*
X257818D01*
G01Y320087D02*
X254618D01*
G01X249731Y323432D02*
X252731D01*
G01X252831Y326532D02*
X249631D01*
G01X252831Y320332D02*
Y326532D01*
G01X249631D02*
Y320332D01*
G01D02*
X252831D01*
G01X249850Y314779D02*
X246650D01*
G01X253850D02*
X250650D01*
G01X245859Y314226D02*
X242859D01*
G01X246501Y318196D02*
Y328396D01*
G01X253640Y329640D02*
X253103D01*
G01X246732Y340903D02*
X246887Y340673D01*
X246990Y340405D01*
Y340098D01*
X246835Y339753D01*
X246577Y339485D01*
X246267Y339293D01*
X245750Y339140D01*
X245285Y339102D01*
X244820Y339178D01*
X244510Y339293D01*
X244200Y339523D01*
X243993Y339792D01*
X243890Y340060D01*
Y340328D01*
X243993Y340597D01*
X244148Y340827D01*
X244355Y341018D01*
G01X243890Y343083D02*
X244562Y343160D01*
X245130Y343275D01*
X245647Y343428D01*
X246215Y343620D01*
X246990Y343927D01*
Y342393D01*
G01X245182Y345532D02*
X245543Y345800D01*
X245750Y346030D01*
X245853Y346337D01*
X245750Y346605D01*
X245543Y346797D01*
X245233Y346950D01*
X244872Y346988D01*
X244562Y346950D01*
X244252Y346797D01*
X243993Y346567D01*
X243890Y346298D01*
X243993Y345992D01*
X244303Y345723D01*
X244768Y345570D01*
X245285Y345532D01*
X245957Y345608D01*
X246318Y345723D01*
X246680Y345915D01*
X246938Y346183D01*
X246990Y346452D01*
X246887Y346720D01*
X246628Y346912D01*
G01X245212Y331760D02*
Y337960D01*
G01X257599Y341261D02*
X257754Y341031D01*
X257857Y340763D01*
Y340456D01*
X257702Y340111D01*
X257444Y339843D01*
X257134Y339651D01*
X256617Y339498D01*
X256152Y339460D01*
X255687Y339536D01*
X255377Y339651D01*
X255067Y339881D01*
X254860Y340150D01*
X254757Y340418D01*
Y340686D01*
X254860Y340955D01*
X255015Y341185D01*
X255222Y341376D01*
G01X254757Y343441D02*
X255429Y343518D01*
X255997Y343633D01*
X256514Y343786D01*
X257082Y343978D01*
X257857Y344285D01*
Y342751D01*
G01X254757Y347078D02*
X257857D01*
X255635Y345660D01*
Y347576D01*
G01X254017Y343325D02*
X249417D01*
G01D02*
Y333125D01*
G01D02*
X254017D01*
G01D02*
Y343325D01*
G01X249417Y338225D02*
X254017D01*
G01X247167Y358572D02*
X250267D01*
Y359531D01*
X250112Y359837D01*
X249905Y360029D01*
X249492Y360106D01*
X249079Y360029D01*
X248820Y359799D01*
X248665Y359531D01*
Y358572D01*
G01Y359531D02*
X247167Y360106D01*
G01X247632Y361596D02*
X247374Y361826D01*
X247219Y362094D01*
X247167Y362439D01*
X247270Y362784D01*
X247477Y363052D01*
X247839Y363244D01*
X248252Y363282D01*
X248665Y363206D01*
X248924Y363014D01*
X249130Y362746D01*
X249182Y362477D01*
X249130Y362209D01*
X248924Y361864D01*
X250267Y361979D01*
Y363014D01*
G01X247529Y364887D02*
X247270Y365156D01*
X247167Y365462D01*
X247270Y365769D01*
X247580Y366037D01*
X248045Y366229D01*
X248510Y366306D01*
X249079D01*
X249544Y366229D01*
X249957Y366037D01*
X250164Y365807D01*
X250267Y365539D01*
X250164Y365232D01*
X249957Y365002D01*
X249647Y364849D01*
X249234Y364772D01*
X248872Y364849D01*
X248510Y365041D01*
X248304Y365271D01*
X248252Y365539D01*
X248355Y365846D01*
X248614Y366076D01*
X249079Y366306D01*
G01X245588Y375550D02*
Y378750D01*
G01X250290Y387408D02*
Y393608D01*
G01X247090D02*
Y387408D01*
G01D02*
X250290D01*
G01X250287Y377596D02*
Y383796D01*
G01D02*
X247087D01*
G01D02*
Y377596D01*
G01D02*
X250287D01*
G01X254287D02*
Y383796D01*
G01D02*
X251087D01*
G01D02*
Y377596D01*
G01D02*
X254287D01*
G01X246274Y379597D02*
Y382797D01*
G01X257087Y393577D02*
Y387377D01*
G01D02*
X260287D01*
G01X258287Y377596D02*
Y383796D01*
G01D02*
X255087D01*
G01D02*
Y377596D01*
G01D02*
X258287D01*
G01X247308Y394806D02*
X250408D01*
Y395765D01*
X250253Y396071D01*
X250046Y396263D01*
X249633Y396340D01*
X249220Y396263D01*
X248961Y396033D01*
X248806Y395765D01*
Y394806D01*
G01Y395765D02*
X247308Y396340D01*
G01Y398596D02*
X247980Y398673D01*
X248548Y398788D01*
X249065Y398941D01*
X249633Y399133D01*
X250408Y399440D01*
Y397906D01*
G01Y401773D02*
X250305Y401466D01*
X250046Y401236D01*
X249736Y401083D01*
X249323Y400968D01*
X248858Y400930D01*
X248393Y400968D01*
X247980Y401083D01*
X247670Y401236D01*
X247411Y401466D01*
X247308Y401773D01*
X247411Y402080D01*
X247670Y402310D01*
X247980Y402463D01*
X248393Y402578D01*
X248858Y402616D01*
X249323Y402578D01*
X249736Y402463D01*
X250046Y402310D01*
X250305Y402080D01*
X250408Y401773D01*
G01X250290Y393608D02*
X247090D01*
G01X257792Y395174D02*
X260892D01*
Y396133D01*
X260737Y396439D01*
X260530Y396631D01*
X260117Y396708D01*
X259704Y396631D01*
X259445Y396401D01*
X259290Y396133D01*
Y395174D01*
G01Y396133D02*
X257792Y396708D01*
G01Y398964D02*
X258464Y399041D01*
X259032Y399156D01*
X259549Y399309D01*
X260117Y399501D01*
X260892Y399808D01*
Y398274D01*
G01X258257Y401298D02*
X257999Y401528D01*
X257844Y401796D01*
X257792Y402141D01*
X257895Y402486D01*
X258102Y402754D01*
X258464Y402946D01*
X258877Y402984D01*
X259290Y402908D01*
X259549Y402716D01*
X259755Y402448D01*
X259807Y402179D01*
X259755Y401911D01*
X259549Y401566D01*
X260892Y401681D01*
Y402716D01*
G01X260287Y393577D02*
X257087D01*
G01X249649Y448091D02*
X252749D01*
Y449050D01*
X252594Y449356D01*
X252387Y449548D01*
X251974Y449625D01*
X251561Y449548D01*
X251302Y449318D01*
X251147Y449050D01*
Y448091D01*
G01Y449050D02*
X249649Y449625D01*
G01X250269Y451115D02*
X249907Y451345D01*
X249701Y451651D01*
X249649Y451996D01*
X249701Y452303D01*
X249959Y452610D01*
X250269Y452801D01*
X250579Y452840D01*
X250941Y452763D01*
X251199Y452495D01*
X251302Y452226D01*
Y451881D01*
G01Y452226D02*
X251457Y452456D01*
X251716Y452648D01*
X252026Y452725D01*
X252336Y452648D01*
X252594Y452456D01*
X252749Y452111D01*
X252697Y451766D01*
X252491Y451421D01*
G01X252232Y454330D02*
X252542Y454560D01*
X252697Y454828D01*
X252749Y455135D01*
X252646Y455518D01*
X252387Y455786D01*
X252077Y455863D01*
X251767Y455825D01*
X251509Y455671D01*
X250992Y454905D01*
X250631Y454560D01*
X250114Y454330D01*
X249649Y454253D01*
Y455863D01*
G01X252749Y458158D02*
X252646Y457851D01*
X252387Y457621D01*
X252077Y457468D01*
X251664Y457353D01*
X251199Y457315D01*
X250734Y457353D01*
X250321Y457468D01*
X250011Y457621D01*
X249752Y457851D01*
X249649Y458158D01*
X249752Y458465D01*
X250011Y458695D01*
X250321Y458848D01*
X250734Y458963D01*
X251199Y459001D01*
X251664Y458963D01*
X252077Y458848D01*
X252387Y458695D01*
X252646Y458465D01*
X252749Y458158D01*
G01X253692Y448028D02*
X256792D01*
Y448987D01*
X256637Y449293D01*
X256430Y449485D01*
X256017Y449562D01*
X255604Y449485D01*
X255345Y449255D01*
X255190Y448987D01*
Y448028D01*
G01Y448987D02*
X253692Y449562D01*
G01X254312Y451052D02*
X253950Y451282D01*
X253744Y451588D01*
X253692Y451933D01*
X253744Y452240D01*
X254002Y452547D01*
X254312Y452738D01*
X254622Y452777D01*
X254984Y452700D01*
X255242Y452432D01*
X255345Y452163D01*
Y451818D01*
G01Y452163D02*
X255500Y452393D01*
X255759Y452585D01*
X256069Y452662D01*
X256379Y452585D01*
X256637Y452393D01*
X256792Y452048D01*
X256740Y451703D01*
X256534Y451358D01*
G01X254312Y454152D02*
X253950Y454382D01*
X253744Y454688D01*
X253692Y455033D01*
X253744Y455340D01*
X254002Y455647D01*
X254312Y455838D01*
X254622Y455877D01*
X254984Y455800D01*
X255242Y455532D01*
X255345Y455263D01*
Y454918D01*
G01Y455263D02*
X255500Y455493D01*
X255759Y455685D01*
X256069Y455762D01*
X256379Y455685D01*
X256637Y455493D01*
X256792Y455148D01*
X256740Y454803D01*
X256534Y454458D01*
G01X253692Y458555D02*
X256792D01*
X254570Y457137D01*
Y459053D01*
G01X257737Y448028D02*
X260837D01*
Y448987D01*
X260682Y449293D01*
X260475Y449485D01*
X260062Y449562D01*
X259649Y449485D01*
X259390Y449255D01*
X259235Y448987D01*
Y448028D01*
G01Y448987D02*
X257737Y449562D01*
G01X258357Y451052D02*
X257995Y451282D01*
X257789Y451588D01*
X257737Y451933D01*
X257789Y452240D01*
X258047Y452547D01*
X258357Y452738D01*
X258667Y452777D01*
X259029Y452700D01*
X259287Y452432D01*
X259390Y452163D01*
Y451818D01*
G01Y452163D02*
X259545Y452393D01*
X259804Y452585D01*
X260114Y452662D01*
X260424Y452585D01*
X260682Y452393D01*
X260837Y452048D01*
X260785Y451703D01*
X260579Y451358D01*
G01X258357Y454152D02*
X257995Y454382D01*
X257789Y454688D01*
X257737Y455033D01*
X257789Y455340D01*
X258047Y455647D01*
X258357Y455838D01*
X258667Y455877D01*
X259029Y455800D01*
X259287Y455532D01*
X259390Y455263D01*
Y454918D01*
G01Y455263D02*
X259545Y455493D01*
X259804Y455685D01*
X260114Y455762D01*
X260424Y455685D01*
X260682Y455493D01*
X260837Y455148D01*
X260785Y454803D01*
X260579Y454458D01*
G01X258357Y457252D02*
X257995Y457482D01*
X257789Y457788D01*
X257737Y458133D01*
X257789Y458440D01*
X258047Y458747D01*
X258357Y458938D01*
X258667Y458977D01*
X259029Y458900D01*
X259287Y458632D01*
X259390Y458363D01*
Y458018D01*
G01Y458363D02*
X259545Y458593D01*
X259804Y458785D01*
X260114Y458862D01*
X260424Y458785D01*
X260682Y458593D01*
X260837Y458248D01*
X260785Y457903D01*
X260579Y457558D01*
G01X243579Y465053D02*
Y471253D01*
G01X249709Y464553D02*
X252909D01*
G01X249709Y470753D02*
Y464553D01*
G01X252909D02*
Y470753D01*
G01D02*
X249709D01*
G01X253909Y464453D02*
X257109D01*
G01X253909Y470653D02*
Y464453D01*
G01X257109Y470653D02*
X253909D01*
G01X257109Y464453D02*
Y470653D01*
G01X243509Y473453D02*
Y479653D01*
G01X252909D02*
X249709D01*
G01X252909Y473453D02*
Y479653D01*
G01X249709Y473453D02*
X252909D01*
G01X249709Y479653D02*
Y473453D01*
G01X257109Y479653D02*
X253909D01*
G01Y473453D02*
X257109D01*
G01X253909Y479653D02*
Y473453D01*
G01X257109D02*
Y479653D01*
G01X247689Y479704D02*
X244489D01*
G01X247689Y473504D02*
Y479704D01*
G01X244489Y473504D02*
X247689D01*
G01X244489Y479704D02*
Y473504D01*
G01X251470Y506670D02*
X250460D01*
G01X254590D02*
X253560D01*
G01X281440D02*
X256630D01*
G01X244518Y509865D02*
Y513065D01*
G01X244543Y513849D02*
Y517049D01*
G01X256548Y517919D02*
X253548D01*
G01X253448Y514819D02*
X256648D01*
G01X253448Y521019D02*
Y514819D01*
G01X256648D02*
Y521019D01*
G01X251809Y515253D02*
Y521453D01*
G01X248609Y515253D02*
X251809D01*
G01X248609Y521453D02*
Y515253D01*
G01X260500Y517931D02*
X257500D01*
G01X257400Y514831D02*
X260600D01*
G01X257400Y521031D02*
Y514831D01*
G01X257148Y507890D02*
X260348D01*
G01X257148Y514090D02*
Y507890D01*
G01X260348Y514090D02*
X257148D01*
G01X244805Y526237D02*
Y529237D01*
G01X247905Y526137D02*
Y529337D01*
G01X244815Y521214D02*
Y518214D01*
G01X247915Y518114D02*
Y521314D01*
G01X244805Y525232D02*
Y522232D01*
G01X247905Y522132D02*
Y525332D01*
G01X244855Y530281D02*
Y533281D01*
G01X247955Y530181D02*
Y533381D01*
G01X256648Y521019D02*
X253448D01*
G01X251709Y518353D02*
X248709D01*
G01X251809Y521453D02*
X248609D01*
G01X260600Y521031D02*
X257400D01*
G01X244841Y534289D02*
Y537289D01*
G01X247941Y534189D02*
Y537389D01*
G01X243959Y542462D02*
Y545462D01*
G01X247059Y542362D02*
Y545562D01*
G01X244995Y538289D02*
Y541289D01*
G01X248095Y538189D02*
Y541389D01*
G01X247809Y549053D02*
Y555253D01*
G01X244609Y549053D02*
X247809D01*
G01X244609Y555253D02*
Y549053D01*
G01X254868Y548412D02*
Y545412D01*
G01X251768Y548512D02*
Y545312D01*
G01D02*
X257968D01*
G01Y548512D02*
X251768D01*
G01X257968Y545312D02*
Y548512D01*
G01X254848Y544389D02*
Y541389D01*
G01X251748Y544489D02*
Y541289D01*
G01X257948Y544489D02*
X251748D01*
G01Y541289D02*
X257948D01*
G01D02*
Y544489D01*
G01X247768Y542403D02*
X250968D01*
G01X247768Y548603D02*
Y542403D01*
G01X250968D02*
Y548603D01*
G01X247868Y545503D02*
X250868D01*
G01X250968Y548603D02*
X247768D01*
G01X247160Y558210D02*
X251650D01*
G01X244230D02*
X245500D01*
G01X256770D02*
X267180D01*
G01X253300D02*
X254950D01*
G01X253309Y554353D02*
X250309D01*
G01X253409Y557453D02*
X250209D01*
G01X253409Y551253D02*
Y557453D01*
G01X250209Y551253D02*
X253409D01*
G01X250209Y557453D02*
Y551253D01*
G01X247709Y552153D02*
X244709D01*
G01X247809Y555253D02*
X244609D01*
G01X251664Y560353D02*
Y563353D01*
G01X254764Y560253D02*
Y563453D01*
G01X248564Y560253D02*
X254764D01*
G01X248564Y563453D02*
Y560253D01*
G01X254764Y563453D02*
X248564D01*
G01X266685Y566906D02*
X266915Y567061D01*
X267183Y567164D01*
X267490D01*
X267835Y567009D01*
X268103Y566751D01*
X268295Y566441D01*
X268448Y565924D01*
X268486Y565459D01*
X268410Y564994D01*
X268295Y564684D01*
X268065Y564374D01*
X267796Y564167D01*
X267528Y564064D01*
X267260D01*
X266991Y564167D01*
X266761Y564322D01*
X266570Y564529D01*
G01X265156Y566647D02*
X264926Y566957D01*
X264658Y567112D01*
X264351Y567164D01*
X263968Y567061D01*
X263700Y566802D01*
X263623Y566492D01*
X263661Y566182D01*
X263815Y565924D01*
X264581Y565407D01*
X264926Y565046D01*
X265156Y564529D01*
X265233Y564064D01*
X263623D01*
G01X262171Y564529D02*
X261941Y564271D01*
X261673Y564116D01*
X261328Y564064D01*
X260983Y564167D01*
X260715Y564374D01*
X260523Y564736D01*
X260485Y565149D01*
X260561Y565562D01*
X260753Y565821D01*
X261021Y566027D01*
X261290Y566079D01*
X261558Y566027D01*
X261903Y565821D01*
X261788Y567164D01*
X260753D01*
G01X258305Y564064D02*
X258228Y564736D01*
X258113Y565304D01*
X257960Y565821D01*
X257768Y566389D01*
X257461Y567164D01*
X258995D01*
G01X251664Y564653D02*
Y567653D01*
G01X254764Y564553D02*
Y567753D01*
G01X248564Y564553D02*
X254764D01*
G01X248564Y567753D02*
Y564553D01*
G01X254764Y567753D02*
X248564D01*
G01X257538Y576856D02*
X254438D01*
Y578390D01*
G01Y580723D02*
X257538D01*
X256918Y580263D01*
G01X254438D02*
Y581183D01*
G01Y584283D02*
X257538D01*
X255316Y582865D01*
Y584781D01*
G01X247809Y574509D02*
X252409D01*
G01X247609Y569909D02*
X252609D01*
G01D02*
Y580109D01*
G01X247609D02*
Y569909D01*
G01X247809Y575509D02*
X252409D01*
G01X247609Y580109D02*
X252609D01*
G01X246023Y701550D02*
Y704750D01*
G01X246840Y737556D02*
X250040D01*
G01X246840Y743756D02*
Y737556D01*
G01X250040D02*
Y743756D01*
G01X245540Y726056D02*
Y732256D01*
G01X255840Y737556D02*
X259040D01*
G01X255840Y743756D02*
Y737556D01*
G01X251340D02*
X254540D01*
G01X251340Y743756D02*
Y737556D01*
G01X254540D02*
Y743756D01*
G01X259039Y732256D02*
X255841D01*
G01Y726056D02*
X259039D01*
G01X255841Y732256D02*
Y726056D01*
G01X245540Y737556D02*
Y743756D01*
G01X254540Y732256D02*
X251340D01*
G01Y726056D02*
X254540D01*
G01X251340Y732256D02*
Y726056D01*
G01X254540D02*
Y732256D01*
G01X250039D02*
X246841D01*
G01X250039Y726056D02*
Y732256D01*
G01X246841Y726056D02*
X250039D01*
G01X246841Y732256D02*
Y726056D01*
G01X250040Y743756D02*
X246840D01*
G01X246940Y740656D02*
X249940D01*
G01X259040Y743756D02*
X255840D01*
G01X255940Y740656D02*
X258940D01*
G01X254540Y743756D02*
X251340D01*
G01X251440Y740656D02*
X254440D01*
G01X256902Y745884D02*
X260002D01*
Y746843D01*
X259847Y747149D01*
X259640Y747341D01*
X259227Y747418D01*
X258814Y747341D01*
X258555Y747111D01*
X258400Y746843D01*
Y745884D01*
G01Y746843D02*
X256902Y747418D01*
G01Y749751D02*
X256954Y750019D01*
X257109Y750326D01*
X257367Y750518D01*
X257729Y750594D01*
X258090Y750518D01*
X258400Y750288D01*
X258555Y749943D01*
Y749559D01*
X258659Y749329D01*
X258917Y749138D01*
X259279Y749061D01*
X259640Y749176D01*
X259899Y749444D01*
X260002Y749751D01*
X259899Y750058D01*
X259640Y750326D01*
X259279Y750441D01*
X258917Y750364D01*
X258659Y750173D01*
X258555Y749943D01*
Y749559D01*
X258400Y749214D01*
X258090Y748984D01*
X257729Y748908D01*
X257367Y748984D01*
X257109Y749176D01*
X256954Y749483D01*
X256902Y749751D01*
G01X258194Y752123D02*
X258555Y752391D01*
X258762Y752621D01*
X258865Y752928D01*
X258762Y753196D01*
X258555Y753388D01*
X258245Y753541D01*
X257884Y753579D01*
X257574Y753541D01*
X257264Y753388D01*
X257005Y753158D01*
X256902Y752889D01*
X257005Y752583D01*
X257315Y752314D01*
X257780Y752161D01*
X258297Y752123D01*
X258969Y752199D01*
X259330Y752314D01*
X259692Y752506D01*
X259950Y752774D01*
X260002Y753043D01*
X259899Y753311D01*
X259640Y753503D01*
G01X259485Y755223D02*
X259795Y755453D01*
X259950Y755721D01*
X260002Y756028D01*
X259899Y756411D01*
X259640Y756679D01*
X259330Y756756D01*
X259020Y756718D01*
X258762Y756564D01*
X258245Y755798D01*
X257884Y755453D01*
X257367Y755223D01*
X256902Y755146D01*
Y756756D01*
G01X252041Y745884D02*
X255141D01*
Y746843D01*
X254986Y747149D01*
X254779Y747341D01*
X254366Y747418D01*
X253953Y747341D01*
X253694Y747111D01*
X253539Y746843D01*
Y745884D01*
G01Y746843D02*
X252041Y747418D01*
G01Y749751D02*
X252093Y750019D01*
X252248Y750326D01*
X252506Y750518D01*
X252868Y750594D01*
X253229Y750518D01*
X253539Y750288D01*
X253694Y749943D01*
Y749559D01*
X253798Y749329D01*
X254056Y749138D01*
X254418Y749061D01*
X254779Y749176D01*
X255038Y749444D01*
X255141Y749751D01*
X255038Y750058D01*
X254779Y750326D01*
X254418Y750441D01*
X254056Y750364D01*
X253798Y750173D01*
X253694Y749943D01*
Y749559D01*
X253539Y749214D01*
X253229Y748984D01*
X252868Y748908D01*
X252506Y748984D01*
X252248Y749176D01*
X252093Y749483D01*
X252041Y749751D01*
G01X253333Y752123D02*
X253694Y752391D01*
X253901Y752621D01*
X254004Y752928D01*
X253901Y753196D01*
X253694Y753388D01*
X253384Y753541D01*
X253023Y753579D01*
X252713Y753541D01*
X252403Y753388D01*
X252144Y753158D01*
X252041Y752889D01*
X252144Y752583D01*
X252454Y752314D01*
X252919Y752161D01*
X253436Y752123D01*
X254108Y752199D01*
X254469Y752314D01*
X254831Y752506D01*
X255089Y752774D01*
X255141Y753043D01*
X255038Y753311D01*
X254779Y753503D01*
G01X252506Y755108D02*
X252248Y755338D01*
X252093Y755606D01*
X252041Y755951D01*
X252144Y756296D01*
X252351Y756564D01*
X252713Y756756D01*
X253126Y756794D01*
X253539Y756718D01*
X253798Y756526D01*
X254004Y756258D01*
X254056Y755989D01*
X254004Y755721D01*
X253798Y755376D01*
X255141Y755491D01*
Y756526D01*
G01X247673Y745884D02*
X250773D01*
Y746843D01*
X250618Y747149D01*
X250411Y747341D01*
X249998Y747418D01*
X249585Y747341D01*
X249326Y747111D01*
X249171Y746843D01*
Y745884D01*
G01Y746843D02*
X247673Y747418D01*
G01Y749751D02*
X247725Y750019D01*
X247880Y750326D01*
X248138Y750518D01*
X248500Y750594D01*
X248861Y750518D01*
X249171Y750288D01*
X249326Y749943D01*
Y749559D01*
X249430Y749329D01*
X249688Y749138D01*
X250050Y749061D01*
X250411Y749176D01*
X250670Y749444D01*
X250773Y749751D01*
X250670Y750058D01*
X250411Y750326D01*
X250050Y750441D01*
X249688Y750364D01*
X249430Y750173D01*
X249326Y749943D01*
Y749559D01*
X249171Y749214D01*
X248861Y748984D01*
X248500Y748908D01*
X248138Y748984D01*
X247880Y749176D01*
X247725Y749483D01*
X247673Y749751D01*
G01X248965Y752123D02*
X249326Y752391D01*
X249533Y752621D01*
X249636Y752928D01*
X249533Y753196D01*
X249326Y753388D01*
X249016Y753541D01*
X248655Y753579D01*
X248345Y753541D01*
X248035Y753388D01*
X247776Y753158D01*
X247673Y752889D01*
X247776Y752583D01*
X248086Y752314D01*
X248551Y752161D01*
X249068Y752123D01*
X249740Y752199D01*
X250101Y752314D01*
X250463Y752506D01*
X250721Y752774D01*
X250773Y753043D01*
X250670Y753311D01*
X250411Y753503D01*
G01X247673Y755951D02*
X247725Y756219D01*
X247880Y756526D01*
X248138Y756718D01*
X248500Y756794D01*
X248861Y756718D01*
X249171Y756488D01*
X249326Y756143D01*
Y755759D01*
X249430Y755529D01*
X249688Y755338D01*
X250050Y755261D01*
X250411Y755376D01*
X250670Y755644D01*
X250773Y755951D01*
X250670Y756258D01*
X250411Y756526D01*
X250050Y756641D01*
X249688Y756564D01*
X249430Y756373D01*
X249326Y756143D01*
Y755759D01*
X249171Y755414D01*
X248861Y755184D01*
X248500Y755108D01*
X248138Y755184D01*
X247880Y755376D01*
X247725Y755683D01*
X247673Y755951D01*
G01X249050Y759486D02*
X249205Y759256D01*
X249308Y758988D01*
Y758681D01*
X249153Y758336D01*
X248895Y758068D01*
X248585Y757876D01*
X248068Y757723D01*
X247603Y757685D01*
X247138Y757761D01*
X246828Y757876D01*
X246518Y758106D01*
X246311Y758375D01*
X246208Y758643D01*
Y758911D01*
X246311Y759180D01*
X246466Y759410D01*
X246673Y759601D01*
G01X247500Y761015D02*
X247861Y761283D01*
X248068Y761513D01*
X248171Y761820D01*
X248068Y762088D01*
X247861Y762280D01*
X247551Y762433D01*
X247190Y762471D01*
X246880Y762433D01*
X246570Y762280D01*
X246311Y762050D01*
X246208Y761781D01*
X246311Y761475D01*
X246621Y761206D01*
X247086Y761053D01*
X247603Y761015D01*
X248275Y761091D01*
X248636Y761206D01*
X248998Y761398D01*
X249256Y761666D01*
X249308Y761935D01*
X249205Y762203D01*
X248946Y762395D01*
G01X246828Y764000D02*
X246466Y764230D01*
X246260Y764536D01*
X246208Y764881D01*
X246260Y765188D01*
X246518Y765495D01*
X246828Y765686D01*
X247138Y765725D01*
X247500Y765648D01*
X247758Y765380D01*
X247861Y765111D01*
Y764766D01*
G01Y765111D02*
X248016Y765341D01*
X248275Y765533D01*
X248585Y765610D01*
X248895Y765533D01*
X249153Y765341D01*
X249308Y764996D01*
X249256Y764651D01*
X249050Y764306D01*
G01X246208Y767943D02*
X249308D01*
X248688Y767483D01*
G01X246208D02*
Y768403D01*
G01X257171Y759650D02*
X257326Y759420D01*
X257429Y759152D01*
Y758845D01*
X257274Y758500D01*
X257016Y758232D01*
X256706Y758040D01*
X256189Y757887D01*
X255724Y757849D01*
X255259Y757925D01*
X254949Y758040D01*
X254639Y758270D01*
X254432Y758539D01*
X254329Y758807D01*
Y759075D01*
X254432Y759344D01*
X254587Y759574D01*
X254794Y759765D01*
G01X255621Y761179D02*
X255982Y761447D01*
X256189Y761677D01*
X256292Y761984D01*
X256189Y762252D01*
X255982Y762444D01*
X255672Y762597D01*
X255311Y762635D01*
X255001Y762597D01*
X254691Y762444D01*
X254432Y762214D01*
X254329Y761945D01*
X254432Y761639D01*
X254742Y761370D01*
X255207Y761217D01*
X255724Y761179D01*
X256396Y761255D01*
X256757Y761370D01*
X257119Y761562D01*
X257377Y761830D01*
X257429Y762099D01*
X257326Y762367D01*
X257067Y762559D01*
G01X256912Y764279D02*
X257222Y764509D01*
X257377Y764777D01*
X257429Y765084D01*
X257326Y765467D01*
X257067Y765735D01*
X256757Y765812D01*
X256447Y765774D01*
X256189Y765620D01*
X255672Y764854D01*
X255311Y764509D01*
X254794Y764279D01*
X254329Y764202D01*
Y765812D01*
G01X254794Y767264D02*
X254536Y767494D01*
X254381Y767762D01*
X254329Y768107D01*
X254432Y768452D01*
X254639Y768720D01*
X255001Y768912D01*
X255414Y768950D01*
X255827Y768874D01*
X256086Y768682D01*
X256292Y768414D01*
X256344Y768145D01*
X256292Y767877D01*
X256086Y767532D01*
X257429Y767647D01*
Y768682D01*
G01X252848Y759650D02*
X253003Y759420D01*
X253106Y759152D01*
Y758845D01*
X252951Y758500D01*
X252693Y758232D01*
X252383Y758040D01*
X251866Y757887D01*
X251401Y757849D01*
X250936Y757925D01*
X250626Y758040D01*
X250316Y758270D01*
X250109Y758539D01*
X250006Y758807D01*
Y759075D01*
X250109Y759344D01*
X250264Y759574D01*
X250471Y759765D01*
G01X251298Y761179D02*
X251659Y761447D01*
X251866Y761677D01*
X251969Y761984D01*
X251866Y762252D01*
X251659Y762444D01*
X251349Y762597D01*
X250988Y762635D01*
X250678Y762597D01*
X250368Y762444D01*
X250109Y762214D01*
X250006Y761945D01*
X250109Y761639D01*
X250419Y761370D01*
X250884Y761217D01*
X251401Y761179D01*
X252073Y761255D01*
X252434Y761370D01*
X252796Y761562D01*
X253054Y761830D01*
X253106Y762099D01*
X253003Y762367D01*
X252744Y762559D01*
G01X252589Y764279D02*
X252899Y764509D01*
X253054Y764777D01*
X253106Y765084D01*
X253003Y765467D01*
X252744Y765735D01*
X252434Y765812D01*
X252124Y765774D01*
X251866Y765620D01*
X251349Y764854D01*
X250988Y764509D01*
X250471Y764279D01*
X250006Y764202D01*
Y765812D01*
G01Y768107D02*
X250058Y768375D01*
X250213Y768682D01*
X250471Y768874D01*
X250833Y768950D01*
X251194Y768874D01*
X251504Y768644D01*
X251659Y768299D01*
Y767915D01*
X251763Y767685D01*
X252021Y767494D01*
X252383Y767417D01*
X252744Y767532D01*
X253003Y767800D01*
X253106Y768107D01*
X253003Y768414D01*
X252744Y768682D01*
X252383Y768797D01*
X252021Y768720D01*
X251763Y768529D01*
X251659Y768299D01*
Y767915D01*
X251504Y767570D01*
X251194Y767340D01*
X250833Y767264D01*
X250471Y767340D01*
X250213Y767532D01*
X250058Y767839D01*
X250006Y768107D01*
G01X261908Y759650D02*
X262063Y759420D01*
X262166Y759152D01*
Y758845D01*
X262011Y758500D01*
X261753Y758232D01*
X261443Y758040D01*
X260926Y757887D01*
X260461Y757849D01*
X259996Y757925D01*
X259686Y758040D01*
X259376Y758270D01*
X259169Y758539D01*
X259066Y758807D01*
Y759075D01*
X259169Y759344D01*
X259324Y759574D01*
X259531Y759765D01*
G01X260358Y761179D02*
X260719Y761447D01*
X260926Y761677D01*
X261029Y761984D01*
X260926Y762252D01*
X260719Y762444D01*
X260409Y762597D01*
X260048Y762635D01*
X259738Y762597D01*
X259428Y762444D01*
X259169Y762214D01*
X259066Y761945D01*
X259169Y761639D01*
X259479Y761370D01*
X259944Y761217D01*
X260461Y761179D01*
X261133Y761255D01*
X261494Y761370D01*
X261856Y761562D01*
X262114Y761830D01*
X262166Y762099D01*
X262063Y762367D01*
X261804Y762559D01*
G01X261649Y764279D02*
X261959Y764509D01*
X262114Y764777D01*
X262166Y765084D01*
X262063Y765467D01*
X261804Y765735D01*
X261494Y765812D01*
X261184Y765774D01*
X260926Y765620D01*
X260409Y764854D01*
X260048Y764509D01*
X259531Y764279D01*
X259066Y764202D01*
Y765812D01*
G01X261649Y767379D02*
X261959Y767609D01*
X262114Y767877D01*
X262166Y768184D01*
X262063Y768567D01*
X261804Y768835D01*
X261494Y768912D01*
X261184Y768874D01*
X260926Y768720D01*
X260409Y767954D01*
X260048Y767609D01*
X259531Y767379D01*
X259066Y767302D01*
Y768912D01*
G01X269597Y62191D02*
X269752Y61961D01*
X269855Y61693D01*
Y61386D01*
X269700Y61041D01*
X269442Y60773D01*
X269132Y60581D01*
X268615Y60428D01*
X268150Y60390D01*
X267685Y60466D01*
X267375Y60581D01*
X267065Y60811D01*
X266858Y61080D01*
X266755Y61348D01*
Y61616D01*
X266858Y61885D01*
X267013Y62115D01*
X267220Y62306D01*
G01X266755Y64448D02*
X269855D01*
X269235Y63988D01*
G01X266755D02*
Y64908D01*
G01X267220Y66705D02*
X266962Y66935D01*
X266807Y67203D01*
X266755Y67548D01*
X266858Y67893D01*
X267065Y68161D01*
X267427Y68353D01*
X267840Y68391D01*
X268253Y68315D01*
X268512Y68123D01*
X268718Y67855D01*
X268770Y67586D01*
X268718Y67318D01*
X268512Y66973D01*
X269855Y67088D01*
Y68123D01*
G01X267220Y69805D02*
X266962Y70035D01*
X266807Y70303D01*
X266755Y70648D01*
X266858Y70993D01*
X267065Y71261D01*
X267427Y71453D01*
X267840Y71491D01*
X268253Y71415D01*
X268512Y71223D01*
X268718Y70955D01*
X268770Y70686D01*
X268718Y70418D01*
X268512Y70073D01*
X269855Y70188D01*
Y71223D01*
G01X277810Y62191D02*
X277965Y61961D01*
X278068Y61693D01*
Y61386D01*
X277913Y61041D01*
X277655Y60773D01*
X277345Y60581D01*
X276828Y60428D01*
X276363Y60390D01*
X275898Y60466D01*
X275588Y60581D01*
X275278Y60811D01*
X275071Y61080D01*
X274968Y61348D01*
Y61616D01*
X275071Y61885D01*
X275226Y62115D01*
X275433Y62306D01*
G01X274968Y64448D02*
X278068D01*
X277448Y63988D01*
G01X274968D02*
Y64908D01*
G01X275433Y66705D02*
X275175Y66935D01*
X275020Y67203D01*
X274968Y67548D01*
X275071Y67893D01*
X275278Y68161D01*
X275640Y68353D01*
X276053Y68391D01*
X276466Y68315D01*
X276725Y68123D01*
X276931Y67855D01*
X276983Y67586D01*
X276931Y67318D01*
X276725Y66973D01*
X278068Y67088D01*
Y68123D01*
G01X276260Y69920D02*
X276621Y70188D01*
X276828Y70418D01*
X276931Y70725D01*
X276828Y70993D01*
X276621Y71185D01*
X276311Y71338D01*
X275950Y71376D01*
X275640Y71338D01*
X275330Y71185D01*
X275071Y70955D01*
X274968Y70686D01*
X275071Y70380D01*
X275381Y70111D01*
X275846Y69958D01*
X276363Y69920D01*
X277035Y69996D01*
X277396Y70111D01*
X277758Y70303D01*
X278016Y70571D01*
X278068Y70840D01*
X277965Y71108D01*
X277706Y71300D01*
G01X273800Y62191D02*
X273955Y61961D01*
X274058Y61693D01*
Y61386D01*
X273903Y61041D01*
X273645Y60773D01*
X273335Y60581D01*
X272818Y60428D01*
X272353Y60390D01*
X271888Y60466D01*
X271578Y60581D01*
X271268Y60811D01*
X271061Y61080D01*
X270958Y61348D01*
Y61616D01*
X271061Y61885D01*
X271216Y62115D01*
X271423Y62306D01*
G01X270958Y64448D02*
X274058D01*
X273438Y63988D01*
G01X270958D02*
Y64908D01*
G01X271423Y66705D02*
X271165Y66935D01*
X271010Y67203D01*
X270958Y67548D01*
X271061Y67893D01*
X271268Y68161D01*
X271630Y68353D01*
X272043Y68391D01*
X272456Y68315D01*
X272715Y68123D01*
X272921Y67855D01*
X272973Y67586D01*
X272921Y67318D01*
X272715Y66973D01*
X274058Y67088D01*
Y68123D01*
G01X270958Y70648D02*
X271010Y70916D01*
X271165Y71223D01*
X271423Y71415D01*
X271785Y71491D01*
X272146Y71415D01*
X272456Y71185D01*
X272611Y70840D01*
Y70456D01*
X272715Y70226D01*
X272973Y70035D01*
X273335Y69958D01*
X273696Y70073D01*
X273955Y70341D01*
X274058Y70648D01*
X273955Y70955D01*
X273696Y71223D01*
X273335Y71338D01*
X272973Y71261D01*
X272715Y71070D01*
X272611Y70840D01*
Y70456D01*
X272456Y70111D01*
X272146Y69881D01*
X271785Y69805D01*
X271423Y69881D01*
X271165Y70073D01*
X271010Y70380D01*
X270958Y70648D01*
G01X272939Y86420D02*
X269739D01*
G01D02*
Y80220D01*
G01D02*
X272939D01*
G01D02*
Y86420D01*
G01X272839Y83320D02*
X269839D01*
G01X277142Y86453D02*
X273942D01*
G01D02*
Y80253D01*
G01D02*
X277142D01*
G01X277042Y83353D02*
X274042D01*
G01X275262Y102399D02*
X275417Y102169D01*
X275520Y101901D01*
Y101594D01*
X275365Y101249D01*
X275107Y100981D01*
X274797Y100789D01*
X274280Y100636D01*
X273815Y100598D01*
X273350Y100674D01*
X273040Y100789D01*
X272730Y101019D01*
X272523Y101288D01*
X272420Y101556D01*
Y101824D01*
X272523Y102093D01*
X272678Y102323D01*
X272885Y102514D01*
G01X272420Y104656D02*
X275520D01*
X274900Y104196D01*
G01X272420D02*
Y105116D01*
G01Y107679D02*
X273092Y107756D01*
X273660Y107871D01*
X274177Y108024D01*
X274745Y108216D01*
X275520Y108523D01*
Y106989D01*
G01Y110856D02*
X275417Y110549D01*
X275158Y110319D01*
X274848Y110166D01*
X274435Y110051D01*
X273970Y110013D01*
X273505Y110051D01*
X273092Y110166D01*
X272782Y110319D01*
X272523Y110549D01*
X272420Y110856D01*
X272523Y111163D01*
X272782Y111393D01*
X273092Y111546D01*
X273505Y111661D01*
X273970Y111699D01*
X274435Y111661D01*
X274848Y111546D01*
X275158Y111393D01*
X275417Y111163D01*
X275520Y110856D01*
G01X268025Y98764D02*
X271225D01*
G01D02*
Y104964D01*
G01D02*
X268025D01*
G01D02*
Y98764D01*
G01X268125Y101864D02*
X271125D01*
G01X263353Y112627D02*
X266553D01*
G01D02*
Y118827D01*
G01D02*
X263353D01*
G01D02*
Y112627D01*
G01X263453Y115727D02*
X266453D01*
G01X273389Y123428D02*
X273544Y123198D01*
X273647Y122930D01*
Y122623D01*
X273492Y122278D01*
X273234Y122010D01*
X272924Y121818D01*
X272407Y121665D01*
X271942Y121627D01*
X271477Y121703D01*
X271167Y121818D01*
X270857Y122048D01*
X270650Y122317D01*
X270547Y122585D01*
Y122853D01*
X270650Y123122D01*
X270805Y123352D01*
X271012Y123543D01*
G01X270547Y125685D02*
X273647D01*
X273027Y125225D01*
G01X270547D02*
Y126145D01*
G01X270909Y128133D02*
X270650Y128402D01*
X270547Y128708D01*
X270650Y129015D01*
X270960Y129283D01*
X271425Y129475D01*
X271890Y129552D01*
X272459D01*
X272924Y129475D01*
X273337Y129283D01*
X273544Y129053D01*
X273647Y128785D01*
X273544Y128478D01*
X273337Y128248D01*
X273027Y128095D01*
X272614Y128018D01*
X272252Y128095D01*
X271890Y128287D01*
X271684Y128517D01*
X271632Y128785D01*
X271735Y129092D01*
X271994Y129322D01*
X272459Y129552D01*
G01X270547Y132345D02*
X273647D01*
X271425Y130927D01*
Y132843D01*
G01X271453Y115727D02*
X274453D01*
G01X274552Y112627D02*
Y118827D01*
X271354D01*
Y112627D01*
X274552D01*
G01X262413Y115282D02*
Y119882D01*
G01X259773Y108997D02*
Y112197D01*
G01X266970Y120970D02*
X270070D01*
Y121929D01*
X269915Y122235D01*
X269708Y122427D01*
X269295Y122504D01*
X268882Y122427D01*
X268623Y122197D01*
X268468Y121929D01*
Y120970D01*
G01Y121929D02*
X266970Y122504D01*
G01X269553Y124109D02*
X269863Y124339D01*
X270018Y124607D01*
X270070Y124914D01*
X269967Y125297D01*
X269708Y125565D01*
X269398Y125642D01*
X269088Y125604D01*
X268830Y125450D01*
X268313Y124684D01*
X267952Y124339D01*
X267435Y124109D01*
X266970Y124032D01*
Y125642D01*
G01X270070Y127937D02*
X269967Y127630D01*
X269708Y127400D01*
X269398Y127247D01*
X268985Y127132D01*
X268520Y127094D01*
X268055Y127132D01*
X267642Y127247D01*
X267332Y127400D01*
X267073Y127630D01*
X266970Y127937D01*
X267073Y128244D01*
X267332Y128474D01*
X267642Y128627D01*
X268055Y128742D01*
X268520Y128780D01*
X268985Y128742D01*
X269398Y128627D01*
X269708Y128474D01*
X269967Y128244D01*
X270070Y127937D01*
G01X267590Y130194D02*
X267228Y130424D01*
X267022Y130730D01*
X266970Y131075D01*
X267022Y131382D01*
X267280Y131689D01*
X267590Y131880D01*
X267900Y131919D01*
X268262Y131842D01*
X268520Y131574D01*
X268623Y131305D01*
Y130960D01*
G01Y131305D02*
X268778Y131535D01*
X269037Y131727D01*
X269347Y131804D01*
X269657Y131727D01*
X269915Y131535D01*
X270070Y131190D01*
X270018Y130845D01*
X269812Y130500D01*
G01X267353Y112627D02*
X270553D01*
G01D02*
Y118827D01*
G01D02*
X267353D01*
G01D02*
Y112627D01*
G01X274719Y121239D02*
X277819D01*
Y122198D01*
X277664Y122504D01*
X277457Y122696D01*
X277044Y122773D01*
X276631Y122696D01*
X276372Y122466D01*
X276217Y122198D01*
Y121239D01*
G01Y122198D02*
X274719Y122773D01*
G01X277302Y124378D02*
X277612Y124608D01*
X277767Y124876D01*
X277819Y125183D01*
X277716Y125566D01*
X277457Y125834D01*
X277147Y125911D01*
X276837Y125873D01*
X276579Y125719D01*
X276062Y124953D01*
X275701Y124608D01*
X275184Y124378D01*
X274719Y124301D01*
Y125911D01*
G01X277819Y128206D02*
X277716Y127899D01*
X277457Y127669D01*
X277147Y127516D01*
X276734Y127401D01*
X276269Y127363D01*
X275804Y127401D01*
X275391Y127516D01*
X275081Y127669D01*
X274822Y127899D01*
X274719Y128206D01*
X274822Y128513D01*
X275081Y128743D01*
X275391Y128896D01*
X275804Y129011D01*
X276269Y129049D01*
X276734Y129011D01*
X277147Y128896D01*
X277457Y128743D01*
X277716Y128513D01*
X277819Y128206D01*
G01X277302Y130578D02*
X277612Y130808D01*
X277767Y131076D01*
X277819Y131383D01*
X277716Y131766D01*
X277457Y132034D01*
X277147Y132111D01*
X276837Y132073D01*
X276579Y131919D01*
X276062Y131153D01*
X275701Y130808D01*
X275184Y130578D01*
X274719Y130501D01*
Y132111D01*
G01X265842Y126295D02*
X265997Y126065D01*
X266100Y125797D01*
Y125490D01*
X265945Y125145D01*
X265687Y124877D01*
X265377Y124685D01*
X264860Y124532D01*
X264395Y124494D01*
X263930Y124570D01*
X263620Y124685D01*
X263310Y124915D01*
X263103Y125184D01*
X263000Y125452D01*
Y125720D01*
X263103Y125989D01*
X263258Y126219D01*
X263465Y126410D01*
G01X263000Y128552D02*
X266100D01*
X265480Y128092D01*
G01X263000D02*
Y129012D01*
G01Y132112D02*
X266100D01*
X263878Y130694D01*
Y132610D01*
G01X265583Y134024D02*
X265893Y134254D01*
X266048Y134522D01*
X266100Y134829D01*
X265997Y135212D01*
X265738Y135480D01*
X265428Y135557D01*
X265118Y135519D01*
X264860Y135365D01*
X264343Y134599D01*
X263982Y134254D01*
X263465Y134024D01*
X263000Y133947D01*
Y135557D01*
G01X385278Y159921D02*
X384498Y160701D01*
X383913Y162001D01*
X383523Y163821D01*
X383913Y165381D01*
X384693Y166421D01*
X386058Y167201D01*
X391323D01*
Y151601D01*
X384888D01*
X383523Y152641D01*
X382743Y154201D01*
X382353Y156021D01*
X382743Y157841D01*
X383913Y159401D01*
X385278Y159921D01*
X391323D01*
G01X365428Y151601D02*
Y162001D01*
G01Y160181D02*
X366208Y161221D01*
X367378Y161741D01*
X368743Y162001D01*
X370108Y161481D01*
X371278Y160441D01*
X372058Y158881D01*
X372448Y156801D01*
X372058Y154721D01*
X371278Y153161D01*
X370108Y152121D01*
X368743Y151601D01*
X367378Y151861D01*
X366208Y152641D01*
X365428Y153681D01*
G01X353768Y151601D02*
Y162001D01*
G01Y159921D02*
X352793Y160961D01*
X351818Y161741D01*
X350453Y162001D01*
X349478Y161741D01*
X348308Y160961D01*
G01X330018Y160701D02*
X331383Y161741D01*
X332553Y162001D01*
X334113Y161481D01*
X335283Y160441D01*
X336063Y158621D01*
X336258Y156801D01*
X336063Y154981D01*
X335283Y153421D01*
X334113Y152121D01*
X332553Y151601D01*
X331188Y152121D01*
X330018Y153161D01*
G01X315238Y151601D02*
X316408Y151861D01*
X317578Y152901D01*
X318358Y154721D01*
X318748Y156801D01*
X318358Y158881D01*
X317578Y160701D01*
X316408Y161741D01*
X315238Y162001D01*
X314068Y161741D01*
X312898Y160701D01*
X312118Y158881D01*
X311923Y156801D01*
X312118Y154721D01*
X312898Y152901D01*
X314068Y151861D01*
X315238Y151601D01*
G01X293828Y167201D02*
Y151601D01*
G01Y153941D02*
X294608Y152641D01*
X295778Y151861D01*
X297143Y151601D01*
X298703Y152121D01*
X299873Y153421D01*
X300653Y154981D01*
X300848Y156801D01*
X300653Y158621D01*
X299873Y160181D01*
X298703Y161481D01*
X297143Y162001D01*
X295778Y161741D01*
X294803Y161221D01*
X293828Y160181D01*
G01X282363Y158621D02*
X276123D01*
X276708Y160441D01*
X277683Y161481D01*
X279048Y162001D01*
X280413Y161741D01*
X281583Y160961D01*
X282363Y159141D01*
X282753Y157581D01*
Y156021D01*
X282363Y154461D01*
X281388Y152901D01*
X280218Y151861D01*
X278853Y151601D01*
X277488Y152121D01*
X276123Y153681D01*
G01X262360Y214060D02*
Y182080D01*
G01X263343Y229311D02*
X263498Y229081D01*
X263601Y228813D01*
Y228506D01*
X263446Y228161D01*
X263188Y227893D01*
X262878Y227701D01*
X262361Y227548D01*
X261896Y227510D01*
X261431Y227586D01*
X261121Y227701D01*
X260811Y227931D01*
X260604Y228200D01*
X260501Y228468D01*
Y228736D01*
X260604Y229005D01*
X260759Y229235D01*
X260966Y229426D01*
G01X260501Y231568D02*
X263601D01*
X262981Y231108D01*
G01X260501D02*
Y232028D01*
G01X263084Y233940D02*
X263394Y234170D01*
X263549Y234438D01*
X263601Y234745D01*
X263498Y235128D01*
X263239Y235396D01*
X262929Y235473D01*
X262619Y235435D01*
X262361Y235281D01*
X261844Y234515D01*
X261483Y234170D01*
X260966Y233940D01*
X260501Y233863D01*
Y235473D01*
G01X263601Y237768D02*
X263498Y237461D01*
X263239Y237231D01*
X262929Y237078D01*
X262516Y236963D01*
X262051Y236925D01*
X261586Y236963D01*
X261173Y237078D01*
X260863Y237231D01*
X260604Y237461D01*
X260501Y237768D01*
X260604Y238075D01*
X260863Y238305D01*
X261173Y238458D01*
X261586Y238573D01*
X262051Y238611D01*
X262516Y238573D01*
X262929Y238458D01*
X263239Y238305D01*
X263498Y238075D01*
X263601Y237768D01*
G01X267212Y229304D02*
X267367Y229074D01*
X267470Y228806D01*
Y228499D01*
X267315Y228154D01*
X267057Y227886D01*
X266747Y227694D01*
X266230Y227541D01*
X265765Y227503D01*
X265300Y227579D01*
X264990Y227694D01*
X264680Y227924D01*
X264473Y228193D01*
X264370Y228461D01*
Y228729D01*
X264473Y228998D01*
X264628Y229228D01*
X264835Y229419D01*
G01X264370Y231561D02*
X267470D01*
X266850Y231101D01*
G01X264370D02*
Y232021D01*
G01Y234661D02*
X267470D01*
X266850Y234201D01*
G01X264370D02*
Y235121D01*
G01Y238221D02*
X267470D01*
X265248Y236803D01*
Y238719D01*
G01X259863Y244371D02*
Y250571D01*
G01X260532Y244364D02*
X263732D01*
G01X260532Y250564D02*
Y244364D01*
G01X263732D02*
Y250564D01*
G01X260632Y247464D02*
X263632D01*
G01X282707Y242673D02*
X282937Y242828D01*
X283205Y242931D01*
X283512D01*
X283857Y242776D01*
X284125Y242518D01*
X284317Y242208D01*
X284470Y241691D01*
X284508Y241226D01*
X284432Y240761D01*
X284317Y240451D01*
X284087Y240141D01*
X283818Y239934D01*
X283550Y239831D01*
X283282D01*
X283013Y239934D01*
X282783Y240089D01*
X282592Y240296D01*
G01X280450Y239831D02*
Y242931D01*
X280910Y242311D01*
G01Y239831D02*
X279990D01*
G01X277350D02*
Y242931D01*
X277810Y242311D01*
G01Y239831D02*
X276890D01*
G01X274978Y241123D02*
X274710Y241484D01*
X274480Y241691D01*
X274173Y241794D01*
X273905Y241691D01*
X273713Y241484D01*
X273560Y241174D01*
X273522Y240813D01*
X273560Y240503D01*
X273713Y240193D01*
X273943Y239934D01*
X274212Y239831D01*
X274518Y239934D01*
X274787Y240244D01*
X274940Y240709D01*
X274978Y241226D01*
X274902Y241898D01*
X274787Y242259D01*
X274595Y242621D01*
X274327Y242879D01*
X274058Y242931D01*
X273790Y242828D01*
X273598Y242569D01*
G01X263732Y250564D02*
X260532D01*
G01X264920Y277301D02*
Y267949D01*
G01X261643Y274046D02*
X258643D01*
G01X261743Y270946D02*
Y277146D01*
G01X259490Y294822D02*
Y282137D01*
G01Y298750D02*
Y297092D01*
G01X266700Y306157D02*
Y304826D01*
G01Y298750D02*
Y301988D01*
G01Y308519D02*
Y307613D01*
G01Y312270D02*
Y311048D01*
G01X274992Y312270D02*
X271759D01*
G01X266700D02*
X269365D01*
G01X266700Y298750D02*
X259490D01*
G01X264618Y305387D02*
Y308587D01*
G01X263035Y321450D02*
X279779D01*
G01X261135D02*
X263035D01*
G01X273818Y313887D02*
Y320087D01*
G01X273718Y316987D02*
X270718D01*
G01X270618Y320087D02*
Y313887D01*
G01D02*
X273818D01*
G01Y320087D02*
X270618D01*
G01X265718Y316987D02*
X262718D01*
G01X262618Y320087D02*
Y313887D01*
G01D02*
X265818D01*
G01D02*
Y320087D01*
G01D02*
X262618D01*
G01X261718Y316987D02*
X258718D01*
G01X258618Y320087D02*
Y313887D01*
G01D02*
X261818D01*
G01D02*
Y320087D01*
G01D02*
X258618D01*
G01X269718Y316987D02*
X266718D01*
G01X266618Y320087D02*
Y313887D01*
G01D02*
X269818D01*
G01D02*
Y320087D01*
G01D02*
X266618D01*
G01X262890Y357089D02*
X265990D01*
Y358048D01*
X265835Y358354D01*
X265628Y358546D01*
X265215Y358623D01*
X264802Y358546D01*
X264543Y358316D01*
X264388Y358048D01*
Y357089D01*
G01Y358048D02*
X262890Y358623D01*
G01Y360956D02*
X265990D01*
X265370Y360496D01*
G01X262890D02*
Y361416D01*
G01X263355Y363213D02*
X263097Y363443D01*
X262942Y363711D01*
X262890Y364056D01*
X262993Y364401D01*
X263200Y364669D01*
X263562Y364861D01*
X263975Y364899D01*
X264388Y364823D01*
X264647Y364631D01*
X264853Y364363D01*
X264905Y364094D01*
X264853Y363826D01*
X264647Y363481D01*
X265990Y363596D01*
Y364631D01*
G01X263355Y366313D02*
X263097Y366543D01*
X262942Y366811D01*
X262890Y367156D01*
X262993Y367501D01*
X263200Y367769D01*
X263562Y367961D01*
X263975Y367999D01*
X264388Y367923D01*
X264647Y367731D01*
X264853Y367463D01*
X264905Y367194D01*
X264853Y366926D01*
X264647Y366581D01*
X265990Y366696D01*
Y367731D01*
G01X270154Y368371D02*
X273254D01*
Y369330D01*
X273099Y369636D01*
X272892Y369828D01*
X272479Y369905D01*
X272066Y369828D01*
X271807Y369598D01*
X271652Y369330D01*
Y368371D01*
G01Y369330D02*
X270154Y369905D01*
G01X270516Y371586D02*
X270257Y371855D01*
X270154Y372161D01*
X270257Y372468D01*
X270567Y372736D01*
X271032Y372928D01*
X271497Y373005D01*
X272066D01*
X272531Y372928D01*
X272944Y372736D01*
X273151Y372506D01*
X273254Y372238D01*
X273151Y371931D01*
X272944Y371701D01*
X272634Y371548D01*
X272221Y371471D01*
X271859Y371548D01*
X271497Y371740D01*
X271291Y371970D01*
X271239Y372238D01*
X271342Y372545D01*
X271601Y372775D01*
X272066Y373005D01*
G01X273254Y375338D02*
X273151Y375031D01*
X272892Y374801D01*
X272582Y374648D01*
X272169Y374533D01*
X271704Y374495D01*
X271239Y374533D01*
X270826Y374648D01*
X270516Y374801D01*
X270257Y375031D01*
X270154Y375338D01*
X270257Y375645D01*
X270516Y375875D01*
X270826Y376028D01*
X271239Y376143D01*
X271704Y376181D01*
X272169Y376143D01*
X272582Y376028D01*
X272892Y375875D01*
X273151Y375645D01*
X273254Y375338D01*
G01X263396Y370718D02*
X266496D01*
Y371677D01*
X266341Y371983D01*
X266134Y372175D01*
X265721Y372252D01*
X265308Y372175D01*
X265049Y371945D01*
X264894Y371677D01*
Y370718D01*
G01Y371677D02*
X263396Y372252D01*
G01Y374585D02*
X266496D01*
X265876Y374125D01*
G01X263396D02*
Y375045D01*
G01Y377685D02*
X266496D01*
X265876Y377225D01*
G01X263396D02*
Y378145D01*
G01X266496Y380785D02*
X266393Y380478D01*
X266134Y380248D01*
X265824Y380095D01*
X265411Y379980D01*
X264946Y379942D01*
X264481Y379980D01*
X264068Y380095D01*
X263758Y380248D01*
X263499Y380478D01*
X263396Y380785D01*
X263499Y381092D01*
X263758Y381322D01*
X264068Y381475D01*
X264481Y381590D01*
X264946Y381628D01*
X265411Y381590D01*
X265824Y381475D01*
X266134Y381322D01*
X266393Y381092D01*
X266496Y380785D01*
G01X258750Y368512D02*
Y362312D01*
G01D02*
X261950D01*
G01D02*
Y368512D01*
G01D02*
X258750D01*
G01X260287Y387377D02*
Y393577D01*
G01X274287Y377596D02*
Y383796D01*
G01D02*
X271087D01*
G01D02*
Y377596D01*
G01D02*
X274287D01*
G01X267087Y383796D02*
Y377596D01*
G01D02*
X270287D01*
G01D02*
Y383796D01*
G01D02*
X267087D01*
G01X259087D02*
Y377596D01*
G01D02*
X262287D01*
G01D02*
Y383796D01*
G01D02*
X259087D01*
G01X279788Y389269D02*
X273588D01*
G01D02*
Y386069D01*
G01D02*
X279788D01*
G01X261711Y447997D02*
X264811D01*
Y448956D01*
X264656Y449262D01*
X264449Y449454D01*
X264036Y449531D01*
X263623Y449454D01*
X263364Y449224D01*
X263209Y448956D01*
Y447997D01*
G01Y448956D02*
X261711Y449531D01*
G01X262331Y451021D02*
X261969Y451251D01*
X261763Y451557D01*
X261711Y451902D01*
X261763Y452209D01*
X262021Y452516D01*
X262331Y452707D01*
X262641Y452746D01*
X263003Y452669D01*
X263261Y452401D01*
X263364Y452132D01*
Y451787D01*
G01Y452132D02*
X263519Y452362D01*
X263778Y452554D01*
X264088Y452631D01*
X264398Y452554D01*
X264656Y452362D01*
X264811Y452017D01*
X264759Y451672D01*
X264553Y451327D01*
G01X264294Y454236D02*
X264604Y454466D01*
X264759Y454734D01*
X264811Y455041D01*
X264708Y455424D01*
X264449Y455692D01*
X264139Y455769D01*
X263829Y455731D01*
X263571Y455577D01*
X263054Y454811D01*
X262693Y454466D01*
X262176Y454236D01*
X261711Y454159D01*
Y455769D01*
G01Y458524D02*
X264811D01*
X262589Y457106D01*
Y459022D01*
G01X265552Y447915D02*
X268652D01*
Y448874D01*
X268497Y449180D01*
X268290Y449372D01*
X267877Y449449D01*
X267464Y449372D01*
X267205Y449142D01*
X267050Y448874D01*
Y447915D01*
G01Y448874D02*
X265552Y449449D01*
G01X266172Y450939D02*
X265810Y451169D01*
X265604Y451475D01*
X265552Y451820D01*
X265604Y452127D01*
X265862Y452434D01*
X266172Y452625D01*
X266482Y452664D01*
X266844Y452587D01*
X267102Y452319D01*
X267205Y452050D01*
Y451705D01*
G01Y452050D02*
X267360Y452280D01*
X267619Y452472D01*
X267929Y452549D01*
X268239Y452472D01*
X268497Y452280D01*
X268652Y451935D01*
X268600Y451590D01*
X268394Y451245D01*
G01X268135Y454154D02*
X268445Y454384D01*
X268600Y454652D01*
X268652Y454959D01*
X268549Y455342D01*
X268290Y455610D01*
X267980Y455687D01*
X267670Y455649D01*
X267412Y455495D01*
X266895Y454729D01*
X266534Y454384D01*
X266017Y454154D01*
X265552Y454077D01*
Y455687D01*
G01X265914Y457330D02*
X265655Y457599D01*
X265552Y457905D01*
X265655Y458212D01*
X265965Y458480D01*
X266430Y458672D01*
X266895Y458749D01*
X267464D01*
X267929Y458672D01*
X268342Y458480D01*
X268549Y458250D01*
X268652Y457982D01*
X268549Y457675D01*
X268342Y457445D01*
X268032Y457292D01*
X267619Y457215D01*
X267257Y457292D01*
X266895Y457484D01*
X266689Y457714D01*
X266637Y457982D01*
X266740Y458289D01*
X266999Y458519D01*
X267464Y458749D01*
G01X269478Y447896D02*
X272578D01*
Y448855D01*
X272423Y449161D01*
X272216Y449353D01*
X271803Y449430D01*
X271390Y449353D01*
X271131Y449123D01*
X270976Y448855D01*
Y447896D01*
G01Y448855D02*
X269478Y449430D01*
G01X270098Y450920D02*
X269736Y451150D01*
X269530Y451456D01*
X269478Y451801D01*
X269530Y452108D01*
X269788Y452415D01*
X270098Y452606D01*
X270408Y452645D01*
X270770Y452568D01*
X271028Y452300D01*
X271131Y452031D01*
Y451686D01*
G01Y452031D02*
X271286Y452261D01*
X271545Y452453D01*
X271855Y452530D01*
X272165Y452453D01*
X272423Y452261D01*
X272578Y451916D01*
X272526Y451571D01*
X272320Y451226D01*
G01X270098Y454020D02*
X269736Y454250D01*
X269530Y454556D01*
X269478Y454901D01*
X269530Y455208D01*
X269788Y455515D01*
X270098Y455706D01*
X270408Y455745D01*
X270770Y455668D01*
X271028Y455400D01*
X271131Y455131D01*
Y454786D01*
G01Y455131D02*
X271286Y455361D01*
X271545Y455553D01*
X271855Y455630D01*
X272165Y455553D01*
X272423Y455361D01*
X272578Y455016D01*
X272526Y454671D01*
X272320Y454326D01*
G01X269840Y457311D02*
X269581Y457580D01*
X269478Y457886D01*
X269581Y458193D01*
X269891Y458461D01*
X270356Y458653D01*
X270821Y458730D01*
X271390D01*
X271855Y458653D01*
X272268Y458461D01*
X272475Y458231D01*
X272578Y457963D01*
X272475Y457656D01*
X272268Y457426D01*
X271958Y457273D01*
X271545Y457196D01*
X271183Y457273D01*
X270821Y457465D01*
X270615Y457695D01*
X270563Y457963D01*
X270666Y458270D01*
X270925Y458500D01*
X271390Y458730D01*
G01X259009Y464453D02*
X262209D01*
G01X259009Y470653D02*
Y464453D01*
G01X262209D02*
Y470653D01*
G01D02*
X259009D01*
G01X263309Y464453D02*
X266509D01*
G01X263309Y470653D02*
Y464453D01*
G01X266509D02*
Y470653D01*
G01D02*
X263309D01*
G01X267609Y464453D02*
X270809D01*
G01X267609Y470653D02*
Y464453D01*
G01X270809D02*
Y470653D01*
G01D02*
X267609D01*
G01X271909Y464453D02*
X275109D01*
G01X271909Y470653D02*
Y464453D01*
G01X275109Y470653D02*
X271909D01*
G01X262209Y479653D02*
X259009D01*
G01X262209Y473453D02*
Y479653D01*
G01X259009Y473453D02*
X262209D01*
G01X259009Y479653D02*
Y473453D01*
G01X270709Y479653D02*
X267509D01*
G01X270709Y473453D02*
Y479653D01*
G01X267509Y473453D02*
X270709D01*
G01X267509Y479653D02*
Y473453D01*
G01X266509Y479653D02*
X263309D01*
G01X266509Y473453D02*
Y479653D01*
G01X263309Y473453D02*
X266509D01*
G01X263309Y479653D02*
Y473453D01*
G01X274809Y479653D02*
X271609D01*
G01Y473453D02*
X274809D01*
G01X271609Y479653D02*
Y473453D01*
G01X268709Y491853D02*
X271709D01*
G01X268609Y488753D02*
X271809D01*
G01X268609Y494953D02*
Y488753D01*
G01X271809Y494953D02*
X268609D01*
G01X271809Y488753D02*
Y494953D01*
G01X272709Y491853D02*
X275709D01*
G01X272609Y488753D02*
X275809D01*
G01X272609Y494953D02*
Y488753D01*
G01X275809Y494953D02*
X272609D01*
G01X276723Y507673D02*
X275140Y512673D01*
X273557Y507673D01*
G01X274127Y509423D02*
X276153D01*
G01X260600Y514831D02*
Y521031D01*
G01X271709Y516853D02*
X268709D01*
G01X268609Y513753D02*
X271809D01*
G01X268609Y519953D02*
Y513753D01*
G01X271809D02*
Y519953D01*
G01X275709Y516853D02*
X272709D01*
G01X272609Y513753D02*
X275809D01*
G01X272609Y519953D02*
Y513753D01*
G01X260348Y507890D02*
Y514090D01*
G01X269838Y531022D02*
Y527822D01*
G01D02*
X276038D01*
G01Y531022D02*
X269838D01*
G01X272938Y530922D02*
Y527922D01*
G01X269609Y523953D02*
Y520753D01*
G01X275809Y523953D02*
X269609D01*
G01Y520753D02*
X275809D01*
G01X272709Y523853D02*
Y520853D01*
G01X269838Y535022D02*
Y531822D01*
G01D02*
X276038D01*
G01X272938Y534922D02*
Y531922D01*
G01X271809Y519953D02*
X268609D01*
G01X275809D02*
X272609D01*
G01X261895Y548612D02*
Y545612D01*
G01X258795Y548712D02*
Y545512D01*
G01X264995Y548712D02*
X258795D01*
G01X264995Y545512D02*
Y548712D01*
G01X258795Y545512D02*
X264995D01*
G01X261909Y544753D02*
Y541753D01*
G01X258809Y544853D02*
Y541653D01*
G01X265009Y544853D02*
X258809D01*
G01X265009Y541653D02*
Y544853D01*
G01X258809Y541653D02*
X265009D01*
G01X265742Y545080D02*
X268742D01*
G01X265642Y541980D02*
X268842D01*
G01X265642Y548180D02*
Y541980D01*
G01X268842D02*
Y548180D01*
G01D02*
X265642D01*
G01X269873Y543030D02*
Y539830D01*
G01X276073Y543030D02*
X269873D01*
G01Y539830D02*
X276073D01*
G01X272973Y542930D02*
Y539930D01*
G01X269838Y539022D02*
Y535822D01*
G01X276038Y539022D02*
X269838D01*
G01Y535822D02*
X276038D01*
G01X272938Y538922D02*
Y535922D01*
G01X276038Y535022D02*
X269838D01*
G01X269777Y548943D02*
Y544343D01*
G01D02*
X279977D01*
G01Y548943D02*
X269777D01*
G01X272280Y558210D02*
X276910D01*
G01X269240D02*
X270490D01*
G01X275838Y565573D02*
X272738D01*
G01X275838Y564691D02*
Y566455D01*
G01X272738Y567906D02*
X275838D01*
Y568826D01*
X275683Y569133D01*
X275321Y569363D01*
X274908Y569440D01*
X274495Y569363D01*
X274185Y569171D01*
X274030Y568826D01*
Y567906D01*
G01X272738Y571773D02*
X272790Y572041D01*
X272945Y572348D01*
X273203Y572540D01*
X273565Y572616D01*
X273926Y572540D01*
X274236Y572310D01*
X274391Y571965D01*
Y571581D01*
X274495Y571351D01*
X274753Y571160D01*
X275115Y571083D01*
X275476Y571198D01*
X275735Y571466D01*
X275838Y571773D01*
X275735Y572080D01*
X275476Y572348D01*
X275115Y572463D01*
X274753Y572386D01*
X274495Y572195D01*
X274391Y571965D01*
Y571581D01*
X274236Y571236D01*
X273926Y571006D01*
X273565Y570930D01*
X273203Y571006D01*
X272945Y571198D01*
X272790Y571505D01*
X272738Y571773D01*
G01X272518Y576662D02*
X275618D01*
Y577582D01*
X275463Y577889D01*
X275101Y578119D01*
X274688Y578196D01*
X274275Y578119D01*
X273965Y577927D01*
X273810Y577582D01*
Y576662D01*
G01X273138Y579762D02*
X272828Y579954D01*
X272621Y580184D01*
X272518Y580452D01*
X272621Y580759D01*
X272828Y580989D01*
X273138Y581219D01*
X273551Y581296D01*
X275618D01*
G01X272518Y583629D02*
X275618D01*
X274998Y583169D01*
G01X272518D02*
Y584089D01*
G01X272880Y586077D02*
X272621Y586346D01*
X272518Y586652D01*
X272621Y586959D01*
X272931Y587227D01*
X273396Y587419D01*
X273861Y587496D01*
X274430D01*
X274895Y587419D01*
X275308Y587227D01*
X275515Y586997D01*
X275618Y586729D01*
X275515Y586422D01*
X275308Y586192D01*
X274998Y586039D01*
X274585Y585962D01*
X274223Y586039D01*
X273861Y586231D01*
X273655Y586461D01*
X273603Y586729D01*
X273706Y587036D01*
X273965Y587266D01*
X274430Y587496D01*
G01X263925Y585799D02*
X267025D01*
Y586719D01*
X266870Y587026D01*
X266508Y587256D01*
X266095Y587333D01*
X265682Y587256D01*
X265372Y587064D01*
X265217Y586719D01*
Y585799D01*
G01X264545Y588899D02*
X264235Y589091D01*
X264028Y589321D01*
X263925Y589589D01*
X264028Y589896D01*
X264235Y590126D01*
X264545Y590356D01*
X264958Y590433D01*
X267025D01*
G01X263925Y592766D02*
X267025D01*
X266405Y592306D01*
G01X263925D02*
Y593226D01*
G01Y595866D02*
X263977Y596134D01*
X264132Y596441D01*
X264390Y596633D01*
X264752Y596709D01*
X265113Y596633D01*
X265423Y596403D01*
X265578Y596058D01*
Y595674D01*
X265682Y595444D01*
X265940Y595253D01*
X266302Y595176D01*
X266663Y595291D01*
X266922Y595559D01*
X267025Y595866D01*
X266922Y596173D01*
X266663Y596441D01*
X266302Y596556D01*
X265940Y596479D01*
X265682Y596288D01*
X265578Y596058D01*
Y595674D01*
X265423Y595329D01*
X265113Y595099D01*
X264752Y595023D01*
X264390Y595099D01*
X264132Y595291D01*
X263977Y595598D01*
X263925Y595866D01*
G01X259040Y737556D02*
Y743756D01*
G01X272540Y732256D02*
X269340D01*
G01X272540Y726056D02*
Y732256D01*
G01X269340Y726056D02*
X272540D01*
G01X269340Y732256D02*
Y726056D01*
G01X272440Y729156D02*
X269440D01*
G01X260340Y737556D02*
X263540D01*
G01X260340Y743756D02*
Y737556D01*
G01X263540D02*
Y743756D01*
G01X273840Y737556D02*
X277040D01*
G01X273840Y743756D02*
Y737556D01*
G01X268040D02*
Y743756D01*
X264840D01*
Y737556D01*
X268040D01*
G01X259039Y726056D02*
Y732256D01*
G01X263540D02*
X260340D01*
G01X263540Y726056D02*
Y732256D01*
G01X260340Y726056D02*
X263540D01*
G01X260340Y732256D02*
Y726056D01*
G01X272540Y737556D02*
Y743756D01*
G01X269340Y737556D02*
X272540D01*
G01X269340Y743756D02*
Y737556D01*
G01X268040Y732256D02*
X264840D01*
G01X268040Y726056D02*
Y732256D01*
G01X264840Y726056D02*
X268040D01*
G01X264840Y732256D02*
Y726056D01*
G01X277040Y732256D02*
X273840D01*
G01Y726056D02*
X277040D01*
G01X273840Y732256D02*
Y726056D01*
G01X272883Y747494D02*
X273038Y747264D01*
X273141Y746996D01*
Y746689D01*
X272986Y746344D01*
X272728Y746076D01*
X272418Y745884D01*
X271901Y745731D01*
X271436Y745693D01*
X270971Y745769D01*
X270661Y745884D01*
X270351Y746114D01*
X270144Y746383D01*
X270041Y746651D01*
Y746919D01*
X270144Y747188D01*
X270299Y747418D01*
X270506Y747609D01*
G01X271333Y749023D02*
X271694Y749291D01*
X271901Y749521D01*
X272004Y749828D01*
X271901Y750096D01*
X271694Y750288D01*
X271384Y750441D01*
X271023Y750479D01*
X270713Y750441D01*
X270403Y750288D01*
X270144Y750058D01*
X270041Y749789D01*
X270144Y749483D01*
X270454Y749214D01*
X270919Y749061D01*
X271436Y749023D01*
X272108Y749099D01*
X272469Y749214D01*
X272831Y749406D01*
X273089Y749674D01*
X273141Y749943D01*
X273038Y750211D01*
X272779Y750403D01*
G01X270041Y752851D02*
X270093Y753119D01*
X270248Y753426D01*
X270506Y753618D01*
X270868Y753694D01*
X271229Y753618D01*
X271539Y753388D01*
X271694Y753043D01*
Y752659D01*
X271798Y752429D01*
X272056Y752238D01*
X272418Y752161D01*
X272779Y752276D01*
X273038Y752544D01*
X273141Y752851D01*
X273038Y753158D01*
X272779Y753426D01*
X272418Y753541D01*
X272056Y753464D01*
X271798Y753273D01*
X271694Y753043D01*
Y752659D01*
X271539Y752314D01*
X271229Y752084D01*
X270868Y752008D01*
X270506Y752084D01*
X270248Y752276D01*
X270093Y752583D01*
X270041Y752851D01*
G01X270403Y755299D02*
X270144Y755568D01*
X270041Y755874D01*
X270144Y756181D01*
X270454Y756449D01*
X270919Y756641D01*
X271384Y756718D01*
X271953D01*
X272418Y756641D01*
X272831Y756449D01*
X273038Y756219D01*
X273141Y755951D01*
X273038Y755644D01*
X272831Y755414D01*
X272521Y755261D01*
X272108Y755184D01*
X271746Y755261D01*
X271384Y755453D01*
X271178Y755683D01*
X271126Y755951D01*
X271229Y756258D01*
X271488Y756488D01*
X271953Y756718D01*
G01X263540Y743756D02*
X260340D01*
G01X260440Y740656D02*
X263440D01*
G01X277040Y743756D02*
X273840D01*
G01X273940Y740656D02*
X276940D01*
G01X264940D02*
X267940D01*
G01X260917Y745884D02*
X264017D01*
Y746843D01*
X263862Y747149D01*
X263655Y747341D01*
X263242Y747418D01*
X262829Y747341D01*
X262570Y747111D01*
X262415Y746843D01*
Y745884D01*
G01Y746843D02*
X260917Y747418D01*
G01Y749751D02*
X260969Y750019D01*
X261124Y750326D01*
X261382Y750518D01*
X261744Y750594D01*
X262105Y750518D01*
X262415Y750288D01*
X262570Y749943D01*
Y749559D01*
X262674Y749329D01*
X262932Y749138D01*
X263294Y749061D01*
X263655Y749176D01*
X263914Y749444D01*
X264017Y749751D01*
X263914Y750058D01*
X263655Y750326D01*
X263294Y750441D01*
X262932Y750364D01*
X262674Y750173D01*
X262570Y749943D01*
Y749559D01*
X262415Y749214D01*
X262105Y748984D01*
X261744Y748908D01*
X261382Y748984D01*
X261124Y749176D01*
X260969Y749483D01*
X260917Y749751D01*
G01X261382Y752008D02*
X261124Y752238D01*
X260969Y752506D01*
X260917Y752851D01*
X261020Y753196D01*
X261227Y753464D01*
X261589Y753656D01*
X262002Y753694D01*
X262415Y753618D01*
X262674Y753426D01*
X262880Y753158D01*
X262932Y752889D01*
X262880Y752621D01*
X262674Y752276D01*
X264017Y752391D01*
Y753426D01*
G01X261279Y755299D02*
X261020Y755568D01*
X260917Y755874D01*
X261020Y756181D01*
X261330Y756449D01*
X261795Y756641D01*
X262260Y756718D01*
X262829D01*
X263294Y756641D01*
X263707Y756449D01*
X263914Y756219D01*
X264017Y755951D01*
X263914Y755644D01*
X263707Y755414D01*
X263397Y755261D01*
X262984Y755184D01*
X262622Y755261D01*
X262260Y755453D01*
X262054Y755683D01*
X262002Y755951D01*
X262105Y756258D01*
X262364Y756488D01*
X262829Y756718D01*
G01X272540Y743756D02*
X269340D01*
G01X265054Y745884D02*
X268154D01*
Y746843D01*
X267999Y747149D01*
X267792Y747341D01*
X267379Y747418D01*
X266966Y747341D01*
X266707Y747111D01*
X266552Y746843D01*
Y745884D01*
G01Y746843D02*
X265054Y747418D01*
G01X265416Y749099D02*
X265157Y749368D01*
X265054Y749674D01*
X265157Y749981D01*
X265467Y750249D01*
X265932Y750441D01*
X266397Y750518D01*
X266966D01*
X267431Y750441D01*
X267844Y750249D01*
X268051Y750019D01*
X268154Y749751D01*
X268051Y749444D01*
X267844Y749214D01*
X267534Y749061D01*
X267121Y748984D01*
X266759Y749061D01*
X266397Y749253D01*
X266191Y749483D01*
X266139Y749751D01*
X266242Y750058D01*
X266501Y750288D01*
X266966Y750518D01*
G01X267637Y752123D02*
X267947Y752353D01*
X268102Y752621D01*
X268154Y752928D01*
X268051Y753311D01*
X267792Y753579D01*
X267482Y753656D01*
X267172Y753618D01*
X266914Y753464D01*
X266397Y752698D01*
X266036Y752353D01*
X265519Y752123D01*
X265054Y752046D01*
Y753656D01*
G01X265416Y755299D02*
X265157Y755568D01*
X265054Y755874D01*
X265157Y756181D01*
X265467Y756449D01*
X265932Y756641D01*
X266397Y756718D01*
X266966D01*
X267431Y756641D01*
X267844Y756449D01*
X268051Y756219D01*
X268154Y755951D01*
X268051Y755644D01*
X267844Y755414D01*
X267534Y755261D01*
X267121Y755184D01*
X266759Y755261D01*
X266397Y755453D01*
X266191Y755683D01*
X266139Y755951D01*
X266242Y756258D01*
X266501Y756488D01*
X266966Y756718D01*
G01X274020Y745884D02*
X277120D01*
Y746843D01*
X276965Y747149D01*
X276758Y747341D01*
X276345Y747418D01*
X275932Y747341D01*
X275673Y747111D01*
X275518Y746843D01*
Y745884D01*
G01Y746843D02*
X274020Y747418D01*
G01X274382Y749099D02*
X274123Y749368D01*
X274020Y749674D01*
X274123Y749981D01*
X274433Y750249D01*
X274898Y750441D01*
X275363Y750518D01*
X275932D01*
X276397Y750441D01*
X276810Y750249D01*
X277017Y750019D01*
X277120Y749751D01*
X277017Y749444D01*
X276810Y749214D01*
X276500Y749061D01*
X276087Y748984D01*
X275725Y749061D01*
X275363Y749253D01*
X275157Y749483D01*
X275105Y749751D01*
X275208Y750058D01*
X275467Y750288D01*
X275932Y750518D01*
G01X276603Y752123D02*
X276913Y752353D01*
X277068Y752621D01*
X277120Y752928D01*
X277017Y753311D01*
X276758Y753579D01*
X276448Y753656D01*
X276138Y753618D01*
X275880Y753464D01*
X275363Y752698D01*
X275002Y752353D01*
X274485Y752123D01*
X274020Y752046D01*
Y753656D01*
G01X274640Y755108D02*
X274278Y755338D01*
X274072Y755644D01*
X274020Y755989D01*
X274072Y756296D01*
X274330Y756603D01*
X274640Y756794D01*
X274950Y756833D01*
X275312Y756756D01*
X275570Y756488D01*
X275673Y756219D01*
Y755874D01*
G01Y756219D02*
X275828Y756449D01*
X276087Y756641D01*
X276397Y756718D01*
X276707Y756641D01*
X276965Y756449D01*
X277120Y756104D01*
X277068Y755759D01*
X276862Y755414D01*
G01X275702Y759650D02*
X275857Y759420D01*
X275960Y759152D01*
Y758845D01*
X275805Y758500D01*
X275547Y758232D01*
X275237Y758040D01*
X274720Y757887D01*
X274255Y757849D01*
X273790Y757925D01*
X273480Y758040D01*
X273170Y758270D01*
X272963Y758539D01*
X272860Y758807D01*
Y759075D01*
X272963Y759344D01*
X273118Y759574D01*
X273325Y759765D01*
G01X274152Y761179D02*
X274513Y761447D01*
X274720Y761677D01*
X274823Y761984D01*
X274720Y762252D01*
X274513Y762444D01*
X274203Y762597D01*
X273842Y762635D01*
X273532Y762597D01*
X273222Y762444D01*
X272963Y762214D01*
X272860Y761945D01*
X272963Y761639D01*
X273273Y761370D01*
X273738Y761217D01*
X274255Y761179D01*
X274927Y761255D01*
X275288Y761370D01*
X275650Y761562D01*
X275908Y761830D01*
X275960Y762099D01*
X275857Y762367D01*
X275598Y762559D01*
G01X272860Y765007D02*
X272912Y765275D01*
X273067Y765582D01*
X273325Y765774D01*
X273687Y765850D01*
X274048Y765774D01*
X274358Y765544D01*
X274513Y765199D01*
Y764815D01*
X274617Y764585D01*
X274875Y764394D01*
X275237Y764317D01*
X275598Y764432D01*
X275857Y764700D01*
X275960Y765007D01*
X275857Y765314D01*
X275598Y765582D01*
X275237Y765697D01*
X274875Y765620D01*
X274617Y765429D01*
X274513Y765199D01*
Y764815D01*
X274358Y764470D01*
X274048Y764240D01*
X273687Y764164D01*
X273325Y764240D01*
X273067Y764432D01*
X272912Y764739D01*
X272860Y765007D01*
G01X274152Y767379D02*
X274513Y767647D01*
X274720Y767877D01*
X274823Y768184D01*
X274720Y768452D01*
X274513Y768644D01*
X274203Y768797D01*
X273842Y768835D01*
X273532Y768797D01*
X273222Y768644D01*
X272963Y768414D01*
X272860Y768145D01*
X272963Y767839D01*
X273273Y767570D01*
X273738Y767417D01*
X274255Y767379D01*
X274927Y767455D01*
X275288Y767570D01*
X275650Y767762D01*
X275908Y768030D01*
X275960Y768299D01*
X275857Y768567D01*
X275598Y768759D01*
G01X266398Y759612D02*
X266553Y759382D01*
X266656Y759114D01*
Y758807D01*
X266501Y758462D01*
X266243Y758194D01*
X265933Y758002D01*
X265416Y757849D01*
X264951Y757811D01*
X264486Y757887D01*
X264176Y758002D01*
X263866Y758232D01*
X263659Y758501D01*
X263556Y758769D01*
Y759037D01*
X263659Y759306D01*
X263814Y759536D01*
X264021Y759727D01*
G01X264848Y761141D02*
X265209Y761409D01*
X265416Y761639D01*
X265519Y761946D01*
X265416Y762214D01*
X265209Y762406D01*
X264899Y762559D01*
X264538Y762597D01*
X264228Y762559D01*
X263918Y762406D01*
X263659Y762176D01*
X263556Y761907D01*
X263659Y761601D01*
X263969Y761332D01*
X264434Y761179D01*
X264951Y761141D01*
X265623Y761217D01*
X265984Y761332D01*
X266346Y761524D01*
X266604Y761792D01*
X266656Y762061D01*
X266553Y762329D01*
X266294Y762521D01*
G01X263918Y764317D02*
X263659Y764586D01*
X263556Y764892D01*
X263659Y765199D01*
X263969Y765467D01*
X264434Y765659D01*
X264899Y765736D01*
X265468D01*
X265933Y765659D01*
X266346Y765467D01*
X266553Y765237D01*
X266656Y764969D01*
X266553Y764662D01*
X266346Y764432D01*
X266036Y764279D01*
X265623Y764202D01*
X265261Y764279D01*
X264899Y764471D01*
X264693Y764701D01*
X264641Y764969D01*
X264744Y765276D01*
X265003Y765506D01*
X265468Y765736D01*
G01X266139Y767341D02*
X266449Y767571D01*
X266604Y767839D01*
X266656Y768146D01*
X266553Y768529D01*
X266294Y768797D01*
X265984Y768874D01*
X265674Y768836D01*
X265416Y768682D01*
X264899Y767916D01*
X264538Y767571D01*
X264021Y767341D01*
X263556Y767264D01*
Y768874D01*
G01X268262Y758040D02*
X271362D01*
Y758999D01*
X271207Y759305D01*
X271000Y759497D01*
X270587Y759574D01*
X270174Y759497D01*
X269915Y759267D01*
X269760Y758999D01*
Y758040D01*
G01Y758999D02*
X268262Y759574D01*
G01X268624Y761255D02*
X268365Y761524D01*
X268262Y761830D01*
X268365Y762137D01*
X268675Y762405D01*
X269140Y762597D01*
X269605Y762674D01*
X270174D01*
X270639Y762597D01*
X271052Y762405D01*
X271259Y762175D01*
X271362Y761907D01*
X271259Y761600D01*
X271052Y761370D01*
X270742Y761217D01*
X270329Y761140D01*
X269967Y761217D01*
X269605Y761409D01*
X269399Y761639D01*
X269347Y761907D01*
X269450Y762214D01*
X269709Y762444D01*
X270174Y762674D01*
G01X270845Y764279D02*
X271155Y764509D01*
X271310Y764777D01*
X271362Y765084D01*
X271259Y765467D01*
X271000Y765735D01*
X270690Y765812D01*
X270380Y765774D01*
X270122Y765620D01*
X269605Y764854D01*
X269244Y764509D01*
X268727Y764279D01*
X268262Y764202D01*
Y765812D01*
G01X269554Y767379D02*
X269915Y767647D01*
X270122Y767877D01*
X270225Y768184D01*
X270122Y768452D01*
X269915Y768644D01*
X269605Y768797D01*
X269244Y768835D01*
X268934Y768797D01*
X268624Y768644D01*
X268365Y768414D01*
X268262Y768145D01*
X268365Y767839D01*
X268675Y767570D01*
X269140Y767417D01*
X269657Y767379D01*
X270329Y767455D01*
X270690Y767570D01*
X271052Y767762D01*
X271310Y768030D01*
X271362Y768299D01*
X271259Y768567D01*
X271000Y768759D01*
G01X286163Y62191D02*
X286318Y61961D01*
X286421Y61693D01*
Y61386D01*
X286266Y61041D01*
X286008Y60773D01*
X285698Y60581D01*
X285181Y60428D01*
X284716Y60390D01*
X284251Y60466D01*
X283941Y60581D01*
X283631Y60811D01*
X283424Y61080D01*
X283321Y61348D01*
Y61616D01*
X283424Y61885D01*
X283579Y62115D01*
X283786Y62306D01*
G01X283321Y64448D02*
X286421D01*
X285801Y63988D01*
G01X283321D02*
Y64908D01*
G01X284613Y66820D02*
X284974Y67088D01*
X285181Y67318D01*
X285284Y67625D01*
X285181Y67893D01*
X284974Y68085D01*
X284664Y68238D01*
X284303Y68276D01*
X283993Y68238D01*
X283683Y68085D01*
X283424Y67855D01*
X283321Y67586D01*
X283424Y67280D01*
X283734Y67011D01*
X284199Y66858D01*
X284716Y66820D01*
X285388Y66896D01*
X285749Y67011D01*
X286111Y67203D01*
X286369Y67471D01*
X286421Y67740D01*
X286318Y68008D01*
X286059Y68200D01*
G01X285904Y69920D02*
X286214Y70150D01*
X286369Y70418D01*
X286421Y70725D01*
X286318Y71108D01*
X286059Y71376D01*
X285749Y71453D01*
X285439Y71415D01*
X285181Y71261D01*
X284664Y70495D01*
X284303Y70150D01*
X283786Y69920D01*
X283321Y69843D01*
Y71453D01*
G01X282044Y62191D02*
X282199Y61961D01*
X282302Y61693D01*
Y61386D01*
X282147Y61041D01*
X281889Y60773D01*
X281579Y60581D01*
X281062Y60428D01*
X280597Y60390D01*
X280132Y60466D01*
X279822Y60581D01*
X279512Y60811D01*
X279305Y61080D01*
X279202Y61348D01*
Y61616D01*
X279305Y61885D01*
X279460Y62115D01*
X279667Y62306D01*
G01X279202Y64448D02*
X282302D01*
X281682Y63988D01*
G01X279202D02*
Y64908D01*
G01X280494Y66820D02*
X280855Y67088D01*
X281062Y67318D01*
X281165Y67625D01*
X281062Y67893D01*
X280855Y68085D01*
X280545Y68238D01*
X280184Y68276D01*
X279874Y68238D01*
X279564Y68085D01*
X279305Y67855D01*
X279202Y67586D01*
X279305Y67280D01*
X279615Y67011D01*
X280080Y66858D01*
X280597Y66820D01*
X281269Y66896D01*
X281630Y67011D01*
X281992Y67203D01*
X282250Y67471D01*
X282302Y67740D01*
X282199Y68008D01*
X281940Y68200D01*
G01X279202Y70648D02*
X279254Y70916D01*
X279409Y71223D01*
X279667Y71415D01*
X280029Y71491D01*
X280390Y71415D01*
X280700Y71185D01*
X280855Y70840D01*
Y70456D01*
X280959Y70226D01*
X281217Y70035D01*
X281579Y69958D01*
X281940Y70073D01*
X282199Y70341D01*
X282302Y70648D01*
X282199Y70955D01*
X281940Y71223D01*
X281579Y71338D01*
X281217Y71261D01*
X280959Y71070D01*
X280855Y70840D01*
Y70456D01*
X280700Y70111D01*
X280390Y69881D01*
X280029Y69805D01*
X279667Y69881D01*
X279409Y70073D01*
X279254Y70380D01*
X279202Y70648D01*
G01X290082Y62191D02*
X290237Y61961D01*
X290340Y61693D01*
Y61386D01*
X290185Y61041D01*
X289927Y60773D01*
X289617Y60581D01*
X289100Y60428D01*
X288635Y60390D01*
X288170Y60466D01*
X287860Y60581D01*
X287550Y60811D01*
X287343Y61080D01*
X287240Y61348D01*
Y61616D01*
X287343Y61885D01*
X287498Y62115D01*
X287705Y62306D01*
G01X287240Y64448D02*
X290340D01*
X289720Y63988D01*
G01X287240D02*
Y64908D01*
G01Y67471D02*
X287912Y67548D01*
X288480Y67663D01*
X288997Y67816D01*
X289565Y68008D01*
X290340Y68315D01*
Y66781D01*
G01X287240Y70648D02*
X290340D01*
X289720Y70188D01*
G01X287240D02*
Y71108D01*
G01X281152Y86433D02*
X277952D01*
G01D02*
Y80233D01*
G01D02*
X281152D01*
G01D02*
Y86433D01*
G01X281052Y83333D02*
X278052D01*
G01X289505Y86220D02*
X286305D01*
G01D02*
Y80020D01*
G01D02*
X289505D01*
G01D02*
Y86220D01*
G01X289405Y83120D02*
X286405D01*
G01X285386Y86220D02*
X282186D01*
G01D02*
Y80020D01*
G01D02*
X285386D01*
G01D02*
Y86220D01*
G01X285286Y83120D02*
X282286D01*
G01X277142Y80253D02*
Y86453D01*
G01X282599Y104584D02*
X285799D01*
G01D02*
Y110784D01*
G01X282599D02*
Y104584D01*
G01X282699Y107684D02*
X285699D01*
G01X285572Y113995D02*
X285727Y113765D01*
X285830Y113497D01*
Y113190D01*
X285675Y112845D01*
X285417Y112577D01*
X285107Y112385D01*
X284590Y112232D01*
X284125Y112194D01*
X283660Y112270D01*
X283350Y112385D01*
X283040Y112615D01*
X282833Y112884D01*
X282730Y113152D01*
Y113420D01*
X282833Y113689D01*
X282988Y113919D01*
X283195Y114110D01*
G01X282730Y116252D02*
X285830D01*
X285210Y115792D01*
G01X282730D02*
Y116712D01*
G01X284022Y118624D02*
X284383Y118892D01*
X284590Y119122D01*
X284693Y119429D01*
X284590Y119697D01*
X284383Y119889D01*
X284073Y120042D01*
X283712Y120080D01*
X283402Y120042D01*
X283092Y119889D01*
X282833Y119659D01*
X282730Y119390D01*
X282833Y119084D01*
X283143Y118815D01*
X283608Y118662D01*
X284125Y118624D01*
X284797Y118700D01*
X285158Y118815D01*
X285520Y119007D01*
X285778Y119275D01*
X285830Y119544D01*
X285727Y119812D01*
X285468Y120004D01*
G01X283092Y121800D02*
X282833Y122069D01*
X282730Y122375D01*
X282833Y122682D01*
X283143Y122950D01*
X283608Y123142D01*
X284073Y123219D01*
X284642D01*
X285107Y123142D01*
X285520Y122950D01*
X285727Y122720D01*
X285830Y122452D01*
X285727Y122145D01*
X285520Y121915D01*
X285210Y121762D01*
X284797Y121685D01*
X284435Y121762D01*
X284073Y121954D01*
X283867Y122184D01*
X283815Y122452D01*
X283918Y122759D01*
X284177Y122989D01*
X284642Y123219D01*
G01X285799Y110784D02*
X282599D01*
G01X278553Y118827D02*
X275353D01*
G01D02*
Y112627D01*
G01D02*
X278553D01*
G01D02*
Y118827D01*
G01X278492Y246178D02*
Y249178D01*
G01X281592Y246078D02*
Y249278D01*
G01X275392Y246078D02*
X281592D01*
G01X275392Y249278D02*
Y246078D01*
G01X281592Y249278D02*
X275392D01*
G01X296310Y312270D02*
X280865D01*
G01X293527Y299558D02*
Y302658D01*
X292568D01*
X292262Y302503D01*
X292070Y302296D01*
X291993Y301883D01*
X292070Y301470D01*
X292300Y301211D01*
X292568Y301056D01*
X293527D01*
G01X292568D02*
X291993Y299558D01*
G01X289660D02*
Y302658D01*
X290120Y302038D01*
G01Y299558D02*
X289200D01*
G01X286560D02*
Y302658D01*
X287020Y302038D01*
G01Y299558D02*
X286100D01*
G01X283537D02*
X283460Y300230D01*
X283345Y300798D01*
X283192Y301315D01*
X283000Y301883D01*
X282693Y302658D01*
X284227D01*
G01X287417Y308475D02*
Y305275D01*
G01X293617Y308475D02*
X287417D01*
G01Y305275D02*
X293617D01*
G01X283283Y321450D02*
X284282D01*
G01X283283D02*
X282802D01*
G01X290490D02*
X287206D01*
G01X277718Y316987D02*
X274718D01*
G01X274618Y320087D02*
Y313887D01*
G01D02*
X277818D01*
G01D02*
Y320087D01*
G01D02*
X274618D01*
G01X285718Y316987D02*
X282718D01*
G01X282618Y320087D02*
Y313887D01*
G01D02*
X285818D01*
G01D02*
Y320087D01*
G01D02*
X282618D01*
G01X281718Y316987D02*
X278718D01*
G01X278618Y320087D02*
Y313887D01*
G01D02*
X281818D01*
G01D02*
Y320087D01*
G01D02*
X278618D01*
G01X289818Y313887D02*
Y320087D01*
G01X289718Y316987D02*
X286718D01*
G01X286618Y320087D02*
Y313887D01*
G01D02*
X289818D01*
G01Y320087D02*
X286618D01*
G01X278969Y328952D02*
X285169D01*
G01D02*
Y332152D01*
G01X278969D02*
Y328952D01*
G01X291437Y334779D02*
Y337879D01*
X290478D01*
X290172Y337724D01*
X289980Y337517D01*
X289903Y337104D01*
X289980Y336691D01*
X290210Y336432D01*
X290478Y336277D01*
X291437D01*
G01X290478D02*
X289903Y334779D01*
G01X287647D02*
X287570Y335451D01*
X287455Y336019D01*
X287302Y336536D01*
X287110Y337104D01*
X286803Y337879D01*
X288337D01*
G01X284547Y334779D02*
X284470Y335451D01*
X284355Y336019D01*
X284202Y336536D01*
X284010Y337104D01*
X283703Y337879D01*
X285237D01*
G01X285169Y332152D02*
X278969D01*
G01X290134Y360701D02*
X293234D01*
Y361660D01*
X293079Y361966D01*
X292872Y362158D01*
X292459Y362235D01*
X292046Y362158D01*
X291787Y361928D01*
X291632Y361660D01*
Y360701D01*
G01Y361660D02*
X290134Y362235D01*
G01Y364568D02*
X290186Y364836D01*
X290341Y365143D01*
X290599Y365335D01*
X290961Y365411D01*
X291322Y365335D01*
X291632Y365105D01*
X291787Y364760D01*
Y364376D01*
X291891Y364146D01*
X292149Y363955D01*
X292511Y363878D01*
X292872Y363993D01*
X293131Y364261D01*
X293234Y364568D01*
X293131Y364875D01*
X292872Y365143D01*
X292511Y365258D01*
X292149Y365181D01*
X291891Y364990D01*
X291787Y364760D01*
Y364376D01*
X291632Y364031D01*
X291322Y363801D01*
X290961Y363725D01*
X290599Y363801D01*
X290341Y363993D01*
X290186Y364300D01*
X290134Y364568D01*
G01X290496Y367016D02*
X290237Y367285D01*
X290134Y367591D01*
X290237Y367898D01*
X290547Y368166D01*
X291012Y368358D01*
X291477Y368435D01*
X292046D01*
X292511Y368358D01*
X292924Y368166D01*
X293131Y367936D01*
X293234Y367668D01*
X293131Y367361D01*
X292924Y367131D01*
X292614Y366978D01*
X292201Y366901D01*
X291839Y366978D01*
X291477Y367170D01*
X291271Y367400D01*
X291219Y367668D01*
X291322Y367975D01*
X291581Y368205D01*
X292046Y368435D01*
G01X286250Y360671D02*
X289350D01*
Y361630D01*
X289195Y361936D01*
X288988Y362128D01*
X288575Y362205D01*
X288162Y362128D01*
X287903Y361898D01*
X287748Y361630D01*
Y360671D01*
G01Y361630D02*
X286250Y362205D01*
G01Y364538D02*
X286302Y364806D01*
X286457Y365113D01*
X286715Y365305D01*
X287077Y365381D01*
X287438Y365305D01*
X287748Y365075D01*
X287903Y364730D01*
Y364346D01*
X288007Y364116D01*
X288265Y363925D01*
X288627Y363848D01*
X288988Y363963D01*
X289247Y364231D01*
X289350Y364538D01*
X289247Y364845D01*
X288988Y365113D01*
X288627Y365228D01*
X288265Y365151D01*
X288007Y364960D01*
X287903Y364730D01*
Y364346D01*
X287748Y364001D01*
X287438Y363771D01*
X287077Y363695D01*
X286715Y363771D01*
X286457Y363963D01*
X286302Y364270D01*
X286250Y364538D01*
G01X286715Y366795D02*
X286457Y367025D01*
X286302Y367293D01*
X286250Y367638D01*
X286353Y367983D01*
X286560Y368251D01*
X286922Y368443D01*
X287335Y368481D01*
X287748Y368405D01*
X288007Y368213D01*
X288213Y367945D01*
X288265Y367676D01*
X288213Y367408D01*
X288007Y367063D01*
X289350Y367178D01*
Y368213D01*
G01X290925Y348039D02*
Y351139D01*
X289966D01*
X289660Y350984D01*
X289468Y350777D01*
X289391Y350364D01*
X289468Y349951D01*
X289698Y349692D01*
X289966Y349537D01*
X290925D01*
G01X289966D02*
X289391Y348039D01*
G01X287058D02*
X286790Y348091D01*
X286483Y348246D01*
X286291Y348504D01*
X286215Y348866D01*
X286291Y349227D01*
X286521Y349537D01*
X286866Y349692D01*
X287250D01*
X287480Y349796D01*
X287671Y350054D01*
X287748Y350416D01*
X287633Y350777D01*
X287365Y351036D01*
X287058Y351139D01*
X286751Y351036D01*
X286483Y350777D01*
X286368Y350416D01*
X286445Y350054D01*
X286636Y349796D01*
X286866Y349692D01*
X287250D01*
X287595Y349537D01*
X287825Y349227D01*
X287901Y348866D01*
X287825Y348504D01*
X287633Y348246D01*
X287326Y348091D01*
X287058Y348039D01*
G01X284035D02*
X283958Y348711D01*
X283843Y349279D01*
X283690Y349796D01*
X283498Y350364D01*
X283191Y351139D01*
X284725D01*
G01X276296Y348130D02*
X282496D01*
G01D02*
Y351330D01*
G01D02*
X276296D01*
G01D02*
Y348130D01*
G01X281898Y368927D02*
Y362727D01*
G01D02*
X285098D01*
G01D02*
Y368927D01*
G01D02*
X281898D01*
G01X275225Y368542D02*
Y362342D01*
G01D02*
X278425D01*
G01D02*
Y368542D01*
G01D02*
X275225D01*
G01X286220Y380087D02*
Y383187D01*
X285261D01*
X284955Y383032D01*
X284763Y382825D01*
X284686Y382412D01*
X284763Y381999D01*
X284993Y381740D01*
X285261Y381585D01*
X286220D01*
G01X285261D02*
X284686Y380087D01*
G01X283005Y380449D02*
X282736Y380190D01*
X282430Y380087D01*
X282123Y380190D01*
X281855Y380500D01*
X281663Y380965D01*
X281586Y381430D01*
Y381999D01*
X281663Y382464D01*
X281855Y382877D01*
X282085Y383084D01*
X282353Y383187D01*
X282660Y383084D01*
X282890Y382877D01*
X283043Y382567D01*
X283120Y382154D01*
X283043Y381792D01*
X282851Y381430D01*
X282621Y381224D01*
X282353Y381172D01*
X282046Y381275D01*
X281816Y381534D01*
X281586Y381999D01*
G01X279981Y382670D02*
X279751Y382980D01*
X279483Y383135D01*
X279176Y383187D01*
X278793Y383084D01*
X278525Y382825D01*
X278448Y382515D01*
X278486Y382205D01*
X278640Y381947D01*
X279406Y381430D01*
X279751Y381069D01*
X279981Y380552D01*
X280058Y380087D01*
X278448D01*
G01X279788Y386069D02*
Y389269D01*
G01X280737Y447911D02*
X283837D01*
Y448870D01*
X283682Y449176D01*
X283475Y449368D01*
X283062Y449445D01*
X282649Y449368D01*
X282390Y449138D01*
X282235Y448870D01*
Y447911D01*
G01Y448870D02*
X280737Y449445D01*
G01X281357Y450935D02*
X280995Y451165D01*
X280789Y451471D01*
X280737Y451816D01*
X280789Y452123D01*
X281047Y452430D01*
X281357Y452621D01*
X281667Y452660D01*
X282029Y452583D01*
X282287Y452315D01*
X282390Y452046D01*
Y451701D01*
G01Y452046D02*
X282545Y452276D01*
X282804Y452468D01*
X283114Y452545D01*
X283424Y452468D01*
X283682Y452276D01*
X283837Y451931D01*
X283785Y451586D01*
X283579Y451241D01*
G01X280737Y455338D02*
X283837D01*
X281615Y453920D01*
Y455836D01*
G01X283320Y457250D02*
X283630Y457480D01*
X283785Y457748D01*
X283837Y458055D01*
X283734Y458438D01*
X283475Y458706D01*
X283165Y458783D01*
X282855Y458745D01*
X282597Y458591D01*
X282080Y457825D01*
X281719Y457480D01*
X281202Y457250D01*
X280737Y457173D01*
Y458783D01*
G01X289624Y447911D02*
X292724D01*
Y448870D01*
X292569Y449176D01*
X292362Y449368D01*
X291949Y449445D01*
X291536Y449368D01*
X291277Y449138D01*
X291122Y448870D01*
Y447911D01*
G01Y448870D02*
X289624Y449445D01*
G01X290244Y450935D02*
X289882Y451165D01*
X289676Y451471D01*
X289624Y451816D01*
X289676Y452123D01*
X289934Y452430D01*
X290244Y452621D01*
X290554Y452660D01*
X290916Y452583D01*
X291174Y452315D01*
X291277Y452046D01*
Y451701D01*
G01Y452046D02*
X291432Y452276D01*
X291691Y452468D01*
X292001Y452545D01*
X292311Y452468D01*
X292569Y452276D01*
X292724Y451931D01*
X292672Y451586D01*
X292466Y451241D01*
G01X292207Y454150D02*
X292517Y454380D01*
X292672Y454648D01*
X292724Y454955D01*
X292621Y455338D01*
X292362Y455606D01*
X292052Y455683D01*
X291742Y455645D01*
X291484Y455491D01*
X290967Y454725D01*
X290606Y454380D01*
X290089Y454150D01*
X289624Y454073D01*
Y455683D01*
G01Y457978D02*
X292724D01*
X292104Y457518D01*
G01X289624D02*
Y458438D01*
G01X284927Y447911D02*
X288027D01*
Y448870D01*
X287872Y449176D01*
X287665Y449368D01*
X287252Y449445D01*
X286839Y449368D01*
X286580Y449138D01*
X286425Y448870D01*
Y447911D01*
G01Y448870D02*
X284927Y449445D01*
G01X285547Y450935D02*
X285185Y451165D01*
X284979Y451471D01*
X284927Y451816D01*
X284979Y452123D01*
X285237Y452430D01*
X285547Y452621D01*
X285857Y452660D01*
X286219Y452583D01*
X286477Y452315D01*
X286580Y452046D01*
Y451701D01*
G01Y452046D02*
X286735Y452276D01*
X286994Y452468D01*
X287304Y452545D01*
X287614Y452468D01*
X287872Y452276D01*
X288027Y451931D01*
X287975Y451586D01*
X287769Y451241D01*
G01X284927Y454878D02*
X288027D01*
X287407Y454418D01*
G01X284927D02*
Y455338D01*
G01X286219Y457250D02*
X286580Y457518D01*
X286787Y457748D01*
X286890Y458055D01*
X286787Y458323D01*
X286580Y458515D01*
X286270Y458668D01*
X285909Y458706D01*
X285599Y458668D01*
X285289Y458515D01*
X285030Y458285D01*
X284927Y458016D01*
X285030Y457710D01*
X285340Y457441D01*
X285805Y457288D01*
X286322Y457250D01*
X286994Y457326D01*
X287355Y457441D01*
X287717Y457633D01*
X287975Y457901D01*
X288027Y458170D01*
X287924Y458438D01*
X287665Y458630D01*
G01X283738Y460797D02*
Y470541D01*
X283493Y470786D01*
G01X275109Y464453D02*
Y470653D01*
G01X274809Y473453D02*
Y479653D01*
G01X283968Y479713D02*
X280768D01*
G01X283968Y473513D02*
Y479713D01*
G01X280768Y473513D02*
X283968D01*
G01X280768Y479713D02*
Y473513D01*
G01X279911Y479727D02*
X276711D01*
G01X279911Y473527D02*
Y479727D01*
G01X276711Y473527D02*
X279911D01*
G01X276711Y479727D02*
Y473527D01*
G01X275809Y488753D02*
Y494953D01*
G01X281304Y492055D02*
X276704D01*
G01Y486955D02*
X281304D01*
G01X276704Y497155D02*
Y486955D01*
G01X281304Y497155D02*
X276704D01*
G01X281304Y486955D02*
Y497155D01*
G01X293499Y492392D02*
X288899D01*
G01X293699Y496992D02*
X288699D01*
G01X293699Y486792D02*
X288699D01*
G01Y496992D02*
Y486792D01*
G01X293499Y491392D02*
X288899D01*
G01X287024Y493118D02*
X282424D01*
G01X287224Y487518D02*
X282224D01*
G01Y497718D02*
Y487518D01*
G01X287224D02*
Y497718D01*
G01X287024Y492118D02*
X282424D01*
G01X287224Y497718D02*
X282224D01*
G01X281440Y523180D02*
Y506670D01*
G01X275809Y513753D02*
Y519953D01*
G01X279809Y513253D02*
Y519453D01*
G01X276609Y513253D02*
X279809D01*
G01X276609Y519453D02*
Y513253D01*
G01X279709Y516353D02*
X276709D01*
G01X277670Y532720D02*
Y529150D01*
G01Y526150D02*
Y523180D01*
G01D02*
X281440D01*
G01X276038Y527822D02*
Y531022D01*
G01X275809Y520753D02*
Y523953D01*
G01X276038Y531822D02*
Y535022D01*
G01X279809Y519453D02*
X276609D01*
G01X281120Y548570D02*
Y545120D01*
G01Y542300D02*
Y541970D01*
G01X277670D02*
Y541810D01*
G01Y539050D02*
Y538710D01*
G01Y535940D02*
Y535490D01*
G01X281120Y541970D02*
X277670D01*
G01X276073Y539830D02*
Y543030D01*
G01X276038Y535822D02*
Y539022D01*
G01X279977Y544343D02*
Y548943D01*
G01X274877Y544343D02*
Y548943D01*
G01X278460Y558210D02*
X279990D01*
G01X281120Y557990D02*
Y557630D01*
G01Y554820D02*
Y554410D01*
G01Y551510D02*
Y551140D01*
G01X296175Y643978D02*
Y647078D01*
X295216D01*
X294910Y646923D01*
X294718Y646716D01*
X294641Y646303D01*
X294718Y645890D01*
X294948Y645631D01*
X295216Y645476D01*
X296175D01*
G01X295216D02*
X294641Y643978D01*
G01X293036Y645270D02*
X292768Y645631D01*
X292538Y645838D01*
X292231Y645941D01*
X291963Y645838D01*
X291771Y645631D01*
X291618Y645321D01*
X291580Y644960D01*
X291618Y644650D01*
X291771Y644340D01*
X292001Y644081D01*
X292270Y643978D01*
X292576Y644081D01*
X292845Y644391D01*
X292998Y644856D01*
X293036Y645373D01*
X292960Y646045D01*
X292845Y646406D01*
X292653Y646768D01*
X292385Y647026D01*
X292116Y647078D01*
X291848Y646975D01*
X291656Y646716D01*
G01X289936Y646561D02*
X289706Y646871D01*
X289438Y647026D01*
X289131Y647078D01*
X288748Y646975D01*
X288480Y646716D01*
X288403Y646406D01*
X288441Y646096D01*
X288595Y645838D01*
X289361Y645321D01*
X289706Y644960D01*
X289936Y644443D01*
X290013Y643978D01*
X288403D01*
G01X286836Y646561D02*
X286606Y646871D01*
X286338Y647026D01*
X286031Y647078D01*
X285648Y646975D01*
X285380Y646716D01*
X285303Y646406D01*
X285341Y646096D01*
X285495Y645838D01*
X286261Y645321D01*
X286606Y644960D01*
X286836Y644443D01*
X286913Y643978D01*
X285303D01*
G01X291345Y639475D02*
Y642575D01*
X290386D01*
X290080Y642420D01*
X289888Y642213D01*
X289811Y641800D01*
X289888Y641387D01*
X290118Y641128D01*
X290386Y640973D01*
X291345D01*
G01X290386D02*
X289811Y639475D01*
G01X287555D02*
X287478Y640147D01*
X287363Y640715D01*
X287210Y641232D01*
X287018Y641800D01*
X286711Y642575D01*
X288245D01*
G01X285030Y639837D02*
X284761Y639578D01*
X284455Y639475D01*
X284148Y639578D01*
X283880Y639888D01*
X283688Y640353D01*
X283611Y640818D01*
Y641387D01*
X283688Y641852D01*
X283880Y642265D01*
X284110Y642472D01*
X284378Y642575D01*
X284685Y642472D01*
X284915Y642265D01*
X285068Y641955D01*
X285145Y641542D01*
X285068Y641180D01*
X284876Y640818D01*
X284646Y640612D01*
X284378Y640560D01*
X284071Y640663D01*
X283841Y640922D01*
X283611Y641387D01*
G01X282121Y640095D02*
X281891Y639733D01*
X281585Y639527D01*
X281240Y639475D01*
X280933Y639527D01*
X280626Y639785D01*
X280435Y640095D01*
X280396Y640405D01*
X280473Y640767D01*
X280741Y641025D01*
X281010Y641128D01*
X281355D01*
G01X281010D02*
X280780Y641283D01*
X280588Y641542D01*
X280511Y641852D01*
X280588Y642162D01*
X280780Y642420D01*
X281125Y642575D01*
X281470Y642523D01*
X281815Y642317D01*
G01X280617Y653049D02*
X283717D01*
Y654008D01*
X283562Y654314D01*
X283355Y654506D01*
X282942Y654583D01*
X282529Y654506D01*
X282270Y654276D01*
X282115Y654008D01*
Y653049D01*
G01Y654008D02*
X280617Y654583D01*
G01X280979Y656264D02*
X280720Y656533D01*
X280617Y656839D01*
X280720Y657146D01*
X281030Y657414D01*
X281495Y657606D01*
X281960Y657683D01*
X282529D01*
X282994Y657606D01*
X283407Y657414D01*
X283614Y657184D01*
X283717Y656916D01*
X283614Y656609D01*
X283407Y656379D01*
X283097Y656226D01*
X282684Y656149D01*
X282322Y656226D01*
X281960Y656418D01*
X281754Y656648D01*
X281702Y656916D01*
X281805Y657223D01*
X282064Y657453D01*
X282529Y657683D01*
G01X280617Y660016D02*
X283717D01*
X283097Y659556D01*
G01X280617D02*
Y660476D01*
G01Y663116D02*
X283717D01*
X283097Y662656D01*
G01X280617D02*
Y663576D01*
G01X284088Y653034D02*
X287188D01*
Y653993D01*
X287033Y654299D01*
X286826Y654491D01*
X286413Y654568D01*
X286000Y654491D01*
X285741Y654261D01*
X285586Y653993D01*
Y653034D01*
G01Y653993D02*
X284088Y654568D01*
G01X284450Y656249D02*
X284191Y656518D01*
X284088Y656824D01*
X284191Y657131D01*
X284501Y657399D01*
X284966Y657591D01*
X285431Y657668D01*
X286000D01*
X286465Y657591D01*
X286878Y657399D01*
X287085Y657169D01*
X287188Y656901D01*
X287085Y656594D01*
X286878Y656364D01*
X286568Y656211D01*
X286155Y656134D01*
X285793Y656211D01*
X285431Y656403D01*
X285225Y656633D01*
X285173Y656901D01*
X285276Y657208D01*
X285535Y657438D01*
X286000Y657668D01*
G01X284088Y660001D02*
X287188D01*
X286568Y659541D01*
G01X284088D02*
Y660461D01*
G01Y663024D02*
X284760Y663101D01*
X285328Y663216D01*
X285845Y663369D01*
X286413Y663561D01*
X287188Y663868D01*
Y662334D01*
G01X284850Y687423D02*
X287950D01*
Y688382D01*
X287795Y688688D01*
X287588Y688880D01*
X287175Y688957D01*
X286762Y688880D01*
X286503Y688650D01*
X286348Y688382D01*
Y687423D01*
G01Y688382D02*
X284850Y688957D01*
G01Y691290D02*
X287950D01*
X287330Y690830D01*
G01X284850D02*
Y691750D01*
G01Y694390D02*
X287950D01*
X287330Y693930D01*
G01X284850D02*
Y694850D01*
G01X286142Y696762D02*
X286503Y697030D01*
X286710Y697260D01*
X286813Y697567D01*
X286710Y697835D01*
X286503Y698027D01*
X286193Y698180D01*
X285832Y698218D01*
X285522Y698180D01*
X285212Y698027D01*
X284953Y697797D01*
X284850Y697528D01*
X284953Y697222D01*
X285263Y696953D01*
X285728Y696800D01*
X286245Y696762D01*
X286917Y696838D01*
X287278Y696953D01*
X287640Y697145D01*
X287898Y697413D01*
X287950Y697682D01*
X287847Y697950D01*
X287588Y698142D01*
G01X285315Y699747D02*
X285057Y699977D01*
X284902Y700245D01*
X284850Y700590D01*
X284953Y700935D01*
X285160Y701203D01*
X285522Y701395D01*
X285935Y701433D01*
X286348Y701357D01*
X286607Y701165D01*
X286813Y700897D01*
X286865Y700628D01*
X286813Y700360D01*
X286607Y700015D01*
X287950Y700130D01*
Y701165D01*
G01X290321Y687735D02*
X293421D01*
Y688694D01*
X293266Y689000D01*
X293059Y689192D01*
X292646Y689269D01*
X292233Y689192D01*
X291974Y688962D01*
X291819Y688694D01*
Y687735D01*
G01Y688694D02*
X290321Y689269D01*
G01Y691602D02*
X293421D01*
X292801Y691142D01*
G01X290321D02*
Y692062D01*
G01Y694702D02*
X293421D01*
X292801Y694242D01*
G01X290321D02*
Y695162D01*
G01X291613Y697074D02*
X291974Y697342D01*
X292181Y697572D01*
X292284Y697879D01*
X292181Y698147D01*
X291974Y698339D01*
X291664Y698492D01*
X291303Y698530D01*
X290993Y698492D01*
X290683Y698339D01*
X290424Y698109D01*
X290321Y697840D01*
X290424Y697534D01*
X290734Y697265D01*
X291199Y697112D01*
X291716Y697074D01*
X292388Y697150D01*
X292749Y697265D01*
X293111Y697457D01*
X293369Y697725D01*
X293421Y697994D01*
X293318Y698262D01*
X293059Y698454D01*
G01X291613Y700174D02*
X291974Y700442D01*
X292181Y700672D01*
X292284Y700979D01*
X292181Y701247D01*
X291974Y701439D01*
X291664Y701592D01*
X291303Y701630D01*
X290993Y701592D01*
X290683Y701439D01*
X290424Y701209D01*
X290321Y700940D01*
X290424Y700634D01*
X290734Y700365D01*
X291199Y700212D01*
X291716Y700174D01*
X292388Y700250D01*
X292749Y700365D01*
X293111Y700557D01*
X293369Y700825D01*
X293421Y701094D01*
X293318Y701362D01*
X293059Y701554D01*
G01X287030Y725837D02*
X290230D01*
G01X287030Y732037D02*
Y725837D01*
G01X290230Y732037D02*
X287030D01*
G01X287130Y728937D02*
X290130D01*
G01X281840Y737556D02*
X285040D01*
G01X281840Y743756D02*
Y737556D01*
G01X285040D02*
Y743756D01*
G01X277040Y737556D02*
Y743756D01*
G01X278340Y725756D02*
X281540D01*
G01X278340Y731956D02*
Y725756D01*
G01X281540Y731956D02*
X278340D01*
G01X281540Y725756D02*
Y731956D01*
G01X278440Y728856D02*
X281440D01*
G01X289840Y737556D02*
X293040D01*
G01X289840Y743756D02*
Y737556D01*
G01X285840D02*
X289040D01*
G01X285840Y743756D02*
Y737556D01*
G01X289040D02*
Y743756D01*
G01X281040Y737556D02*
Y743756D01*
G01X277840Y737556D02*
X281040D01*
G01X277840Y743756D02*
Y737556D01*
G01X277040Y726056D02*
Y732256D01*
G01X289725Y747275D02*
X289880Y747045D01*
X289983Y746777D01*
Y746470D01*
X289828Y746125D01*
X289570Y745857D01*
X289260Y745665D01*
X288743Y745512D01*
X288278Y745474D01*
X287813Y745550D01*
X287503Y745665D01*
X287193Y745895D01*
X286986Y746164D01*
X286883Y746432D01*
Y746700D01*
X286986Y746969D01*
X287141Y747199D01*
X287348Y747390D01*
G01X288175Y748804D02*
X288536Y749072D01*
X288743Y749302D01*
X288846Y749609D01*
X288743Y749877D01*
X288536Y750069D01*
X288226Y750222D01*
X287865Y750260D01*
X287555Y750222D01*
X287245Y750069D01*
X286986Y749839D01*
X286883Y749570D01*
X286986Y749264D01*
X287296Y748995D01*
X287761Y748842D01*
X288278Y748804D01*
X288950Y748880D01*
X289311Y748995D01*
X289673Y749187D01*
X289931Y749455D01*
X289983Y749724D01*
X289880Y749992D01*
X289621Y750184D01*
G01X286883Y752555D02*
X287555Y752632D01*
X288123Y752747D01*
X288640Y752900D01*
X289208Y753092D01*
X289983Y753399D01*
Y751865D01*
G01X286883Y755655D02*
X287555Y755732D01*
X288123Y755847D01*
X288640Y756000D01*
X289208Y756192D01*
X289983Y756499D01*
Y754965D01*
G01X285040Y743756D02*
X281840D01*
G01X281940Y740656D02*
X284940D01*
G01X281184Y747194D02*
X281339Y746964D01*
X281442Y746696D01*
Y746389D01*
X281287Y746044D01*
X281029Y745776D01*
X280719Y745584D01*
X280202Y745431D01*
X279737Y745393D01*
X279272Y745469D01*
X278962Y745584D01*
X278652Y745814D01*
X278445Y746083D01*
X278342Y746351D01*
Y746619D01*
X278445Y746888D01*
X278600Y747118D01*
X278807Y747309D01*
G01X279634Y748723D02*
X279995Y748991D01*
X280202Y749221D01*
X280305Y749528D01*
X280202Y749796D01*
X279995Y749988D01*
X279685Y750141D01*
X279324Y750179D01*
X279014Y750141D01*
X278704Y749988D01*
X278445Y749758D01*
X278342Y749489D01*
X278445Y749183D01*
X278755Y748914D01*
X279220Y748761D01*
X279737Y748723D01*
X280409Y748799D01*
X280770Y748914D01*
X281132Y749106D01*
X281390Y749374D01*
X281442Y749643D01*
X281339Y749911D01*
X281080Y750103D01*
G01X278342Y752551D02*
X278394Y752819D01*
X278549Y753126D01*
X278807Y753318D01*
X279169Y753394D01*
X279530Y753318D01*
X279840Y753088D01*
X279995Y752743D01*
Y752359D01*
X280099Y752129D01*
X280357Y751938D01*
X280719Y751861D01*
X281080Y751976D01*
X281339Y752244D01*
X281442Y752551D01*
X281339Y752858D01*
X281080Y753126D01*
X280719Y753241D01*
X280357Y753164D01*
X280099Y752973D01*
X279995Y752743D01*
Y752359D01*
X279840Y752014D01*
X279530Y751784D01*
X279169Y751708D01*
X278807Y751784D01*
X278549Y751976D01*
X278394Y752283D01*
X278342Y752551D01*
G01X278962Y754808D02*
X278600Y755038D01*
X278394Y755344D01*
X278342Y755689D01*
X278394Y755996D01*
X278652Y756303D01*
X278962Y756494D01*
X279272Y756533D01*
X279634Y756456D01*
X279892Y756188D01*
X279995Y755919D01*
Y755574D01*
G01Y755919D02*
X280150Y756149D01*
X280409Y756341D01*
X280719Y756418D01*
X281029Y756341D01*
X281287Y756149D01*
X281442Y755804D01*
X281390Y755459D01*
X281184Y755114D01*
G01X293040Y743756D02*
X289840D01*
G01X289940Y740656D02*
X292940D01*
G01X289040Y743756D02*
X285840D01*
G01X281040D02*
X277840D01*
G01X283572Y759650D02*
X283727Y759420D01*
X283830Y759152D01*
Y758845D01*
X283675Y758500D01*
X283417Y758232D01*
X283107Y758040D01*
X282590Y757887D01*
X282125Y757849D01*
X281660Y757925D01*
X281350Y758040D01*
X281040Y758270D01*
X280833Y758539D01*
X280730Y758807D01*
Y759075D01*
X280833Y759344D01*
X280988Y759574D01*
X281195Y759765D01*
G01X282022Y761179D02*
X282383Y761447D01*
X282590Y761677D01*
X282693Y761984D01*
X282590Y762252D01*
X282383Y762444D01*
X282073Y762597D01*
X281712Y762635D01*
X281402Y762597D01*
X281092Y762444D01*
X280833Y762214D01*
X280730Y761945D01*
X280833Y761639D01*
X281143Y761370D01*
X281608Y761217D01*
X282125Y761179D01*
X282797Y761255D01*
X283158Y761370D01*
X283520Y761562D01*
X283778Y761830D01*
X283830Y762099D01*
X283727Y762367D01*
X283468Y762559D01*
G01X280730Y765007D02*
X280782Y765275D01*
X280937Y765582D01*
X281195Y765774D01*
X281557Y765850D01*
X281918Y765774D01*
X282228Y765544D01*
X282383Y765199D01*
Y764815D01*
X282487Y764585D01*
X282745Y764394D01*
X283107Y764317D01*
X283468Y764432D01*
X283727Y764700D01*
X283830Y765007D01*
X283727Y765314D01*
X283468Y765582D01*
X283107Y765697D01*
X282745Y765620D01*
X282487Y765429D01*
X282383Y765199D01*
Y764815D01*
X282228Y764470D01*
X281918Y764240D01*
X281557Y764164D01*
X281195Y764240D01*
X280937Y764432D01*
X280782Y764739D01*
X280730Y765007D01*
G01X283830Y768107D02*
X283727Y767800D01*
X283468Y767570D01*
X283158Y767417D01*
X282745Y767302D01*
X282280Y767264D01*
X281815Y767302D01*
X281402Y767417D01*
X281092Y767570D01*
X280833Y767800D01*
X280730Y768107D01*
X280833Y768414D01*
X281092Y768644D01*
X281402Y768797D01*
X281815Y768912D01*
X282280Y768950D01*
X282745Y768912D01*
X283158Y768797D01*
X283468Y768644D01*
X283727Y768414D01*
X283830Y768107D01*
G01X291288Y759650D02*
X291443Y759420D01*
X291546Y759152D01*
Y758845D01*
X291391Y758500D01*
X291133Y758232D01*
X290823Y758040D01*
X290306Y757887D01*
X289841Y757849D01*
X289376Y757925D01*
X289066Y758040D01*
X288756Y758270D01*
X288549Y758539D01*
X288446Y758807D01*
Y759075D01*
X288549Y759344D01*
X288704Y759574D01*
X288911Y759765D01*
G01X289738Y761179D02*
X290099Y761447D01*
X290306Y761677D01*
X290409Y761984D01*
X290306Y762252D01*
X290099Y762444D01*
X289789Y762597D01*
X289428Y762635D01*
X289118Y762597D01*
X288808Y762444D01*
X288549Y762214D01*
X288446Y761945D01*
X288549Y761639D01*
X288859Y761370D01*
X289324Y761217D01*
X289841Y761179D01*
X290513Y761255D01*
X290874Y761370D01*
X291236Y761562D01*
X291494Y761830D01*
X291546Y762099D01*
X291443Y762367D01*
X291184Y762559D01*
G01X288446Y764930D02*
X289118Y765007D01*
X289686Y765122D01*
X290203Y765275D01*
X290771Y765467D01*
X291546Y765774D01*
Y764240D01*
G01X288446Y768567D02*
X291546D01*
X289324Y767149D01*
Y769065D01*
G01X284782Y758040D02*
X287882D01*
Y758999D01*
X287727Y759305D01*
X287520Y759497D01*
X287107Y759574D01*
X286694Y759497D01*
X286435Y759267D01*
X286280Y758999D01*
Y758040D01*
G01Y758999D02*
X284782Y759574D01*
G01X285144Y761255D02*
X284885Y761524D01*
X284782Y761830D01*
X284885Y762137D01*
X285195Y762405D01*
X285660Y762597D01*
X286125Y762674D01*
X286694D01*
X287159Y762597D01*
X287572Y762405D01*
X287779Y762175D01*
X287882Y761907D01*
X287779Y761600D01*
X287572Y761370D01*
X287262Y761217D01*
X286849Y761140D01*
X286487Y761217D01*
X286125Y761409D01*
X285919Y761639D01*
X285867Y761907D01*
X285970Y762214D01*
X286229Y762444D01*
X286694Y762674D01*
G01X284782Y765007D02*
X287882D01*
X287262Y764547D01*
G01X284782D02*
Y765467D01*
G01Y768567D02*
X287882D01*
X285660Y767149D01*
Y769065D01*
G01X276682Y758040D02*
X279782D01*
Y758999D01*
X279627Y759305D01*
X279420Y759497D01*
X279007Y759574D01*
X278594Y759497D01*
X278335Y759267D01*
X278180Y758999D01*
Y758040D01*
G01Y758999D02*
X276682Y759574D01*
G01X277044Y761255D02*
X276785Y761524D01*
X276682Y761830D01*
X276785Y762137D01*
X277095Y762405D01*
X277560Y762597D01*
X278025Y762674D01*
X278594D01*
X279059Y762597D01*
X279472Y762405D01*
X279679Y762175D01*
X279782Y761907D01*
X279679Y761600D01*
X279472Y761370D01*
X279162Y761217D01*
X278749Y761140D01*
X278387Y761217D01*
X278025Y761409D01*
X277819Y761639D01*
X277767Y761907D01*
X277870Y762214D01*
X278129Y762444D01*
X278594Y762674D01*
G01X279265Y764279D02*
X279575Y764509D01*
X279730Y764777D01*
X279782Y765084D01*
X279679Y765467D01*
X279420Y765735D01*
X279110Y765812D01*
X278800Y765774D01*
X278542Y765620D01*
X278025Y764854D01*
X277664Y764509D01*
X277147Y764279D01*
X276682Y764202D01*
Y765812D01*
G01X279782Y768107D02*
X279679Y767800D01*
X279420Y767570D01*
X279110Y767417D01*
X278697Y767302D01*
X278232Y767264D01*
X277767Y767302D01*
X277354Y767417D01*
X277044Y767570D01*
X276785Y767800D01*
X276682Y768107D01*
X276785Y768414D01*
X277044Y768644D01*
X277354Y768797D01*
X277767Y768912D01*
X278232Y768950D01*
X278697Y768912D01*
X279110Y768797D01*
X279420Y768644D01*
X279679Y768414D01*
X279782Y768107D01*
G01X297000Y62191D02*
X297155Y61961D01*
X297258Y61693D01*
Y61386D01*
X297103Y61041D01*
X296845Y60773D01*
X296535Y60581D01*
X296018Y60428D01*
X295553Y60390D01*
X295088Y60466D01*
X294778Y60581D01*
X294468Y60811D01*
X294261Y61080D01*
X294158Y61348D01*
Y61616D01*
X294261Y61885D01*
X294416Y62115D01*
X294623Y62306D01*
G01X294158Y64448D02*
X297258D01*
X296638Y63988D01*
G01X294158D02*
Y64908D01*
G01X294623Y66705D02*
X294365Y66935D01*
X294210Y67203D01*
X294158Y67548D01*
X294261Y67893D01*
X294468Y68161D01*
X294830Y68353D01*
X295243Y68391D01*
X295656Y68315D01*
X295915Y68123D01*
X296121Y67855D01*
X296173Y67586D01*
X296121Y67318D01*
X295915Y66973D01*
X297258Y67088D01*
Y68123D01*
G01X294158Y71108D02*
X297258D01*
X295036Y69690D01*
Y71606D01*
G01X309354Y62191D02*
X309509Y61961D01*
X309612Y61693D01*
Y61386D01*
X309457Y61041D01*
X309199Y60773D01*
X308889Y60581D01*
X308372Y60428D01*
X307907Y60390D01*
X307442Y60466D01*
X307132Y60581D01*
X306822Y60811D01*
X306615Y61080D01*
X306512Y61348D01*
Y61616D01*
X306615Y61885D01*
X306770Y62115D01*
X306977Y62306D01*
G01X306512Y64448D02*
X309612D01*
X308992Y63988D01*
G01X306512D02*
Y64908D01*
G01Y68008D02*
X309612D01*
X307390Y66590D01*
Y68506D01*
G01X307804Y69920D02*
X308165Y70188D01*
X308372Y70418D01*
X308475Y70725D01*
X308372Y70993D01*
X308165Y71185D01*
X307855Y71338D01*
X307494Y71376D01*
X307184Y71338D01*
X306874Y71185D01*
X306615Y70955D01*
X306512Y70686D01*
X306615Y70380D01*
X306925Y70111D01*
X307390Y69958D01*
X307907Y69920D01*
X308579Y69996D01*
X308940Y70111D01*
X309302Y70303D01*
X309560Y70571D01*
X309612Y70840D01*
X309509Y71108D01*
X309250Y71300D01*
G01X305095Y62191D02*
X305250Y61961D01*
X305353Y61693D01*
Y61386D01*
X305198Y61041D01*
X304940Y60773D01*
X304630Y60581D01*
X304113Y60428D01*
X303648Y60390D01*
X303183Y60466D01*
X302873Y60581D01*
X302563Y60811D01*
X302356Y61080D01*
X302253Y61348D01*
Y61616D01*
X302356Y61885D01*
X302511Y62115D01*
X302718Y62306D01*
G01X302253Y64448D02*
X305353D01*
X304733Y63988D01*
G01X302253D02*
Y64908D01*
G01Y67471D02*
X302925Y67548D01*
X303493Y67663D01*
X304010Y67816D01*
X304578Y68008D01*
X305353Y68315D01*
Y66781D01*
G01X302253Y70648D02*
X302305Y70916D01*
X302460Y71223D01*
X302718Y71415D01*
X303080Y71491D01*
X303441Y71415D01*
X303751Y71185D01*
X303906Y70840D01*
Y70456D01*
X304010Y70226D01*
X304268Y70035D01*
X304630Y69958D01*
X304991Y70073D01*
X305250Y70341D01*
X305353Y70648D01*
X305250Y70955D01*
X304991Y71223D01*
X304630Y71338D01*
X304268Y71261D01*
X304010Y71070D01*
X303906Y70840D01*
Y70456D01*
X303751Y70111D01*
X303441Y69881D01*
X303080Y69805D01*
X302718Y69881D01*
X302460Y70073D01*
X302305Y70380D01*
X302253Y70648D01*
G01X300930Y62191D02*
X301085Y61961D01*
X301188Y61693D01*
Y61386D01*
X301033Y61041D01*
X300775Y60773D01*
X300465Y60581D01*
X299948Y60428D01*
X299483Y60390D01*
X299018Y60466D01*
X298708Y60581D01*
X298398Y60811D01*
X298191Y61080D01*
X298088Y61348D01*
Y61616D01*
X298191Y61885D01*
X298346Y62115D01*
X298553Y62306D01*
G01X298088Y64448D02*
X301188D01*
X300568Y63988D01*
G01X298088D02*
Y64908D01*
G01Y67471D02*
X298760Y67548D01*
X299328Y67663D01*
X299845Y67816D01*
X300413Y68008D01*
X301188Y68315D01*
Y66781D01*
G01X298553Y69805D02*
X298295Y70035D01*
X298140Y70303D01*
X298088Y70648D01*
X298191Y70993D01*
X298398Y71261D01*
X298760Y71453D01*
X299173Y71491D01*
X299586Y71415D01*
X299845Y71223D01*
X300051Y70955D01*
X300103Y70686D01*
X300051Y70418D01*
X299845Y70073D01*
X301188Y70188D01*
Y71223D01*
G01X297462Y86260D02*
X294262D01*
G01D02*
Y80060D01*
G01D02*
X297462D01*
G01D02*
Y86260D01*
G01X297362Y83160D02*
X294362D01*
G01X293424Y86340D02*
X290224D01*
G01D02*
Y80140D01*
G01D02*
X293424D01*
G01D02*
Y86340D01*
G01X293324Y83240D02*
X290324D01*
G01X308521Y87539D02*
X303921D01*
G01Y77339D02*
X308521D01*
G01X303921Y87539D02*
Y77339D01*
G01Y82439D02*
X308521D01*
G01X303121Y87539D02*
X298521D01*
G01Y77339D02*
X303121D01*
G01X298521Y87539D02*
Y77339D01*
G01X303121D02*
Y87539D01*
G01X298521Y82439D02*
X303121D01*
G01X300350Y118097D02*
X300580Y118252D01*
X300848Y118355D01*
X301155D01*
X301500Y118200D01*
X301768Y117942D01*
X301960Y117632D01*
X302113Y117115D01*
X302151Y116650D01*
X302075Y116185D01*
X301960Y115875D01*
X301730Y115565D01*
X301461Y115358D01*
X301193Y115255D01*
X300925D01*
X300656Y115358D01*
X300426Y115513D01*
X300235Y115720D01*
G01X298093Y115255D02*
Y118355D01*
X298553Y117735D01*
G01Y115255D02*
X297633D01*
G01X294533D02*
Y118355D01*
X295951Y116133D01*
X294035D01*
G01X291433Y115255D02*
Y118355D01*
X292851Y116133D01*
X290935D01*
G01X292200Y123310D02*
X298400D01*
G01X292200Y126510D02*
Y123310D01*
G01X298400D02*
Y126510D01*
G01X295300Y126410D02*
Y123410D01*
G01X300350Y114097D02*
X300580Y114252D01*
X300848Y114355D01*
X301155D01*
X301500Y114200D01*
X301768Y113942D01*
X301960Y113632D01*
X302113Y113115D01*
X302151Y112650D01*
X302075Y112185D01*
X301960Y111875D01*
X301730Y111565D01*
X301461Y111358D01*
X301193Y111255D01*
X300925D01*
X300656Y111358D01*
X300426Y111513D01*
X300235Y111720D01*
G01X298093Y111255D02*
Y114355D01*
X298553Y113735D01*
G01Y111255D02*
X297633D01*
G01X295836Y111720D02*
X295606Y111462D01*
X295338Y111307D01*
X294993Y111255D01*
X294648Y111358D01*
X294380Y111565D01*
X294188Y111927D01*
X294150Y112340D01*
X294226Y112753D01*
X294418Y113012D01*
X294686Y113218D01*
X294955Y113270D01*
X295223Y113218D01*
X295568Y113012D01*
X295453Y114355D01*
X294418D01*
G01X292736Y111875D02*
X292506Y111513D01*
X292200Y111307D01*
X291855Y111255D01*
X291548Y111307D01*
X291241Y111565D01*
X291050Y111875D01*
X291011Y112185D01*
X291088Y112547D01*
X291356Y112805D01*
X291625Y112908D01*
X291970D01*
G01X291625D02*
X291395Y113063D01*
X291203Y113322D01*
X291126Y113632D01*
X291203Y113942D01*
X291395Y114200D01*
X291740Y114355D01*
X292085Y114303D01*
X292430Y114097D01*
G01X292200Y119310D02*
X298400D01*
G01Y122510D02*
X292200D01*
G01D02*
Y119310D01*
G01X298400D02*
Y122510D01*
G01X295300Y122410D02*
Y119410D01*
G01X298400Y126510D02*
X292200D01*
G01X302450Y242838D02*
Y245938D01*
X301530D01*
X301223Y245783D01*
X300993Y245421D01*
X300916Y245008D01*
X300993Y244595D01*
X301185Y244285D01*
X301530Y244130D01*
X302450D01*
G01X299350Y243458D02*
X299158Y243148D01*
X298928Y242941D01*
X298660Y242838D01*
X298353Y242941D01*
X298123Y243148D01*
X297893Y243458D01*
X297816Y243871D01*
Y245938D01*
G01X295483Y242838D02*
Y245938D01*
X295943Y245318D01*
G01Y242838D02*
X295023D01*
G01X292383D02*
Y245938D01*
X292843Y245318D01*
G01Y242838D02*
X291923D01*
G01X302634Y238470D02*
Y241570D01*
X301714D01*
X301407Y241415D01*
X301177Y241053D01*
X301100Y240640D01*
X301177Y240227D01*
X301369Y239917D01*
X301714Y239762D01*
X302634D01*
G01X299534Y239090D02*
X299342Y238780D01*
X299112Y238573D01*
X298844Y238470D01*
X298537Y238573D01*
X298307Y238780D01*
X298077Y239090D01*
X298000Y239503D01*
Y241570D01*
G01X295667Y238470D02*
Y241570D01*
X296127Y240950D01*
G01Y238470D02*
X295207D01*
G01X293295Y241053D02*
X293065Y241363D01*
X292797Y241518D01*
X292490Y241570D01*
X292107Y241467D01*
X291839Y241208D01*
X291762Y240898D01*
X291800Y240588D01*
X291954Y240330D01*
X292720Y239813D01*
X293065Y239452D01*
X293295Y238935D01*
X293372Y238470D01*
X291762D01*
G01X296310Y307140D02*
Y310788D01*
G01Y307140D02*
X297621D01*
G01X296310Y312270D02*
Y310788D01*
G01X308000Y307140D02*
X297621D01*
G01X301451Y312143D02*
X308251D01*
G01X301451Y327143D02*
Y312143D01*
G01X293617Y305275D02*
Y308475D01*
G01X296410Y327148D02*
Y322621D01*
G01X290490Y322140D02*
X293930D01*
G01X296410Y330159D02*
Y327148D01*
G01X290490Y321450D02*
Y322140D01*
G01X297635Y324225D02*
X300635D01*
G01X300735Y327325D02*
X297535D01*
G01Y321125D02*
X300735D01*
G01X297535Y327325D02*
Y321125D01*
G01X300735D02*
Y327325D01*
G01X293718Y316987D02*
X290718D01*
G01X290618Y320087D02*
Y313887D01*
G01D02*
X293818D01*
G01D02*
Y320087D01*
G01D02*
X290618D01*
G01X297718Y316987D02*
X294718D01*
G01X294618Y320087D02*
Y313887D01*
G01D02*
X297818D01*
G01D02*
Y320087D01*
G01D02*
X294618D01*
G01X308251Y327143D02*
X301451D01*
G01X308151Y319643D02*
X301551D01*
G01X304939Y332006D02*
Y328806D01*
G01D02*
X311139D01*
G01X302258Y337240D02*
X307576D01*
G01X297916D02*
X298631D01*
G01X296410D02*
X297916D01*
G01X296410D02*
Y330159D01*
G01X298850Y342746D02*
X305050D01*
G01D02*
Y345946D01*
G01X298850D02*
Y342746D01*
G01X311139Y332006D02*
X304939D01*
G01X309645Y335980D02*
X303445D01*
G01D02*
Y332780D01*
G01D02*
X309645D01*
G01X297348Y358871D02*
X300448D01*
Y359830D01*
X300293Y360136D01*
X300086Y360328D01*
X299673Y360405D01*
X299260Y360328D01*
X299001Y360098D01*
X298846Y359830D01*
Y358871D01*
G01Y359830D02*
X297348Y360405D01*
G01X297710Y362086D02*
X297451Y362355D01*
X297348Y362661D01*
X297451Y362968D01*
X297761Y363236D01*
X298226Y363428D01*
X298691Y363505D01*
X299260D01*
X299725Y363428D01*
X300138Y363236D01*
X300345Y363006D01*
X300448Y362738D01*
X300345Y362431D01*
X300138Y362201D01*
X299828Y362048D01*
X299415Y361971D01*
X299053Y362048D01*
X298691Y362240D01*
X298485Y362470D01*
X298433Y362738D01*
X298536Y363045D01*
X298795Y363275D01*
X299260Y363505D01*
G01X298640Y365110D02*
X299001Y365378D01*
X299208Y365608D01*
X299311Y365915D01*
X299208Y366183D01*
X299001Y366375D01*
X298691Y366528D01*
X298330Y366566D01*
X298020Y366528D01*
X297710Y366375D01*
X297451Y366145D01*
X297348Y365876D01*
X297451Y365570D01*
X297761Y365301D01*
X298226Y365148D01*
X298743Y365110D01*
X299415Y365186D01*
X299776Y365301D01*
X300138Y365493D01*
X300396Y365761D01*
X300448Y366030D01*
X300345Y366298D01*
X300086Y366490D01*
G01X301348Y358871D02*
X304448D01*
Y359830D01*
X304293Y360136D01*
X304086Y360328D01*
X303673Y360405D01*
X303260Y360328D01*
X303001Y360098D01*
X302846Y359830D01*
Y358871D01*
G01Y359830D02*
X301348Y360405D01*
G01X301710Y362086D02*
X301451Y362355D01*
X301348Y362661D01*
X301451Y362968D01*
X301761Y363236D01*
X302226Y363428D01*
X302691Y363505D01*
X303260D01*
X303725Y363428D01*
X304138Y363236D01*
X304345Y363006D01*
X304448Y362738D01*
X304345Y362431D01*
X304138Y362201D01*
X303828Y362048D01*
X303415Y361971D01*
X303053Y362048D01*
X302691Y362240D01*
X302485Y362470D01*
X302433Y362738D01*
X302536Y363045D01*
X302795Y363275D01*
X303260Y363505D01*
G01X301348Y366298D02*
X304448D01*
X302226Y364880D01*
Y366796D01*
G01X306617Y348904D02*
Y352004D01*
X305658D01*
X305352Y351849D01*
X305160Y351642D01*
X305083Y351229D01*
X305160Y350816D01*
X305390Y350557D01*
X305658Y350402D01*
X306617D01*
G01X305658D02*
X305083Y348904D01*
G01X302750D02*
Y352004D01*
X303210Y351384D01*
G01Y348904D02*
X302290D01*
G01X299190D02*
Y352004D01*
X300608Y349782D01*
X298692D01*
G01X296090Y348904D02*
Y352004D01*
X297508Y349782D01*
X295592D01*
G01X305050Y345946D02*
X298850D01*
G01X298731Y373696D02*
X295531D01*
G01X298731Y367496D02*
Y373696D01*
G01X295531D02*
Y367496D01*
G01D02*
X298731D01*
G01X302731Y373696D02*
X299531D01*
G01X302731Y367496D02*
Y373696D01*
G01X299531D02*
Y367496D01*
G01D02*
X302731D01*
G01X293722Y447911D02*
X296822D01*
Y448870D01*
X296667Y449176D01*
X296460Y449368D01*
X296047Y449445D01*
X295634Y449368D01*
X295375Y449138D01*
X295220Y448870D01*
Y447911D01*
G01Y448870D02*
X293722Y449445D01*
G01X294342Y450935D02*
X293980Y451165D01*
X293774Y451471D01*
X293722Y451816D01*
X293774Y452123D01*
X294032Y452430D01*
X294342Y452621D01*
X294652Y452660D01*
X295014Y452583D01*
X295272Y452315D01*
X295375Y452046D01*
Y451701D01*
G01Y452046D02*
X295530Y452276D01*
X295789Y452468D01*
X296099Y452545D01*
X296409Y452468D01*
X296667Y452276D01*
X296822Y451931D01*
X296770Y451586D01*
X296564Y451241D01*
G01X294342Y454035D02*
X293980Y454265D01*
X293774Y454571D01*
X293722Y454916D01*
X293774Y455223D01*
X294032Y455530D01*
X294342Y455721D01*
X294652Y455760D01*
X295014Y455683D01*
X295272Y455415D01*
X295375Y455146D01*
Y454801D01*
G01Y455146D02*
X295530Y455376D01*
X295789Y455568D01*
X296099Y455645D01*
X296409Y455568D01*
X296667Y455376D01*
X296822Y455031D01*
X296770Y454686D01*
X296564Y454341D01*
G01X293722Y457901D02*
X294394Y457978D01*
X294962Y458093D01*
X295479Y458246D01*
X296047Y458438D01*
X296822Y458745D01*
Y457211D01*
G01X298233Y447911D02*
X301333D01*
Y448870D01*
X301178Y449176D01*
X300971Y449368D01*
X300558Y449445D01*
X300145Y449368D01*
X299886Y449138D01*
X299731Y448870D01*
Y447911D01*
G01Y448870D02*
X298233Y449445D01*
G01X298853Y450935D02*
X298491Y451165D01*
X298285Y451471D01*
X298233Y451816D01*
X298285Y452123D01*
X298543Y452430D01*
X298853Y452621D01*
X299163Y452660D01*
X299525Y452583D01*
X299783Y452315D01*
X299886Y452046D01*
Y451701D01*
G01Y452046D02*
X300041Y452276D01*
X300300Y452468D01*
X300610Y452545D01*
X300920Y452468D01*
X301178Y452276D01*
X301333Y451931D01*
X301281Y451586D01*
X301075Y451241D01*
G01X300816Y454150D02*
X301126Y454380D01*
X301281Y454648D01*
X301333Y454955D01*
X301230Y455338D01*
X300971Y455606D01*
X300661Y455683D01*
X300351Y455645D01*
X300093Y455491D01*
X299576Y454725D01*
X299215Y454380D01*
X298698Y454150D01*
X298233Y454073D01*
Y455683D01*
G01X298698Y457135D02*
X298440Y457365D01*
X298285Y457633D01*
X298233Y457978D01*
X298336Y458323D01*
X298543Y458591D01*
X298905Y458783D01*
X299318Y458821D01*
X299731Y458745D01*
X299990Y458553D01*
X300196Y458285D01*
X300248Y458016D01*
X300196Y457748D01*
X299990Y457403D01*
X301333Y457518D01*
Y458553D01*
G01X306798Y447911D02*
X309898D01*
Y448870D01*
X309743Y449176D01*
X309536Y449368D01*
X309123Y449445D01*
X308710Y449368D01*
X308451Y449138D01*
X308296Y448870D01*
Y447911D01*
G01Y448870D02*
X306798Y449445D01*
G01X307418Y450935D02*
X307056Y451165D01*
X306850Y451471D01*
X306798Y451816D01*
X306850Y452123D01*
X307108Y452430D01*
X307418Y452621D01*
X307728Y452660D01*
X308090Y452583D01*
X308348Y452315D01*
X308451Y452046D01*
Y451701D01*
G01Y452046D02*
X308606Y452276D01*
X308865Y452468D01*
X309175Y452545D01*
X309485Y452468D01*
X309743Y452276D01*
X309898Y451931D01*
X309846Y451586D01*
X309640Y451241D01*
G01X307418Y454035D02*
X307056Y454265D01*
X306850Y454571D01*
X306798Y454916D01*
X306850Y455223D01*
X307108Y455530D01*
X307418Y455721D01*
X307728Y455760D01*
X308090Y455683D01*
X308348Y455415D01*
X308451Y455146D01*
Y454801D01*
G01Y455146D02*
X308606Y455376D01*
X308865Y455568D01*
X309175Y455645D01*
X309485Y455568D01*
X309743Y455376D01*
X309898Y455031D01*
X309846Y454686D01*
X309640Y454341D01*
G01X309898Y457978D02*
X309795Y457671D01*
X309536Y457441D01*
X309226Y457288D01*
X308813Y457173D01*
X308348Y457135D01*
X307883Y457173D01*
X307470Y457288D01*
X307160Y457441D01*
X306901Y457671D01*
X306798Y457978D01*
X306901Y458285D01*
X307160Y458515D01*
X307470Y458668D01*
X307883Y458783D01*
X308348Y458821D01*
X308813Y458783D01*
X309226Y458668D01*
X309536Y458515D01*
X309795Y458285D01*
X309898Y457978D01*
G01X302424Y447911D02*
X305524D01*
Y448870D01*
X305369Y449176D01*
X305162Y449368D01*
X304749Y449445D01*
X304336Y449368D01*
X304077Y449138D01*
X303922Y448870D01*
Y447911D01*
G01Y448870D02*
X302424Y449445D01*
G01X303044Y450935D02*
X302682Y451165D01*
X302476Y451471D01*
X302424Y451816D01*
X302476Y452123D01*
X302734Y452430D01*
X303044Y452621D01*
X303354Y452660D01*
X303716Y452583D01*
X303974Y452315D01*
X304077Y452046D01*
Y451701D01*
G01Y452046D02*
X304232Y452276D01*
X304491Y452468D01*
X304801Y452545D01*
X305111Y452468D01*
X305369Y452276D01*
X305524Y451931D01*
X305472Y451586D01*
X305266Y451241D01*
G01X303044Y454035D02*
X302682Y454265D01*
X302476Y454571D01*
X302424Y454916D01*
X302476Y455223D01*
X302734Y455530D01*
X303044Y455721D01*
X303354Y455760D01*
X303716Y455683D01*
X303974Y455415D01*
X304077Y455146D01*
Y454801D01*
G01Y455146D02*
X304232Y455376D01*
X304491Y455568D01*
X304801Y455645D01*
X305111Y455568D01*
X305369Y455376D01*
X305524Y455031D01*
X305472Y454686D01*
X305266Y454341D01*
G01X302889Y457135D02*
X302631Y457365D01*
X302476Y457633D01*
X302424Y457978D01*
X302527Y458323D01*
X302734Y458591D01*
X303096Y458783D01*
X303509Y458821D01*
X303922Y458745D01*
X304181Y458553D01*
X304387Y458285D01*
X304439Y458016D01*
X304387Y457748D01*
X304181Y457403D01*
X305524Y457518D01*
Y458553D01*
G01X305515Y479410D02*
X305670Y479180D01*
X305773Y478912D01*
Y478605D01*
X305618Y478260D01*
X305360Y477992D01*
X305050Y477800D01*
X304533Y477647D01*
X304068Y477609D01*
X303603Y477685D01*
X303293Y477800D01*
X302983Y478030D01*
X302776Y478299D01*
X302673Y478567D01*
Y478835D01*
X302776Y479104D01*
X302931Y479334D01*
X303138Y479525D01*
G01X305256Y480939D02*
X305566Y481169D01*
X305721Y481437D01*
X305773Y481744D01*
X305670Y482127D01*
X305411Y482395D01*
X305101Y482472D01*
X304791Y482434D01*
X304533Y482280D01*
X304016Y481514D01*
X303655Y481169D01*
X303138Y480939D01*
X302673Y480862D01*
Y482472D01*
G01Y484690D02*
X303345Y484767D01*
X303913Y484882D01*
X304430Y485035D01*
X304998Y485227D01*
X305773Y485534D01*
Y484000D01*
G01X302673Y487790D02*
X303345Y487867D01*
X303913Y487982D01*
X304430Y488135D01*
X304998Y488327D01*
X305773Y488634D01*
Y487100D01*
G01X294435Y485626D02*
X299035D01*
G01X294435Y495826D02*
Y485626D01*
G01X299035D02*
Y495826D01*
G01X301609Y496253D02*
X307809D01*
G01X301609Y499453D02*
Y496253D01*
G01X307809Y499453D02*
X301609D01*
G01X304709Y496353D02*
Y499353D01*
G01X301609Y492253D02*
X307809D01*
G01X301609Y495453D02*
Y492253D01*
G01X307809Y495453D02*
X301609D01*
G01X304709Y492353D02*
Y495353D01*
G01X299035Y495826D02*
X294435D01*
G01X299035Y490726D02*
X294435D01*
G01X293699Y486792D02*
Y496992D01*
G01X304688Y516086D02*
X307788D01*
Y517045D01*
X307633Y517351D01*
X307426Y517543D01*
X307013Y517620D01*
X306600Y517543D01*
X306341Y517313D01*
X306186Y517045D01*
Y516086D01*
G01Y517045D02*
X304688Y517620D01*
G01Y519953D02*
X307788D01*
X307168Y519493D01*
G01X304688D02*
Y520413D01*
G01X307271Y522325D02*
X307581Y522555D01*
X307736Y522823D01*
X307788Y523130D01*
X307685Y523513D01*
X307426Y523781D01*
X307116Y523858D01*
X306806Y523820D01*
X306548Y523666D01*
X306031Y522900D01*
X305670Y522555D01*
X305153Y522325D01*
X304688Y522248D01*
Y523858D01*
G01X305308Y525310D02*
X304946Y525540D01*
X304740Y525846D01*
X304688Y526191D01*
X304740Y526498D01*
X304998Y526805D01*
X305308Y526996D01*
X305618Y527035D01*
X305980Y526958D01*
X306238Y526690D01*
X306341Y526421D01*
Y526076D01*
G01Y526421D02*
X306496Y526651D01*
X306755Y526843D01*
X307065Y526920D01*
X307375Y526843D01*
X307633Y526651D01*
X307788Y526306D01*
X307736Y525961D01*
X307530Y525616D01*
G01X307788Y529253D02*
X307685Y528946D01*
X307426Y528716D01*
X307116Y528563D01*
X306703Y528448D01*
X306238Y528410D01*
X305773Y528448D01*
X305360Y528563D01*
X305050Y528716D01*
X304791Y528946D01*
X304688Y529253D01*
X304791Y529560D01*
X305050Y529790D01*
X305360Y529943D01*
X305773Y530058D01*
X306238Y530096D01*
X306703Y530058D01*
X307116Y529943D01*
X307426Y529790D01*
X307685Y529560D01*
X307788Y529253D01*
G01X304108Y506293D02*
X307308D01*
G01X304108Y512493D02*
Y506293D01*
G01X307308Y512493D02*
X304108D01*
G01X295148Y516376D02*
X298248D01*
Y517335D01*
X298093Y517641D01*
X297886Y517833D01*
X297473Y517910D01*
X297060Y517833D01*
X296801Y517603D01*
X296646Y517335D01*
Y516376D01*
G01Y517335D02*
X295148Y517910D01*
G01X297731Y519515D02*
X298041Y519745D01*
X298196Y520013D01*
X298248Y520320D01*
X298145Y520703D01*
X297886Y520971D01*
X297576Y521048D01*
X297266Y521010D01*
X297008Y520856D01*
X296491Y520090D01*
X296130Y519745D01*
X295613Y519515D01*
X295148Y519438D01*
Y521048D01*
G01X295613Y522500D02*
X295355Y522730D01*
X295200Y522998D01*
X295148Y523343D01*
X295251Y523688D01*
X295458Y523956D01*
X295820Y524148D01*
X296233Y524186D01*
X296646Y524110D01*
X296905Y523918D01*
X297111Y523650D01*
X297163Y523381D01*
X297111Y523113D01*
X296905Y522768D01*
X298248Y522883D01*
Y523918D01*
G01X296440Y525715D02*
X296801Y525983D01*
X297008Y526213D01*
X297111Y526520D01*
X297008Y526788D01*
X296801Y526980D01*
X296491Y527133D01*
X296130Y527171D01*
X295820Y527133D01*
X295510Y526980D01*
X295251Y526750D01*
X295148Y526481D01*
X295251Y526175D01*
X295561Y525906D01*
X296026Y525753D01*
X296543Y525715D01*
X297215Y525791D01*
X297576Y525906D01*
X297938Y526098D01*
X298196Y526366D01*
X298248Y526635D01*
X298145Y526903D01*
X297886Y527095D01*
G01X298513Y512506D02*
X295313D01*
G01X298513Y506306D02*
Y512506D01*
G01X295313Y506306D02*
X298513D01*
G01X295313Y512506D02*
Y506306D01*
G01X299808Y516016D02*
X302908D01*
Y516975D01*
X302753Y517281D01*
X302546Y517473D01*
X302133Y517550D01*
X301720Y517473D01*
X301461Y517243D01*
X301306Y516975D01*
Y516016D01*
G01Y516975D02*
X299808Y517550D01*
G01X302391Y519155D02*
X302701Y519385D01*
X302856Y519653D01*
X302908Y519960D01*
X302805Y520343D01*
X302546Y520611D01*
X302236Y520688D01*
X301926Y520650D01*
X301668Y520496D01*
X301151Y519730D01*
X300790Y519385D01*
X300273Y519155D01*
X299808Y519078D01*
Y520688D01*
G01X300273Y522140D02*
X300015Y522370D01*
X299860Y522638D01*
X299808Y522983D01*
X299911Y523328D01*
X300118Y523596D01*
X300480Y523788D01*
X300893Y523826D01*
X301306Y523750D01*
X301565Y523558D01*
X301771Y523290D01*
X301823Y523021D01*
X301771Y522753D01*
X301565Y522408D01*
X302908Y522523D01*
Y523558D01*
G01X299808Y526083D02*
X299860Y526351D01*
X300015Y526658D01*
X300273Y526850D01*
X300635Y526926D01*
X300996Y526850D01*
X301306Y526620D01*
X301461Y526275D01*
Y525891D01*
X301565Y525661D01*
X301823Y525470D01*
X302185Y525393D01*
X302546Y525508D01*
X302805Y525776D01*
X302908Y526083D01*
X302805Y526390D01*
X302546Y526658D01*
X302185Y526773D01*
X301823Y526696D01*
X301565Y526505D01*
X301461Y526275D01*
Y525891D01*
X301306Y525546D01*
X300996Y525316D01*
X300635Y525240D01*
X300273Y525316D01*
X300015Y525508D01*
X299860Y525815D01*
X299808Y526083D01*
G01X299857Y506304D02*
X303057D01*
G01X299857Y512504D02*
Y506304D01*
G01X303057Y512504D02*
X299857D01*
G01X303057Y506304D02*
Y512504D01*
G01X297470Y578909D02*
X300570D01*
Y579868D01*
X300415Y580174D01*
X300208Y580366D01*
X299795Y580443D01*
X299382Y580366D01*
X299123Y580136D01*
X298968Y579868D01*
Y578909D01*
G01Y579868D02*
X297470Y580443D01*
G01X300053Y582048D02*
X300363Y582278D01*
X300518Y582546D01*
X300570Y582853D01*
X300467Y583236D01*
X300208Y583504D01*
X299898Y583581D01*
X299588Y583543D01*
X299330Y583389D01*
X298813Y582623D01*
X298452Y582278D01*
X297935Y582048D01*
X297470Y581971D01*
Y583581D01*
G01X297832Y585224D02*
X297573Y585493D01*
X297470Y585799D01*
X297573Y586106D01*
X297883Y586374D01*
X298348Y586566D01*
X298813Y586643D01*
X299382D01*
X299847Y586566D01*
X300260Y586374D01*
X300467Y586144D01*
X300570Y585876D01*
X300467Y585569D01*
X300260Y585339D01*
X299950Y585186D01*
X299537Y585109D01*
X299175Y585186D01*
X298813Y585378D01*
X298607Y585608D01*
X298555Y585876D01*
X298658Y586183D01*
X298917Y586413D01*
X299382Y586643D01*
G01X298090Y588133D02*
X297728Y588363D01*
X297522Y588669D01*
X297470Y589014D01*
X297522Y589321D01*
X297780Y589628D01*
X298090Y589819D01*
X298400Y589858D01*
X298762Y589781D01*
X299020Y589513D01*
X299123Y589244D01*
Y588899D01*
G01Y589244D02*
X299278Y589474D01*
X299537Y589666D01*
X299847Y589743D01*
X300157Y589666D01*
X300415Y589474D01*
X300570Y589129D01*
X300518Y588784D01*
X300312Y588439D01*
G01X300977Y591928D02*
Y599328D01*
G01X292277D02*
Y591928D01*
G01D02*
X309677D01*
G01X296509Y587653D02*
X293309D01*
G01X296509Y581453D02*
Y587653D01*
G01X293309Y581453D02*
X296509D01*
G01X293309Y587653D02*
Y581453D01*
G01X309677Y599328D02*
X292277D01*
G01X299050Y643808D02*
Y640608D01*
G01X305250Y643808D02*
X299050D01*
G01X305250Y640608D02*
Y643808D01*
G01X299050Y640608D02*
X305250D01*
G01X294020Y653917D02*
X290820D01*
G01X294020Y647717D02*
Y653917D01*
G01X290820Y647717D02*
X294020D01*
G01X290820Y653917D02*
Y647717D01*
G01X294853Y647674D02*
X298053D01*
G01X294853Y653874D02*
Y647674D01*
G01X298053Y653874D02*
X294853D01*
G01X298053Y647674D02*
Y653874D01*
G01X305250Y644592D02*
Y647792D01*
G01X299050Y644592D02*
X305250D01*
G01X299050Y647792D02*
Y644592D01*
G01X305250Y647792D02*
X299050D01*
G01X298038Y705523D02*
X301238D01*
G01X298038Y711723D02*
Y705523D01*
G01X301238D02*
Y711723D01*
G01X305138Y705523D02*
Y711723D01*
X301938D01*
Y705523D01*
X305138D01*
G01X301238Y711723D02*
X298038D01*
G01X290230Y725837D02*
Y732037D01*
G01X297840Y737556D02*
X301040D01*
G01X297840Y743756D02*
Y737556D01*
G01X301040D02*
Y743756D01*
G01X293040Y737556D02*
Y743756D01*
G01X291240Y727997D02*
X294440D01*
G01X291240Y734197D02*
Y727997D01*
G01X294440Y734197D02*
X291240D01*
G01X294440Y727997D02*
Y734197D01*
G01X291340Y731097D02*
X294340D01*
G01X301840Y737556D02*
X305040D01*
G01X301840Y743756D02*
Y737556D01*
G01X305040D02*
Y743756D01*
G01X303050Y730870D02*
X299850D01*
G01X303050Y724670D02*
Y730870D01*
G01X299850Y724670D02*
X303050D01*
G01X299850Y730870D02*
Y724670D01*
G01X297040Y737556D02*
Y743756D01*
G01X293840Y737556D02*
X297040D01*
G01X293840Y743756D02*
Y737556D01*
G01X304040Y732467D02*
Y726267D01*
X307240D01*
Y732467D01*
X304040D01*
G01X301040Y743756D02*
X297840D01*
G01X297940Y740656D02*
X300940D01*
G01X297567Y747551D02*
X297722Y747321D01*
X297825Y747053D01*
Y746746D01*
X297670Y746401D01*
X297412Y746133D01*
X297102Y745941D01*
X296585Y745788D01*
X296120Y745750D01*
X295655Y745826D01*
X295345Y745941D01*
X295035Y746171D01*
X294828Y746440D01*
X294725Y746708D01*
Y746976D01*
X294828Y747245D01*
X294983Y747475D01*
X295190Y747666D01*
G01X296017Y749080D02*
X296378Y749348D01*
X296585Y749578D01*
X296688Y749885D01*
X296585Y750153D01*
X296378Y750345D01*
X296068Y750498D01*
X295707Y750536D01*
X295397Y750498D01*
X295087Y750345D01*
X294828Y750115D01*
X294725Y749846D01*
X294828Y749540D01*
X295138Y749271D01*
X295603Y749118D01*
X296120Y749080D01*
X296792Y749156D01*
X297153Y749271D01*
X297515Y749463D01*
X297773Y749731D01*
X297825Y750000D01*
X297722Y750268D01*
X297463Y750460D01*
G01X294725Y752831D02*
X295397Y752908D01*
X295965Y753023D01*
X296482Y753176D01*
X297050Y753368D01*
X297825Y753675D01*
Y752141D01*
G01X294725Y756008D02*
X297825D01*
X297205Y755548D01*
G01X294725D02*
Y756468D01*
G01X305040Y743756D02*
X301840D01*
G01X301940Y740656D02*
X304940D01*
G01X300530Y744498D02*
X303630D01*
Y745457D01*
X303475Y745763D01*
X303268Y745955D01*
X302855Y746032D01*
X302442Y745955D01*
X302183Y745725D01*
X302028Y745457D01*
Y744498D01*
G01Y745457D02*
X300530Y746032D01*
G01Y748365D02*
X300582Y748633D01*
X300737Y748940D01*
X300995Y749132D01*
X301357Y749208D01*
X301718Y749132D01*
X302028Y748902D01*
X302183Y748557D01*
Y748173D01*
X302287Y747943D01*
X302545Y747752D01*
X302907Y747675D01*
X303268Y747790D01*
X303527Y748058D01*
X303630Y748365D01*
X303527Y748672D01*
X303268Y748940D01*
X302907Y749055D01*
X302545Y748978D01*
X302287Y748787D01*
X302183Y748557D01*
Y748173D01*
X302028Y747828D01*
X301718Y747598D01*
X301357Y747522D01*
X300995Y747598D01*
X300737Y747790D01*
X300582Y748097D01*
X300530Y748365D01*
G01X300892Y750813D02*
X300633Y751082D01*
X300530Y751388D01*
X300633Y751695D01*
X300943Y751963D01*
X301408Y752155D01*
X301873Y752232D01*
X302442D01*
X302907Y752155D01*
X303320Y751963D01*
X303527Y751733D01*
X303630Y751465D01*
X303527Y751158D01*
X303320Y750928D01*
X303010Y750775D01*
X302597Y750698D01*
X302235Y750775D01*
X301873Y750967D01*
X301667Y751197D01*
X301615Y751465D01*
X301718Y751772D01*
X301977Y752002D01*
X302442Y752232D01*
G01X303113Y753837D02*
X303423Y754067D01*
X303578Y754335D01*
X303630Y754642D01*
X303527Y755025D01*
X303268Y755293D01*
X302958Y755370D01*
X302648Y755332D01*
X302390Y755178D01*
X301873Y754412D01*
X301512Y754067D01*
X300995Y753837D01*
X300530Y753760D01*
Y755370D01*
G01X297040Y743756D02*
X293840D01*
G01X304546Y744579D02*
X307646D01*
Y745538D01*
X307491Y745844D01*
X307284Y746036D01*
X306871Y746113D01*
X306458Y746036D01*
X306199Y745806D01*
X306044Y745538D01*
Y744579D01*
G01Y745538D02*
X304546Y746113D01*
G01Y748446D02*
X304598Y748714D01*
X304753Y749021D01*
X305011Y749213D01*
X305373Y749289D01*
X305734Y749213D01*
X306044Y748983D01*
X306199Y748638D01*
Y748254D01*
X306303Y748024D01*
X306561Y747833D01*
X306923Y747756D01*
X307284Y747871D01*
X307543Y748139D01*
X307646Y748446D01*
X307543Y748753D01*
X307284Y749021D01*
X306923Y749136D01*
X306561Y749059D01*
X306303Y748868D01*
X306199Y748638D01*
Y748254D01*
X306044Y747909D01*
X305734Y747679D01*
X305373Y747603D01*
X305011Y747679D01*
X304753Y747871D01*
X304598Y748178D01*
X304546Y748446D01*
G01Y751546D02*
X304598Y751814D01*
X304753Y752121D01*
X305011Y752313D01*
X305373Y752389D01*
X305734Y752313D01*
X306044Y752083D01*
X306199Y751738D01*
Y751354D01*
X306303Y751124D01*
X306561Y750933D01*
X306923Y750856D01*
X307284Y750971D01*
X307543Y751239D01*
X307646Y751546D01*
X307543Y751853D01*
X307284Y752121D01*
X306923Y752236D01*
X306561Y752159D01*
X306303Y751968D01*
X306199Y751738D01*
Y751354D01*
X306044Y751009D01*
X305734Y750779D01*
X305373Y750703D01*
X305011Y750779D01*
X304753Y750971D01*
X304598Y751278D01*
X304546Y751546D01*
G01X304908Y753994D02*
X304649Y754263D01*
X304546Y754569D01*
X304649Y754876D01*
X304959Y755144D01*
X305424Y755336D01*
X305889Y755413D01*
X306458D01*
X306923Y755336D01*
X307336Y755144D01*
X307543Y754914D01*
X307646Y754646D01*
X307543Y754339D01*
X307336Y754109D01*
X307026Y753956D01*
X306613Y753879D01*
X306251Y753956D01*
X305889Y754148D01*
X305683Y754378D01*
X305631Y754646D01*
X305734Y754953D01*
X305993Y755183D01*
X306458Y755413D01*
G01X299437Y759650D02*
X299592Y759420D01*
X299695Y759152D01*
Y758845D01*
X299540Y758500D01*
X299282Y758232D01*
X298972Y758040D01*
X298455Y757887D01*
X297990Y757849D01*
X297525Y757925D01*
X297215Y758040D01*
X296905Y758270D01*
X296698Y758539D01*
X296595Y758807D01*
Y759075D01*
X296698Y759344D01*
X296853Y759574D01*
X297060Y759765D01*
G01X297887Y761179D02*
X298248Y761447D01*
X298455Y761677D01*
X298558Y761984D01*
X298455Y762252D01*
X298248Y762444D01*
X297938Y762597D01*
X297577Y762635D01*
X297267Y762597D01*
X296957Y762444D01*
X296698Y762214D01*
X296595Y761945D01*
X296698Y761639D01*
X297008Y761370D01*
X297473Y761217D01*
X297990Y761179D01*
X298662Y761255D01*
X299023Y761370D01*
X299385Y761562D01*
X299643Y761830D01*
X299695Y762099D01*
X299592Y762367D01*
X299333Y762559D01*
G01X297060Y764164D02*
X296802Y764394D01*
X296647Y764662D01*
X296595Y765007D01*
X296698Y765352D01*
X296905Y765620D01*
X297267Y765812D01*
X297680Y765850D01*
X298093Y765774D01*
X298352Y765582D01*
X298558Y765314D01*
X298610Y765045D01*
X298558Y764777D01*
X298352Y764432D01*
X299695Y764547D01*
Y765582D01*
G01X297060Y767264D02*
X296802Y767494D01*
X296647Y767762D01*
X296595Y768107D01*
X296698Y768452D01*
X296905Y768720D01*
X297267Y768912D01*
X297680Y768950D01*
X298093Y768874D01*
X298352Y768682D01*
X298558Y768414D01*
X298610Y768145D01*
X298558Y767877D01*
X298352Y767532D01*
X299695Y767647D01*
Y768682D01*
G01X307949Y758995D02*
X308104Y758765D01*
X308207Y758497D01*
Y758190D01*
X308052Y757845D01*
X307794Y757577D01*
X307484Y757385D01*
X306967Y757232D01*
X306502Y757194D01*
X306037Y757270D01*
X305727Y757385D01*
X305417Y757615D01*
X305210Y757884D01*
X305107Y758152D01*
Y758420D01*
X305210Y758689D01*
X305365Y758919D01*
X305572Y759110D01*
G01X306399Y760524D02*
X306760Y760792D01*
X306967Y761022D01*
X307070Y761329D01*
X306967Y761597D01*
X306760Y761789D01*
X306450Y761942D01*
X306089Y761980D01*
X305779Y761942D01*
X305469Y761789D01*
X305210Y761559D01*
X305107Y761290D01*
X305210Y760984D01*
X305520Y760715D01*
X305985Y760562D01*
X306502Y760524D01*
X307174Y760600D01*
X307535Y760715D01*
X307897Y760907D01*
X308155Y761175D01*
X308207Y761444D01*
X308104Y761712D01*
X307845Y761904D01*
G01X305107Y764812D02*
X308207D01*
X305985Y763394D01*
Y765310D01*
G01X305469Y766800D02*
X305210Y767069D01*
X305107Y767375D01*
X305210Y767682D01*
X305520Y767950D01*
X305985Y768142D01*
X306450Y768219D01*
X307019D01*
X307484Y768142D01*
X307897Y767950D01*
X308104Y767720D01*
X308207Y767452D01*
X308104Y767145D01*
X307897Y766915D01*
X307587Y766762D01*
X307174Y766685D01*
X306812Y766762D01*
X306450Y766954D01*
X306244Y767184D01*
X306192Y767452D01*
X306295Y767759D01*
X306554Y767989D01*
X307019Y768219D01*
G01X304017Y758995D02*
X304172Y758765D01*
X304275Y758497D01*
Y758190D01*
X304120Y757845D01*
X303862Y757577D01*
X303552Y757385D01*
X303035Y757232D01*
X302570Y757194D01*
X302105Y757270D01*
X301795Y757385D01*
X301485Y757615D01*
X301278Y757884D01*
X301175Y758152D01*
Y758420D01*
X301278Y758689D01*
X301433Y758919D01*
X301640Y759110D01*
G01X302467Y760524D02*
X302828Y760792D01*
X303035Y761022D01*
X303138Y761329D01*
X303035Y761597D01*
X302828Y761789D01*
X302518Y761942D01*
X302157Y761980D01*
X301847Y761942D01*
X301537Y761789D01*
X301278Y761559D01*
X301175Y761290D01*
X301278Y760984D01*
X301588Y760715D01*
X302053Y760562D01*
X302570Y760524D01*
X303242Y760600D01*
X303603Y760715D01*
X303965Y760907D01*
X304223Y761175D01*
X304275Y761444D01*
X304172Y761712D01*
X303913Y761904D01*
G01X301640Y763509D02*
X301382Y763739D01*
X301227Y764007D01*
X301175Y764352D01*
X301278Y764697D01*
X301485Y764965D01*
X301847Y765157D01*
X302260Y765195D01*
X302673Y765119D01*
X302932Y764927D01*
X303138Y764659D01*
X303190Y764390D01*
X303138Y764122D01*
X302932Y763777D01*
X304275Y763892D01*
Y764927D01*
G01X303758Y766724D02*
X304068Y766954D01*
X304223Y767222D01*
X304275Y767529D01*
X304172Y767912D01*
X303913Y768180D01*
X303603Y768257D01*
X303293Y768219D01*
X303035Y768065D01*
X302518Y767299D01*
X302157Y766954D01*
X301640Y766724D01*
X301175Y766647D01*
Y768257D01*
G01X292571Y758040D02*
X295671D01*
Y758999D01*
X295516Y759305D01*
X295309Y759497D01*
X294896Y759574D01*
X294483Y759497D01*
X294224Y759267D01*
X294069Y758999D01*
Y758040D01*
G01Y758999D02*
X292571Y759574D01*
G01X292933Y761255D02*
X292674Y761524D01*
X292571Y761830D01*
X292674Y762137D01*
X292984Y762405D01*
X293449Y762597D01*
X293914Y762674D01*
X294483D01*
X294948Y762597D01*
X295361Y762405D01*
X295568Y762175D01*
X295671Y761907D01*
X295568Y761600D01*
X295361Y761370D01*
X295051Y761217D01*
X294638Y761140D01*
X294276Y761217D01*
X293914Y761409D01*
X293708Y761639D01*
X293656Y761907D01*
X293759Y762214D01*
X294018Y762444D01*
X294483Y762674D01*
G01X295671Y765007D02*
X295568Y764700D01*
X295309Y764470D01*
X294999Y764317D01*
X294586Y764202D01*
X294121Y764164D01*
X293656Y764202D01*
X293243Y764317D01*
X292933Y764470D01*
X292674Y764700D01*
X292571Y765007D01*
X292674Y765314D01*
X292933Y765544D01*
X293243Y765697D01*
X293656Y765812D01*
X294121Y765850D01*
X294586Y765812D01*
X294999Y765697D01*
X295309Y765544D01*
X295568Y765314D01*
X295671Y765007D01*
G01X292571Y768107D02*
X292623Y768375D01*
X292778Y768682D01*
X293036Y768874D01*
X293398Y768950D01*
X293759Y768874D01*
X294069Y768644D01*
X294224Y768299D01*
Y767915D01*
X294328Y767685D01*
X294586Y767494D01*
X294948Y767417D01*
X295309Y767532D01*
X295568Y767800D01*
X295671Y768107D01*
X295568Y768414D01*
X295309Y768682D01*
X294948Y768797D01*
X294586Y768720D01*
X294328Y768529D01*
X294224Y768299D01*
Y767915D01*
X294069Y767570D01*
X293759Y767340D01*
X293398Y767264D01*
X293036Y767340D01*
X292778Y767532D01*
X292623Y767839D01*
X292571Y768107D01*
G01X317420Y62191D02*
X317575Y61961D01*
X317678Y61693D01*
Y61386D01*
X317523Y61041D01*
X317265Y60773D01*
X316955Y60581D01*
X316438Y60428D01*
X315973Y60390D01*
X315508Y60466D01*
X315198Y60581D01*
X314888Y60811D01*
X314681Y61080D01*
X314578Y61348D01*
Y61616D01*
X314681Y61885D01*
X314836Y62115D01*
X315043Y62306D01*
G01X314578Y64448D02*
X317678D01*
X317058Y63988D01*
G01X314578D02*
Y64908D01*
G01X315870Y66820D02*
X316231Y67088D01*
X316438Y67318D01*
X316541Y67625D01*
X316438Y67893D01*
X316231Y68085D01*
X315921Y68238D01*
X315560Y68276D01*
X315250Y68238D01*
X314940Y68085D01*
X314681Y67855D01*
X314578Y67586D01*
X314681Y67280D01*
X314991Y67011D01*
X315456Y66858D01*
X315973Y66820D01*
X316645Y66896D01*
X317006Y67011D01*
X317368Y67203D01*
X317626Y67471D01*
X317678Y67740D01*
X317575Y68008D01*
X317316Y68200D01*
G01X315043Y69805D02*
X314785Y70035D01*
X314630Y70303D01*
X314578Y70648D01*
X314681Y70993D01*
X314888Y71261D01*
X315250Y71453D01*
X315663Y71491D01*
X316076Y71415D01*
X316335Y71223D01*
X316541Y70955D01*
X316593Y70686D01*
X316541Y70418D01*
X316335Y70073D01*
X317678Y70188D01*
Y71223D01*
G01X313341Y62191D02*
X313496Y61961D01*
X313599Y61693D01*
Y61386D01*
X313444Y61041D01*
X313186Y60773D01*
X312876Y60581D01*
X312359Y60428D01*
X311894Y60390D01*
X311429Y60466D01*
X311119Y60581D01*
X310809Y60811D01*
X310602Y61080D01*
X310499Y61348D01*
Y61616D01*
X310602Y61885D01*
X310757Y62115D01*
X310964Y62306D01*
G01X310499Y64448D02*
X313599D01*
X312979Y63988D01*
G01X310499D02*
Y64908D01*
G01X311791Y66820D02*
X312152Y67088D01*
X312359Y67318D01*
X312462Y67625D01*
X312359Y67893D01*
X312152Y68085D01*
X311842Y68238D01*
X311481Y68276D01*
X311171Y68238D01*
X310861Y68085D01*
X310602Y67855D01*
X310499Y67586D01*
X310602Y67280D01*
X310912Y67011D01*
X311377Y66858D01*
X311894Y66820D01*
X312566Y66896D01*
X312927Y67011D01*
X313289Y67203D01*
X313547Y67471D01*
X313599Y67740D01*
X313496Y68008D01*
X313237Y68200D01*
G01X310499Y70571D02*
X311171Y70648D01*
X311739Y70763D01*
X312256Y70916D01*
X312824Y71108D01*
X313599Y71415D01*
Y69881D01*
G01X321742Y62077D02*
X321897Y61847D01*
X322000Y61579D01*
Y61272D01*
X321845Y60927D01*
X321587Y60659D01*
X321277Y60467D01*
X320760Y60314D01*
X320295Y60276D01*
X319830Y60352D01*
X319520Y60467D01*
X319210Y60697D01*
X319003Y60966D01*
X318900Y61234D01*
Y61502D01*
X319003Y61771D01*
X319158Y62001D01*
X319365Y62192D01*
G01X318900Y64334D02*
X322000D01*
X321380Y63874D01*
G01X318900D02*
Y64794D01*
G01X320192Y66706D02*
X320553Y66974D01*
X320760Y67204D01*
X320863Y67511D01*
X320760Y67779D01*
X320553Y67971D01*
X320243Y68124D01*
X319882Y68162D01*
X319572Y68124D01*
X319262Y67971D01*
X319003Y67741D01*
X318900Y67472D01*
X319003Y67166D01*
X319313Y66897D01*
X319778Y66744D01*
X320295Y66706D01*
X320967Y66782D01*
X321328Y66897D01*
X321690Y67089D01*
X321948Y67357D01*
X322000Y67626D01*
X321897Y67894D01*
X321638Y68086D01*
G01X319520Y69691D02*
X319158Y69921D01*
X318952Y70227D01*
X318900Y70572D01*
X318952Y70879D01*
X319210Y71186D01*
X319520Y71377D01*
X319830Y71416D01*
X320192Y71339D01*
X320450Y71071D01*
X320553Y70802D01*
Y70457D01*
G01Y70802D02*
X320708Y71032D01*
X320967Y71224D01*
X321277Y71301D01*
X321587Y71224D01*
X321845Y71032D01*
X322000Y70687D01*
X321948Y70342D01*
X321742Y69997D01*
G01X309339Y86340D02*
Y80140D01*
G01X312539Y86340D02*
X309339D01*
G01Y80140D02*
X312539D01*
G01D02*
Y86340D01*
G01X312439Y83240D02*
X309439D01*
G01X320605Y86160D02*
X317405D01*
G01D02*
Y79960D01*
G01D02*
X320605D01*
G01D02*
Y86160D01*
G01X320505Y83060D02*
X317505D01*
G01X316526Y86239D02*
X313326D01*
G01D02*
Y80039D01*
G01D02*
X316526D01*
G01D02*
Y86239D01*
G01X316426Y83139D02*
X313426D01*
G01X324605Y86160D02*
X321405D01*
G01X324505Y83060D02*
X321505D01*
G01X321405Y86160D02*
Y79960D01*
G01D02*
X324605D01*
G01X308521Y77339D02*
Y87539D01*
G01X310878Y116406D02*
X311033Y116176D01*
X311136Y115908D01*
Y115601D01*
X310981Y115256D01*
X310723Y114988D01*
X310413Y114796D01*
X309896Y114643D01*
X309431Y114605D01*
X308966Y114681D01*
X308656Y114796D01*
X308346Y115026D01*
X308139Y115295D01*
X308036Y115563D01*
Y115831D01*
X308139Y116100D01*
X308294Y116330D01*
X308501Y116521D01*
G01X308036Y118663D02*
X311136D01*
X310516Y118203D01*
G01X308036D02*
Y119123D01*
G01X308501Y120920D02*
X308243Y121150D01*
X308088Y121418D01*
X308036Y121763D01*
X308139Y122108D01*
X308346Y122376D01*
X308708Y122568D01*
X309121Y122606D01*
X309534Y122530D01*
X309793Y122338D01*
X309999Y122070D01*
X310051Y121801D01*
X309999Y121533D01*
X309793Y121188D01*
X311136Y121303D01*
Y122338D01*
G01X308036Y124786D02*
X308708Y124863D01*
X309276Y124978D01*
X309793Y125131D01*
X310361Y125323D01*
X311136Y125630D01*
Y124096D01*
G01X315389Y120334D02*
X312189D01*
G01X312289Y117234D02*
X315289D01*
G01X315389Y114134D02*
Y120334D01*
G01X312189D02*
Y114134D01*
G01D02*
X315389D01*
G01X330481Y113578D02*
X330711Y113733D01*
X330979Y113836D01*
X331286D01*
X331631Y113681D01*
X331899Y113423D01*
X332091Y113113D01*
X332244Y112596D01*
X332282Y112131D01*
X332206Y111666D01*
X332091Y111356D01*
X331861Y111046D01*
X331592Y110839D01*
X331324Y110736D01*
X331056D01*
X330787Y110839D01*
X330557Y110994D01*
X330366Y111201D01*
G01X328224Y110736D02*
Y113836D01*
X328684Y113216D01*
G01Y110736D02*
X327764D01*
G01X325201D02*
X325124Y111408D01*
X325009Y111976D01*
X324856Y112493D01*
X324664Y113061D01*
X324357Y113836D01*
X325891D01*
G01X321564Y110736D02*
Y113836D01*
X322982Y111614D01*
X321066D01*
G01X310030Y314316D02*
Y311775D01*
G01Y308700D02*
Y311775D01*
G01X308251Y312143D02*
Y327143D01*
G01X329567Y300292D02*
Y303392D01*
X328608D01*
X328302Y303237D01*
X328110Y303030D01*
X328033Y302617D01*
X328110Y302204D01*
X328340Y301945D01*
X328608Y301790D01*
X329567D01*
G01X328608D02*
X328033Y300292D01*
G01X326352Y300654D02*
X326083Y300395D01*
X325777Y300292D01*
X325470Y300395D01*
X325202Y300705D01*
X325010Y301170D01*
X324933Y301635D01*
Y302204D01*
X325010Y302669D01*
X325202Y303082D01*
X325432Y303289D01*
X325700Y303392D01*
X326007Y303289D01*
X326237Y303082D01*
X326390Y302772D01*
X326467Y302359D01*
X326390Y301997D01*
X326198Y301635D01*
X325968Y301429D01*
X325700Y301377D01*
X325393Y301480D01*
X325163Y301739D01*
X324933Y302204D01*
G01X322600Y300292D02*
Y303392D01*
X323060Y302772D01*
G01Y300292D02*
X322140D01*
G01X319093Y301198D02*
Y304398D01*
G01D02*
X312893D01*
G01D02*
Y301198D01*
G01D02*
X319093D01*
G01X331617Y304328D02*
Y307428D01*
X330658D01*
X330352Y307273D01*
X330160Y307066D01*
X330083Y306653D01*
X330160Y306240D01*
X330390Y305981D01*
X330658Y305826D01*
X331617D01*
G01X330658D02*
X330083Y304328D01*
G01X327750D02*
Y307428D01*
X328210Y306808D01*
G01Y304328D02*
X327290D01*
G01X324650D02*
Y307428D01*
X325110Y306808D01*
G01Y304328D02*
X324190D01*
G01X321550D02*
X321282Y304380D01*
X320975Y304535D01*
X320783Y304793D01*
X320707Y305155D01*
X320783Y305516D01*
X321013Y305826D01*
X321358Y305981D01*
X321742D01*
X321972Y306085D01*
X322163Y306343D01*
X322240Y306705D01*
X322125Y307066D01*
X321857Y307325D01*
X321550Y307428D01*
X321243Y307325D01*
X320975Y307066D01*
X320860Y306705D01*
X320937Y306343D01*
X321128Y306085D01*
X321358Y305981D01*
X321742D01*
X322087Y305826D01*
X322317Y305516D01*
X322393Y305155D01*
X322317Y304793D01*
X322125Y304535D01*
X321818Y304380D01*
X321550Y304328D01*
G01X319132Y305276D02*
Y308476D01*
G01D02*
X312932D01*
G01D02*
Y305276D01*
G01D02*
X319132D01*
G01X312010Y328703D02*
Y332271D01*
G01Y328703D02*
Y328616D01*
G01X310030Y323150D02*
Y320214D01*
G01Y314316D02*
Y315575D01*
G01Y320214D02*
Y315575D01*
G01Y324110D02*
Y323150D01*
G01X312010Y324110D02*
X310030D01*
G01X311139Y328806D02*
Y332006D01*
G01X320750Y327986D02*
X314550D01*
G01D02*
Y324786D01*
G01D02*
X320750D01*
G01D02*
Y327986D01*
G01X331923Y314688D02*
Y317788D01*
X330964D01*
X330658Y317633D01*
X330466Y317426D01*
X330389Y317013D01*
X330466Y316600D01*
X330696Y316341D01*
X330964Y316186D01*
X331923D01*
G01X330964D02*
X330389Y314688D01*
G01X328056D02*
Y317788D01*
X328516Y317168D01*
G01Y314688D02*
X327596D01*
G01X325684Y317271D02*
X325454Y317581D01*
X325186Y317736D01*
X324879Y317788D01*
X324496Y317685D01*
X324228Y317426D01*
X324151Y317116D01*
X324189Y316806D01*
X324343Y316548D01*
X325109Y316031D01*
X325454Y315670D01*
X325684Y315153D01*
X325761Y314688D01*
X324151D01*
G01X321933D02*
X321856Y315360D01*
X321741Y315928D01*
X321588Y316445D01*
X321396Y317013D01*
X321089Y317788D01*
X322623D01*
G01X311590Y343878D02*
Y337678D01*
G01X314690Y340778D02*
X311690D01*
G01X311590Y337678D02*
X314790D01*
G01D02*
Y343878D01*
G01D02*
X311590D01*
G01X309645Y332780D02*
Y335980D01*
G01X314582Y347117D02*
X314737Y346887D01*
X314840Y346619D01*
Y346312D01*
X314685Y345967D01*
X314427Y345699D01*
X314117Y345507D01*
X313600Y345354D01*
X313135Y345316D01*
X312670Y345392D01*
X312360Y345507D01*
X312050Y345737D01*
X311843Y346006D01*
X311740Y346274D01*
Y346542D01*
X311843Y346811D01*
X311998Y347041D01*
X312205Y347232D01*
G01X312360Y348531D02*
X311998Y348761D01*
X311792Y349067D01*
X311740Y349412D01*
X311792Y349719D01*
X312050Y350026D01*
X312360Y350217D01*
X312670Y350256D01*
X313032Y350179D01*
X313290Y349911D01*
X313393Y349642D01*
Y349297D01*
G01Y349642D02*
X313548Y349872D01*
X313807Y350064D01*
X314117Y350141D01*
X314427Y350064D01*
X314685Y349872D01*
X314840Y349527D01*
X314788Y349182D01*
X314582Y348837D01*
G01X312360Y351631D02*
X311998Y351861D01*
X311792Y352167D01*
X311740Y352512D01*
X311792Y352819D01*
X312050Y353126D01*
X312360Y353317D01*
X312670Y353356D01*
X313032Y353279D01*
X313290Y353011D01*
X313393Y352742D01*
Y352397D01*
G01Y352742D02*
X313548Y352972D01*
X313807Y353164D01*
X314117Y353241D01*
X314427Y353164D01*
X314685Y352972D01*
X314840Y352627D01*
X314788Y352282D01*
X314582Y351937D01*
G01X329547Y377420D02*
Y380520D01*
X328588D01*
X328282Y380365D01*
X328090Y380158D01*
X328013Y379745D01*
X328090Y379332D01*
X328320Y379073D01*
X328588Y378918D01*
X329547D01*
G01X328588D02*
X328013Y377420D01*
G01X325680D02*
Y380520D01*
X326140Y379900D01*
G01Y377420D02*
X325220D01*
G01X323423Y378040D02*
X323193Y377678D01*
X322887Y377472D01*
X322542Y377420D01*
X322235Y377472D01*
X321928Y377730D01*
X321737Y378040D01*
X321698Y378350D01*
X321775Y378712D01*
X322043Y378970D01*
X322312Y379073D01*
X322657D01*
G01X322312D02*
X322082Y379228D01*
X321890Y379487D01*
X321813Y379797D01*
X321890Y380107D01*
X322082Y380365D01*
X322427Y380520D01*
X322772Y380468D01*
X323117Y380262D01*
G01X320132Y377782D02*
X319863Y377523D01*
X319557Y377420D01*
X319250Y377523D01*
X318982Y377833D01*
X318790Y378298D01*
X318713Y378763D01*
Y379332D01*
X318790Y379797D01*
X318982Y380210D01*
X319212Y380417D01*
X319480Y380520D01*
X319787Y380417D01*
X320017Y380210D01*
X320170Y379900D01*
X320247Y379487D01*
X320170Y379125D01*
X319978Y378763D01*
X319748Y378557D01*
X319480Y378505D01*
X319173Y378608D01*
X318943Y378867D01*
X318713Y379332D01*
G01X317856Y380571D02*
X311656D01*
G01D02*
Y377371D01*
G01D02*
X317856D01*
G01D02*
Y380571D01*
G01X311417Y447911D02*
X314517D01*
Y448870D01*
X314362Y449176D01*
X314155Y449368D01*
X313742Y449445D01*
X313329Y449368D01*
X313070Y449138D01*
X312915Y448870D01*
Y447911D01*
G01Y448870D02*
X311417Y449445D01*
G01X314000Y451050D02*
X314310Y451280D01*
X314465Y451548D01*
X314517Y451855D01*
X314414Y452238D01*
X314155Y452506D01*
X313845Y452583D01*
X313535Y452545D01*
X313277Y452391D01*
X312760Y451625D01*
X312399Y451280D01*
X311882Y451050D01*
X311417Y450973D01*
Y452583D01*
G01X311882Y454035D02*
X311624Y454265D01*
X311469Y454533D01*
X311417Y454878D01*
X311520Y455223D01*
X311727Y455491D01*
X312089Y455683D01*
X312502Y455721D01*
X312915Y455645D01*
X313174Y455453D01*
X313380Y455185D01*
X313432Y454916D01*
X313380Y454648D01*
X313174Y454303D01*
X314517Y454418D01*
Y455453D01*
G01X312037Y457135D02*
X311675Y457365D01*
X311469Y457671D01*
X311417Y458016D01*
X311469Y458323D01*
X311727Y458630D01*
X312037Y458821D01*
X312347Y458860D01*
X312709Y458783D01*
X312967Y458515D01*
X313070Y458246D01*
Y457901D01*
G01Y458246D02*
X313225Y458476D01*
X313484Y458668D01*
X313794Y458745D01*
X314104Y458668D01*
X314362Y458476D01*
X314517Y458131D01*
X314465Y457786D01*
X314259Y457441D01*
G01X320075Y447859D02*
X323175D01*
Y448818D01*
X323020Y449124D01*
X322813Y449316D01*
X322400Y449393D01*
X321987Y449316D01*
X321728Y449086D01*
X321573Y448818D01*
Y447859D01*
G01Y448818D02*
X320075Y449393D01*
G01X322658Y450998D02*
X322968Y451228D01*
X323123Y451496D01*
X323175Y451803D01*
X323072Y452186D01*
X322813Y452454D01*
X322503Y452531D01*
X322193Y452493D01*
X321935Y452339D01*
X321418Y451573D01*
X321057Y451228D01*
X320540Y450998D01*
X320075Y450921D01*
Y452531D01*
G01Y454749D02*
X320747Y454826D01*
X321315Y454941D01*
X321832Y455094D01*
X322400Y455286D01*
X323175Y455593D01*
Y454059D01*
G01X322658Y457198D02*
X322968Y457428D01*
X323123Y457696D01*
X323175Y458003D01*
X323072Y458386D01*
X322813Y458654D01*
X322503Y458731D01*
X322193Y458693D01*
X321935Y458539D01*
X321418Y457773D01*
X321057Y457428D01*
X320540Y457198D01*
X320075Y457121D01*
Y458731D01*
G01X315648Y447911D02*
X318748D01*
Y448870D01*
X318593Y449176D01*
X318386Y449368D01*
X317973Y449445D01*
X317560Y449368D01*
X317301Y449138D01*
X317146Y448870D01*
Y447911D01*
G01Y448870D02*
X315648Y449445D01*
G01X318231Y451050D02*
X318541Y451280D01*
X318696Y451548D01*
X318748Y451855D01*
X318645Y452238D01*
X318386Y452506D01*
X318076Y452583D01*
X317766Y452545D01*
X317508Y452391D01*
X316991Y451625D01*
X316630Y451280D01*
X316113Y451050D01*
X315648Y450973D01*
Y452583D01*
G01X316113Y454035D02*
X315855Y454265D01*
X315700Y454533D01*
X315648Y454878D01*
X315751Y455223D01*
X315958Y455491D01*
X316320Y455683D01*
X316733Y455721D01*
X317146Y455645D01*
X317405Y455453D01*
X317611Y455185D01*
X317663Y454916D01*
X317611Y454648D01*
X317405Y454303D01*
X318748Y454418D01*
Y455453D01*
G01X315648Y458438D02*
X318748D01*
X316526Y457020D01*
Y458936D01*
G01X309752Y479410D02*
X309907Y479180D01*
X310010Y478912D01*
Y478605D01*
X309855Y478260D01*
X309597Y477992D01*
X309287Y477800D01*
X308770Y477647D01*
X308305Y477609D01*
X307840Y477685D01*
X307530Y477800D01*
X307220Y478030D01*
X307013Y478299D01*
X306910Y478567D01*
Y478835D01*
X307013Y479104D01*
X307168Y479334D01*
X307375Y479525D01*
G01X309493Y480939D02*
X309803Y481169D01*
X309958Y481437D01*
X310010Y481744D01*
X309907Y482127D01*
X309648Y482395D01*
X309338Y482472D01*
X309028Y482434D01*
X308770Y482280D01*
X308253Y481514D01*
X307892Y481169D01*
X307375Y480939D01*
X306910Y480862D01*
Y482472D01*
G01Y484690D02*
X307582Y484767D01*
X308150Y484882D01*
X308667Y485035D01*
X309235Y485227D01*
X310010Y485534D01*
Y484000D01*
G01X306910Y487867D02*
X306962Y488135D01*
X307117Y488442D01*
X307375Y488634D01*
X307737Y488710D01*
X308098Y488634D01*
X308408Y488404D01*
X308563Y488059D01*
Y487675D01*
X308667Y487445D01*
X308925Y487254D01*
X309287Y487177D01*
X309648Y487292D01*
X309907Y487560D01*
X310010Y487867D01*
X309907Y488174D01*
X309648Y488442D01*
X309287Y488557D01*
X308925Y488480D01*
X308667Y488289D01*
X308563Y488059D01*
Y487675D01*
X308408Y487330D01*
X308098Y487100D01*
X307737Y487024D01*
X307375Y487100D01*
X307117Y487292D01*
X306962Y487599D01*
X306910Y487867D01*
G01X314472Y479023D02*
X314627Y478793D01*
X314730Y478525D01*
Y478218D01*
X314575Y477873D01*
X314317Y477605D01*
X314007Y477413D01*
X313490Y477260D01*
X313025Y477222D01*
X312560Y477298D01*
X312250Y477413D01*
X311940Y477643D01*
X311733Y477912D01*
X311630Y478180D01*
Y478448D01*
X311733Y478717D01*
X311888Y478947D01*
X312095Y479138D01*
G01X314213Y480552D02*
X314523Y480782D01*
X314678Y481050D01*
X314730Y481357D01*
X314627Y481740D01*
X314368Y482008D01*
X314058Y482085D01*
X313748Y482047D01*
X313490Y481893D01*
X312973Y481127D01*
X312612Y480782D01*
X312095Y480552D01*
X311630Y480475D01*
Y482085D01*
G01Y484303D02*
X312302Y484380D01*
X312870Y484495D01*
X313387Y484648D01*
X313955Y484840D01*
X314730Y485147D01*
Y483613D01*
G01X312922Y486752D02*
X313283Y487020D01*
X313490Y487250D01*
X313593Y487557D01*
X313490Y487825D01*
X313283Y488017D01*
X312973Y488170D01*
X312612Y488208D01*
X312302Y488170D01*
X311992Y488017D01*
X311733Y487787D01*
X311630Y487518D01*
X311733Y487212D01*
X312043Y486943D01*
X312508Y486790D01*
X313025Y486752D01*
X313697Y486828D01*
X314058Y486943D01*
X314420Y487135D01*
X314678Y487403D01*
X314730Y487672D01*
X314627Y487940D01*
X314368Y488132D01*
G01X322994Y477510D02*
X319894D01*
Y479044D01*
G01Y481377D02*
X322994D01*
X322374Y480917D01*
G01X319894D02*
Y481837D01*
G01Y484477D02*
X319946Y484745D01*
X320101Y485052D01*
X320359Y485244D01*
X320721Y485320D01*
X321082Y485244D01*
X321392Y485014D01*
X321547Y484669D01*
Y484285D01*
X321651Y484055D01*
X321909Y483864D01*
X322271Y483787D01*
X322632Y483902D01*
X322891Y484170D01*
X322994Y484477D01*
X322891Y484784D01*
X322632Y485052D01*
X322271Y485167D01*
X321909Y485090D01*
X321651Y484899D01*
X321547Y484669D01*
Y484285D01*
X321392Y483940D01*
X321082Y483710D01*
X320721Y483634D01*
X320359Y483710D01*
X320101Y483902D01*
X319946Y484209D01*
X319894Y484477D01*
G01X318758Y477602D02*
X315658D01*
Y479136D01*
G01Y481469D02*
X318758D01*
X318138Y481009D01*
G01X315658D02*
Y481929D01*
G01Y484492D02*
X316330Y484569D01*
X316898Y484684D01*
X317415Y484837D01*
X317983Y485029D01*
X318758Y485336D01*
Y483802D01*
G01X318084Y498792D02*
X318314Y498947D01*
X318582Y499050D01*
X318889D01*
X319234Y498895D01*
X319502Y498637D01*
X319694Y498327D01*
X319847Y497810D01*
X319885Y497345D01*
X319809Y496880D01*
X319694Y496570D01*
X319464Y496260D01*
X319195Y496053D01*
X318927Y495950D01*
X318659D01*
X318390Y496053D01*
X318160Y496208D01*
X317969Y496415D01*
G01X316555Y498533D02*
X316325Y498843D01*
X316057Y498998D01*
X315750Y499050D01*
X315367Y498947D01*
X315099Y498688D01*
X315022Y498378D01*
X315060Y498068D01*
X315214Y497810D01*
X315980Y497293D01*
X316325Y496932D01*
X316555Y496415D01*
X316632Y495950D01*
X315022D01*
G01X312727D02*
X312459Y496002D01*
X312152Y496157D01*
X311960Y496415D01*
X311884Y496777D01*
X311960Y497138D01*
X312190Y497448D01*
X312535Y497603D01*
X312919D01*
X313149Y497707D01*
X313340Y497965D01*
X313417Y498327D01*
X313302Y498688D01*
X313034Y498947D01*
X312727Y499050D01*
X312420Y498947D01*
X312152Y498688D01*
X312037Y498327D01*
X312114Y497965D01*
X312305Y497707D01*
X312535Y497603D01*
X312919D01*
X313264Y497448D01*
X313494Y497138D01*
X313570Y496777D01*
X313494Y496415D01*
X313302Y496157D01*
X312995Y496002D01*
X312727Y495950D01*
G01X309167D02*
Y499050D01*
X310585Y496828D01*
X308669D01*
G01X307809Y496253D02*
Y499453D01*
G01X318084Y494343D02*
X318314Y494498D01*
X318582Y494601D01*
X318889D01*
X319234Y494446D01*
X319502Y494188D01*
X319694Y493878D01*
X319847Y493361D01*
X319885Y492896D01*
X319809Y492431D01*
X319694Y492121D01*
X319464Y491811D01*
X319195Y491604D01*
X318927Y491501D01*
X318659D01*
X318390Y491604D01*
X318160Y491759D01*
X317969Y491966D01*
G01X316555Y494084D02*
X316325Y494394D01*
X316057Y494549D01*
X315750Y494601D01*
X315367Y494498D01*
X315099Y494239D01*
X315022Y493929D01*
X315060Y493619D01*
X315214Y493361D01*
X315980Y492844D01*
X316325Y492483D01*
X316555Y491966D01*
X316632Y491501D01*
X315022D01*
G01X312727D02*
X312459Y491553D01*
X312152Y491708D01*
X311960Y491966D01*
X311884Y492328D01*
X311960Y492689D01*
X312190Y492999D01*
X312535Y493154D01*
X312919D01*
X313149Y493258D01*
X313340Y493516D01*
X313417Y493878D01*
X313302Y494239D01*
X313034Y494498D01*
X312727Y494601D01*
X312420Y494498D01*
X312152Y494239D01*
X312037Y493878D01*
X312114Y493516D01*
X312305Y493258D01*
X312535Y493154D01*
X312919D01*
X313264Y492999D01*
X313494Y492689D01*
X313570Y492328D01*
X313494Y491966D01*
X313302Y491708D01*
X312995Y491553D01*
X312727Y491501D01*
G01X310470Y491966D02*
X310240Y491708D01*
X309972Y491553D01*
X309627Y491501D01*
X309282Y491604D01*
X309014Y491811D01*
X308822Y492173D01*
X308784Y492586D01*
X308860Y492999D01*
X309052Y493258D01*
X309320Y493464D01*
X309589Y493516D01*
X309857Y493464D01*
X310202Y493258D01*
X310087Y494601D01*
X309052D01*
G01X307809Y492253D02*
Y495453D01*
G01X307308Y506293D02*
Y512493D01*
G01X318449Y543357D02*
X321549D01*
Y544316D01*
X321394Y544622D01*
X321187Y544814D01*
X320774Y544891D01*
X320361Y544814D01*
X320102Y544584D01*
X319947Y544316D01*
Y543357D01*
G01Y544316D02*
X318449Y544891D01*
G01Y547224D02*
X321549D01*
X320929Y546764D01*
G01X318449D02*
Y547684D01*
G01X321549Y550324D02*
X321446Y550017D01*
X321187Y549787D01*
X320877Y549634D01*
X320464Y549519D01*
X319999Y549481D01*
X319534Y549519D01*
X319121Y549634D01*
X318811Y549787D01*
X318552Y550017D01*
X318449Y550324D01*
X318552Y550631D01*
X318811Y550861D01*
X319121Y551014D01*
X319534Y551129D01*
X319999Y551167D01*
X320464Y551129D01*
X320877Y551014D01*
X321187Y550861D01*
X321446Y550631D01*
X321549Y550324D01*
G01X318811Y552772D02*
X318552Y553041D01*
X318449Y553347D01*
X318552Y553654D01*
X318862Y553922D01*
X319327Y554114D01*
X319792Y554191D01*
X320361D01*
X320826Y554114D01*
X321239Y553922D01*
X321446Y553692D01*
X321549Y553424D01*
X321446Y553117D01*
X321239Y552887D01*
X320929Y552734D01*
X320516Y552657D01*
X320154Y552734D01*
X319792Y552926D01*
X319586Y553156D01*
X319534Y553424D01*
X319637Y553731D01*
X319896Y553961D01*
X320361Y554191D01*
G01X318449Y556524D02*
X318501Y556792D01*
X318656Y557099D01*
X318914Y557291D01*
X319276Y557367D01*
X319637Y557291D01*
X319947Y557061D01*
X320102Y556716D01*
Y556332D01*
X320206Y556102D01*
X320464Y555911D01*
X320826Y555834D01*
X321187Y555949D01*
X321446Y556217D01*
X321549Y556524D01*
X321446Y556831D01*
X321187Y557099D01*
X320826Y557214D01*
X320464Y557137D01*
X320206Y556946D01*
X320102Y556716D01*
Y556332D01*
X319947Y555987D01*
X319637Y555757D01*
X319276Y555681D01*
X318914Y555757D01*
X318656Y555949D01*
X318501Y556256D01*
X318449Y556524D01*
G01X320387Y534527D02*
X323587D01*
G01X320387Y540727D02*
Y534527D01*
G01X323587Y540727D02*
X320387D01*
G01X318830Y596430D02*
Y599530D01*
X317910D01*
X317603Y599375D01*
X317373Y599013D01*
X317296Y598600D01*
X317373Y598187D01*
X317565Y597877D01*
X317910Y597722D01*
X318830D01*
G01X314120Y599272D02*
X314350Y599427D01*
X314618Y599530D01*
X314925D01*
X315270Y599375D01*
X315538Y599117D01*
X315730Y598807D01*
X315883Y598290D01*
X315921Y597825D01*
X315845Y597360D01*
X315730Y597050D01*
X315500Y596740D01*
X315231Y596533D01*
X314963Y596430D01*
X314695D01*
X314426Y596533D01*
X314196Y596688D01*
X314005Y596895D01*
G01X312706Y597050D02*
X312476Y596688D01*
X312170Y596482D01*
X311825Y596430D01*
X311518Y596482D01*
X311211Y596740D01*
X311020Y597050D01*
X310981Y597360D01*
X311058Y597722D01*
X311326Y597980D01*
X311595Y598083D01*
X311940D01*
G01X311595D02*
X311365Y598238D01*
X311173Y598497D01*
X311096Y598807D01*
X311173Y599117D01*
X311365Y599375D01*
X311710Y599530D01*
X312055Y599478D01*
X312400Y599272D01*
G01X309677Y591928D02*
Y599328D01*
G01X325010Y708086D02*
X346707D01*
Y703910D01*
X362018D01*
Y634225D01*
X351450D01*
Y641676D01*
X314197D01*
Y643886D01*
X307073D01*
Y643805D01*
X306582D01*
Y702591D01*
X318863D01*
Y708086D01*
X325010D01*
G01X320643Y634620D02*
X320873Y634775D01*
X321141Y634878D01*
X321448D01*
X321793Y634723D01*
X322061Y634465D01*
X322253Y634155D01*
X322406Y633638D01*
X322444Y633173D01*
X322368Y632708D01*
X322253Y632398D01*
X322023Y632088D01*
X321754Y631881D01*
X321486Y631778D01*
X321218D01*
X320949Y631881D01*
X320719Y632036D01*
X320528Y632243D01*
G01X319229D02*
X318999Y631985D01*
X318731Y631830D01*
X318386Y631778D01*
X318041Y631881D01*
X317773Y632088D01*
X317581Y632450D01*
X317543Y632863D01*
X317619Y633276D01*
X317811Y633535D01*
X318079Y633741D01*
X318348Y633793D01*
X318616Y633741D01*
X318961Y633535D01*
X318846Y634878D01*
X317811D01*
G01X315363Y631778D02*
X315286Y632450D01*
X315171Y633018D01*
X315018Y633535D01*
X314826Y634103D01*
X314519Y634878D01*
X316053D01*
G01X312838Y632140D02*
X312569Y631881D01*
X312263Y631778D01*
X311956Y631881D01*
X311688Y632191D01*
X311496Y632656D01*
X311419Y633121D01*
Y633690D01*
X311496Y634155D01*
X311688Y634568D01*
X311918Y634775D01*
X312186Y634878D01*
X312493Y634775D01*
X312723Y634568D01*
X312876Y634258D01*
X312953Y633845D01*
X312876Y633483D01*
X312684Y633121D01*
X312454Y632915D01*
X312186Y632863D01*
X311879Y632966D01*
X311649Y633225D01*
X311419Y633690D01*
G01X311100Y637636D02*
Y640636D01*
G01X314200Y637536D02*
Y640736D01*
G01X308000Y637536D02*
X314200D01*
G01X308000Y640736D02*
Y637536D01*
G01X314200Y640736D02*
X308000D01*
G01X307260Y652756D02*
Y649556D01*
G01X313460D02*
Y652756D01*
G01X307260Y649556D02*
X313460D01*
G01Y652756D02*
X307260D01*
G01Y660756D02*
Y657556D01*
G01X313460D02*
Y660756D01*
G01X307260Y657556D02*
X313460D01*
G01X307260Y656756D02*
Y653556D01*
G01X313460Y656756D02*
X307260D01*
G01X313460Y653556D02*
Y656756D01*
G01X307260Y653556D02*
X313460D01*
G01Y645556D02*
Y648756D01*
G01X307260Y645556D02*
X313460D01*
G01X307260Y648756D02*
Y645556D01*
G01X313460Y648756D02*
X307260D01*
G01Y676756D02*
Y673556D01*
G01X313460D02*
Y676756D01*
G01X307260Y673556D02*
X313460D01*
G01Y660756D02*
X307260D01*
G01Y664756D02*
Y661556D01*
G01X313460Y664756D02*
X307260D01*
G01X313460Y661556D02*
Y664756D01*
G01X307260Y661556D02*
X313460D01*
G01X307260Y669556D02*
X313460D01*
Y672756D01*
X307260D01*
Y669556D01*
G01X313460Y668756D02*
X307260D01*
Y665556D01*
X313460D01*
Y668756D01*
G01X307260Y684756D02*
Y681556D01*
G01X313460D02*
Y684756D01*
G01X307260Y681556D02*
X313460D01*
G01Y684756D02*
X307260D01*
G01Y688756D02*
Y685556D01*
G01X313460Y688756D02*
X307260D01*
G01X313460Y685556D02*
Y688756D01*
G01X307260Y685556D02*
X313460D01*
G01X307260Y692756D02*
Y689556D01*
G01X313460D02*
Y692756D01*
G01X307260Y689556D02*
X313460D01*
G01Y676756D02*
X307260D01*
G01Y680756D02*
Y677556D01*
G01X313460Y680756D02*
X307260D01*
G01X313460Y677556D02*
Y680756D01*
G01X307260Y677556D02*
X313460D01*
G01X307260Y700756D02*
Y697556D01*
G01X313460D02*
Y700756D01*
G01X307260Y697556D02*
X313460D01*
G01Y700756D02*
X307260D01*
G01Y696756D02*
Y693556D01*
G01X313460Y696756D02*
X307260D01*
G01X313460Y693556D02*
Y696756D01*
G01X307260Y693556D02*
X313460D01*
G01Y692756D02*
X307260D01*
G01X310340Y737556D02*
X313540D01*
G01X310340Y743756D02*
Y737556D01*
G01X313540D02*
Y743756D01*
G01X306340Y737556D02*
X309540D01*
G01X306340Y743756D02*
Y737556D01*
G01X309540D02*
Y743756D01*
G01X315010Y733801D02*
X311810D01*
G01Y727601D02*
X315010D01*
G01X311810Y733801D02*
Y727601D01*
G01X315010D02*
Y733801D01*
G01X311130Y732467D02*
X307930D01*
G01X311130Y726267D02*
Y732467D01*
G01X307930Y726267D02*
X311130D01*
G01X307930Y732467D02*
Y726267D01*
G01X313540Y743756D02*
X310340D01*
G01X310440Y740656D02*
X313440D01*
G01X309540Y743756D02*
X306340D01*
G01X306440Y740656D02*
X309440D01*
G01X311042Y744652D02*
X314142D01*
Y745611D01*
X313987Y745917D01*
X313780Y746109D01*
X313367Y746186D01*
X312954Y746109D01*
X312695Y745879D01*
X312540Y745611D01*
Y744652D01*
G01Y745611D02*
X311042Y746186D01*
G01Y748519D02*
X311094Y748787D01*
X311249Y749094D01*
X311507Y749286D01*
X311869Y749362D01*
X312230Y749286D01*
X312540Y749056D01*
X312695Y748711D01*
Y748327D01*
X312799Y748097D01*
X313057Y747906D01*
X313419Y747829D01*
X313780Y747944D01*
X314039Y748212D01*
X314142Y748519D01*
X314039Y748826D01*
X313780Y749094D01*
X313419Y749209D01*
X313057Y749132D01*
X312799Y748941D01*
X312695Y748711D01*
Y748327D01*
X312540Y747982D01*
X312230Y747752D01*
X311869Y747676D01*
X311507Y747752D01*
X311249Y747944D01*
X311094Y748251D01*
X311042Y748519D01*
G01Y751619D02*
X311094Y751887D01*
X311249Y752194D01*
X311507Y752386D01*
X311869Y752462D01*
X312230Y752386D01*
X312540Y752156D01*
X312695Y751811D01*
Y751427D01*
X312799Y751197D01*
X313057Y751006D01*
X313419Y750929D01*
X313780Y751044D01*
X314039Y751312D01*
X314142Y751619D01*
X314039Y751926D01*
X313780Y752194D01*
X313419Y752309D01*
X313057Y752232D01*
X312799Y752041D01*
X312695Y751811D01*
Y751427D01*
X312540Y751082D01*
X312230Y750852D01*
X311869Y750776D01*
X311507Y750852D01*
X311249Y751044D01*
X311094Y751351D01*
X311042Y751619D01*
G01X311662Y753876D02*
X311300Y754106D01*
X311094Y754412D01*
X311042Y754757D01*
X311094Y755064D01*
X311352Y755371D01*
X311662Y755562D01*
X311972Y755601D01*
X312334Y755524D01*
X312592Y755256D01*
X312695Y754987D01*
Y754642D01*
G01Y754987D02*
X312850Y755217D01*
X313109Y755409D01*
X313419Y755486D01*
X313729Y755409D01*
X313987Y755217D01*
X314142Y754872D01*
X314090Y754527D01*
X313884Y754182D01*
G01X308297Y744703D02*
X311397D01*
Y745662D01*
X311242Y745968D01*
X311035Y746160D01*
X310622Y746237D01*
X310209Y746160D01*
X309950Y745930D01*
X309795Y745662D01*
Y744703D01*
G01Y745662D02*
X308297Y746237D01*
G01Y748570D02*
X308349Y748838D01*
X308504Y749145D01*
X308762Y749337D01*
X309124Y749413D01*
X309485Y749337D01*
X309795Y749107D01*
X309950Y748762D01*
Y748378D01*
X310054Y748148D01*
X310312Y747957D01*
X310674Y747880D01*
X311035Y747995D01*
X311294Y748263D01*
X311397Y748570D01*
X311294Y748877D01*
X311035Y749145D01*
X310674Y749260D01*
X310312Y749183D01*
X310054Y748992D01*
X309950Y748762D01*
Y748378D01*
X309795Y748033D01*
X309485Y747803D01*
X309124Y747727D01*
X308762Y747803D01*
X308504Y747995D01*
X308349Y748302D01*
X308297Y748570D01*
G01Y751670D02*
X308349Y751938D01*
X308504Y752245D01*
X308762Y752437D01*
X309124Y752513D01*
X309485Y752437D01*
X309795Y752207D01*
X309950Y751862D01*
Y751478D01*
X310054Y751248D01*
X310312Y751057D01*
X310674Y750980D01*
X311035Y751095D01*
X311294Y751363D01*
X311397Y751670D01*
X311294Y751977D01*
X311035Y752245D01*
X310674Y752360D01*
X310312Y752283D01*
X310054Y752092D01*
X309950Y751862D01*
Y751478D01*
X309795Y751133D01*
X309485Y750903D01*
X309124Y750827D01*
X308762Y750903D01*
X308504Y751095D01*
X308349Y751402D01*
X308297Y751670D01*
G01X309589Y754042D02*
X309950Y754310D01*
X310157Y754540D01*
X310260Y754847D01*
X310157Y755115D01*
X309950Y755307D01*
X309640Y755460D01*
X309279Y755498D01*
X308969Y755460D01*
X308659Y755307D01*
X308400Y755077D01*
X308297Y754808D01*
X308400Y754502D01*
X308710Y754233D01*
X309175Y754080D01*
X309692Y754042D01*
X310364Y754118D01*
X310725Y754233D01*
X311087Y754425D01*
X311345Y754693D01*
X311397Y754962D01*
X311294Y755230D01*
X311035Y755422D01*
G01X312704Y759077D02*
X312859Y758847D01*
X312962Y758579D01*
Y758272D01*
X312807Y757927D01*
X312549Y757659D01*
X312239Y757467D01*
X311722Y757314D01*
X311257Y757276D01*
X310792Y757352D01*
X310482Y757467D01*
X310172Y757697D01*
X309965Y757966D01*
X309862Y758234D01*
Y758502D01*
X309965Y758771D01*
X310120Y759001D01*
X310327Y759192D01*
G01X311154Y760606D02*
X311515Y760874D01*
X311722Y761104D01*
X311825Y761411D01*
X311722Y761679D01*
X311515Y761871D01*
X311205Y762024D01*
X310844Y762062D01*
X310534Y762024D01*
X310224Y761871D01*
X309965Y761641D01*
X309862Y761372D01*
X309965Y761066D01*
X310275Y760797D01*
X310740Y760644D01*
X311257Y760606D01*
X311929Y760682D01*
X312290Y760797D01*
X312652Y760989D01*
X312910Y761257D01*
X312962Y761526D01*
X312859Y761794D01*
X312600Y761986D01*
G01X309862Y764894D02*
X312962D01*
X310740Y763476D01*
Y765392D01*
G01X311154Y766806D02*
X311515Y767074D01*
X311722Y767304D01*
X311825Y767611D01*
X311722Y767879D01*
X311515Y768071D01*
X311205Y768224D01*
X310844Y768262D01*
X310534Y768224D01*
X310224Y768071D01*
X309965Y767841D01*
X309862Y767572D01*
X309965Y767266D01*
X310275Y766997D01*
X310740Y766844D01*
X311257Y766806D01*
X311929Y766882D01*
X312290Y766997D01*
X312652Y767189D01*
X312910Y767457D01*
X312962Y767726D01*
X312859Y767994D01*
X312600Y768186D01*
G01X327614Y794713D02*
X326656Y797813D01*
X325698Y794713D01*
G01X326043Y795798D02*
X327269D01*
G01X323556Y794713D02*
Y797813D01*
X324016Y797193D01*
G01Y794713D02*
X323096D01*
G01X321184Y797296D02*
X320954Y797606D01*
X320686Y797761D01*
X320379Y797813D01*
X319996Y797710D01*
X319728Y797451D01*
X319651Y797141D01*
X319689Y796831D01*
X319843Y796573D01*
X320609Y796056D01*
X320954Y795695D01*
X321184Y795178D01*
X321261Y794713D01*
X319651D01*
G01X325972Y62462D02*
X326127Y62232D01*
X326230Y61964D01*
Y61657D01*
X326075Y61312D01*
X325817Y61044D01*
X325507Y60852D01*
X324990Y60699D01*
X324525Y60661D01*
X324060Y60737D01*
X323750Y60852D01*
X323440Y61082D01*
X323233Y61351D01*
X323130Y61619D01*
Y61887D01*
X323233Y62156D01*
X323388Y62386D01*
X323595Y62577D01*
G01X323130Y64719D02*
X326230D01*
X325610Y64259D01*
G01X323130D02*
Y65179D01*
G01Y68279D02*
X326230D01*
X324008Y66861D01*
Y68777D01*
G01X323130Y70842D02*
X323802Y70919D01*
X324370Y71034D01*
X324887Y71187D01*
X325455Y71379D01*
X326230Y71686D01*
Y70152D01*
G01X328505Y83060D02*
X325505D01*
G01X328605Y86160D02*
X325405D01*
G01X328605Y79960D02*
Y86160D01*
G01X325405Y79960D02*
X328605D01*
G01X325405Y86160D02*
Y79960D01*
G01X324605D02*
Y86160D01*
G01X331957Y119710D02*
X321757D01*
G01D02*
Y115110D01*
G01D02*
X331957D01*
G01D02*
Y119710D01*
G01X326857D02*
Y115110D01*
G01X345301Y111247D02*
Y114347D01*
X344342D01*
X344036Y114192D01*
X343844Y113985D01*
X343767Y113572D01*
X343844Y113159D01*
X344074Y112900D01*
X344342Y112745D01*
X345301D01*
G01X344342D02*
X343767Y111247D01*
G01X342162Y113830D02*
X341932Y114140D01*
X341664Y114295D01*
X341357Y114347D01*
X340974Y114244D01*
X340706Y113985D01*
X340629Y113675D01*
X340667Y113365D01*
X340821Y113107D01*
X341587Y112590D01*
X341932Y112229D01*
X342162Y111712D01*
X342239Y111247D01*
X340629D01*
G01X338334Y114347D02*
X338641Y114244D01*
X338871Y113985D01*
X339024Y113675D01*
X339139Y113262D01*
X339177Y112797D01*
X339139Y112332D01*
X339024Y111919D01*
X338871Y111609D01*
X338641Y111350D01*
X338334Y111247D01*
X338027Y111350D01*
X337797Y111609D01*
X337644Y111919D01*
X337529Y112332D01*
X337491Y112797D01*
X337529Y113262D01*
X337644Y113675D01*
X337797Y113985D01*
X338027Y114244D01*
X338334Y114347D01*
G01X335234Y111247D02*
X334966Y111299D01*
X334659Y111454D01*
X334467Y111712D01*
X334391Y112074D01*
X334467Y112435D01*
X334697Y112745D01*
X335042Y112900D01*
X335426D01*
X335656Y113004D01*
X335847Y113262D01*
X335924Y113624D01*
X335809Y113985D01*
X335541Y114244D01*
X335234Y114347D01*
X334927Y114244D01*
X334659Y113985D01*
X334544Y113624D01*
X334621Y113262D01*
X334812Y113004D01*
X335042Y112900D01*
X335426D01*
X335771Y112745D01*
X336001Y112435D01*
X336077Y112074D01*
X336001Y111712D01*
X335809Y111454D01*
X335502Y111299D01*
X335234Y111247D01*
G01X334273Y118897D02*
Y115697D01*
G01D02*
X340473D01*
G01Y118897D02*
X334273D01*
G01X341602Y249989D02*
Y253089D01*
X340643D01*
X340337Y252934D01*
X340145Y252727D01*
X340068Y252314D01*
X340145Y251901D01*
X340375Y251642D01*
X340643Y251487D01*
X341602D01*
G01X340643D02*
X340068Y249989D01*
G01X337735D02*
Y253089D01*
X338195Y252469D01*
G01Y249989D02*
X337275D01*
G01X335363Y251281D02*
X335095Y251642D01*
X334865Y251849D01*
X334558Y251952D01*
X334290Y251849D01*
X334098Y251642D01*
X333945Y251332D01*
X333907Y250971D01*
X333945Y250661D01*
X334098Y250351D01*
X334328Y250092D01*
X334597Y249989D01*
X334903Y250092D01*
X335172Y250402D01*
X335325Y250867D01*
X335363Y251384D01*
X335287Y252056D01*
X335172Y252417D01*
X334980Y252779D01*
X334712Y253037D01*
X334443Y253089D01*
X334175Y252986D01*
X333983Y252727D01*
G01X331535Y249989D02*
Y253089D01*
X331995Y252469D01*
G01Y249989D02*
X331075D01*
G01X341602Y245482D02*
Y248582D01*
X340643D01*
X340337Y248427D01*
X340145Y248220D01*
X340068Y247807D01*
X340145Y247394D01*
X340375Y247135D01*
X340643Y246980D01*
X341602D01*
G01X340643D02*
X340068Y245482D01*
G01X337735D02*
Y248582D01*
X338195Y247962D01*
G01Y245482D02*
X337275D01*
G01X335363Y246774D02*
X335095Y247135D01*
X334865Y247342D01*
X334558Y247445D01*
X334290Y247342D01*
X334098Y247135D01*
X333945Y246825D01*
X333907Y246464D01*
X333945Y246154D01*
X334098Y245844D01*
X334328Y245585D01*
X334597Y245482D01*
X334903Y245585D01*
X335172Y245895D01*
X335325Y246360D01*
X335363Y246877D01*
X335287Y247549D01*
X335172Y247910D01*
X334980Y248272D01*
X334712Y248530D01*
X334443Y248582D01*
X334175Y248479D01*
X333983Y248220D01*
G01X331535Y245482D02*
X331267Y245534D01*
X330960Y245689D01*
X330768Y245947D01*
X330692Y246309D01*
X330768Y246670D01*
X330998Y246980D01*
X331343Y247135D01*
X331727D01*
X331957Y247239D01*
X332148Y247497D01*
X332225Y247859D01*
X332110Y248220D01*
X331842Y248479D01*
X331535Y248582D01*
X331228Y248479D01*
X330960Y248220D01*
X330845Y247859D01*
X330922Y247497D01*
X331113Y247239D01*
X331343Y247135D01*
X331727D01*
X332072Y246980D01*
X332302Y246670D01*
X332378Y246309D01*
X332302Y245947D01*
X332110Y245689D01*
X331803Y245534D01*
X331535Y245482D01*
G01X341602Y241435D02*
Y244535D01*
X340643D01*
X340337Y244380D01*
X340145Y244173D01*
X340068Y243760D01*
X340145Y243347D01*
X340375Y243088D01*
X340643Y242933D01*
X341602D01*
G01X340643D02*
X340068Y241435D01*
G01X337735D02*
Y244535D01*
X338195Y243915D01*
G01Y241435D02*
X337275D01*
G01X334712D02*
X334635Y242107D01*
X334520Y242675D01*
X334367Y243192D01*
X334175Y243760D01*
X333868Y244535D01*
X335402D01*
G01X331075Y241435D02*
Y244535D01*
X332493Y242313D01*
X330577D01*
G01X337039Y262318D02*
Y265418D01*
X336080D01*
X335774Y265263D01*
X335582Y265056D01*
X335505Y264643D01*
X335582Y264230D01*
X335812Y263971D01*
X336080Y263816D01*
X337039D01*
G01X336080D02*
X335505Y262318D01*
G01X333172D02*
Y265418D01*
X333632Y264798D01*
G01Y262318D02*
X332712D01*
G01X329612D02*
Y265418D01*
X331030Y263196D01*
X329114D01*
G01X326972Y262318D02*
Y265418D01*
X327432Y264798D01*
G01Y262318D02*
X326512D01*
G01X341602Y254035D02*
Y257135D01*
X340643D01*
X340337Y256980D01*
X340145Y256773D01*
X340068Y256360D01*
X340145Y255947D01*
X340375Y255688D01*
X340643Y255533D01*
X341602D01*
G01X340643D02*
X340068Y254035D01*
G01X337735D02*
Y257135D01*
X338195Y256515D01*
G01Y254035D02*
X337275D01*
G01X335363Y255327D02*
X335095Y255688D01*
X334865Y255895D01*
X334558Y255998D01*
X334290Y255895D01*
X334098Y255688D01*
X333945Y255378D01*
X333907Y255017D01*
X333945Y254707D01*
X334098Y254397D01*
X334328Y254138D01*
X334597Y254035D01*
X334903Y254138D01*
X335172Y254448D01*
X335325Y254913D01*
X335363Y255430D01*
X335287Y256102D01*
X335172Y256463D01*
X334980Y256825D01*
X334712Y257083D01*
X334443Y257135D01*
X334175Y257032D01*
X333983Y256773D01*
G01X332263Y256618D02*
X332033Y256928D01*
X331765Y257083D01*
X331458Y257135D01*
X331075Y257032D01*
X330807Y256773D01*
X330730Y256463D01*
X330768Y256153D01*
X330922Y255895D01*
X331688Y255378D01*
X332033Y255017D01*
X332263Y254500D01*
X332340Y254035D01*
X330730D01*
G01X341602Y257989D02*
Y261089D01*
X340643D01*
X340337Y260934D01*
X340145Y260727D01*
X340068Y260314D01*
X340145Y259901D01*
X340375Y259642D01*
X340643Y259487D01*
X341602D01*
G01X340643D02*
X340068Y257989D01*
G01X337735D02*
Y261089D01*
X338195Y260469D01*
G01Y257989D02*
X337275D01*
G01X335363Y259281D02*
X335095Y259642D01*
X334865Y259849D01*
X334558Y259952D01*
X334290Y259849D01*
X334098Y259642D01*
X333945Y259332D01*
X333907Y258971D01*
X333945Y258661D01*
X334098Y258351D01*
X334328Y258092D01*
X334597Y257989D01*
X334903Y258092D01*
X335172Y258402D01*
X335325Y258867D01*
X335363Y259384D01*
X335287Y260056D01*
X335172Y260417D01*
X334980Y260779D01*
X334712Y261037D01*
X334443Y261089D01*
X334175Y260986D01*
X333983Y260727D01*
G01X331612Y257989D02*
X331535Y258661D01*
X331420Y259229D01*
X331267Y259746D01*
X331075Y260314D01*
X330768Y261089D01*
X332302D01*
G01X341602Y266634D02*
Y269734D01*
X340643D01*
X340337Y269579D01*
X340145Y269372D01*
X340068Y268959D01*
X340145Y268546D01*
X340375Y268287D01*
X340643Y268132D01*
X341602D01*
G01X340643D02*
X340068Y266634D01*
G01X337735D02*
Y269734D01*
X338195Y269114D01*
G01Y266634D02*
X337275D01*
G01X334712D02*
X334635Y267306D01*
X334520Y267874D01*
X334367Y268391D01*
X334175Y268959D01*
X333868Y269734D01*
X335402D01*
G01X331535Y266634D02*
Y269734D01*
X331995Y269114D01*
G01Y266634D02*
X331075D01*
G01X340847Y279329D02*
Y282429D01*
X339888D01*
X339582Y282274D01*
X339390Y282067D01*
X339313Y281654D01*
X339390Y281241D01*
X339620Y280982D01*
X339888Y280827D01*
X340847D01*
G01X339888D02*
X339313Y279329D01*
G01X336980D02*
Y282429D01*
X337440Y281809D01*
G01Y279329D02*
X336520D01*
G01X333880D02*
Y282429D01*
X334340Y281809D01*
G01Y279329D02*
X333420D01*
G01X331432Y279691D02*
X331163Y279432D01*
X330857Y279329D01*
X330550Y279432D01*
X330282Y279742D01*
X330090Y280207D01*
X330013Y280672D01*
Y281241D01*
X330090Y281706D01*
X330282Y282119D01*
X330512Y282326D01*
X330780Y282429D01*
X331087Y282326D01*
X331317Y282119D01*
X331470Y281809D01*
X331547Y281396D01*
X331470Y281034D01*
X331278Y280672D01*
X331048Y280466D01*
X330780Y280414D01*
X330473Y280517D01*
X330243Y280776D01*
X330013Y281241D01*
G01X341374Y275234D02*
Y278334D01*
X340415D01*
X340109Y278179D01*
X339917Y277972D01*
X339840Y277559D01*
X339917Y277146D01*
X340147Y276887D01*
X340415Y276732D01*
X341374D01*
G01X340415D02*
X339840Y275234D01*
G01X337507D02*
Y278334D01*
X337967Y277714D01*
G01Y275234D02*
X337047D01*
G01X334407D02*
Y278334D01*
X334867Y277714D01*
G01Y275234D02*
X333947D01*
G01X332150Y275699D02*
X331920Y275441D01*
X331652Y275286D01*
X331307Y275234D01*
X330962Y275337D01*
X330694Y275544D01*
X330502Y275906D01*
X330464Y276319D01*
X330540Y276732D01*
X330732Y276991D01*
X331000Y277197D01*
X331269Y277249D01*
X331537Y277197D01*
X331882Y276991D01*
X331767Y278334D01*
X330732D01*
G01X341602Y270865D02*
Y273965D01*
X340643D01*
X340337Y273810D01*
X340145Y273603D01*
X340068Y273190D01*
X340145Y272777D01*
X340375Y272518D01*
X340643Y272363D01*
X341602D01*
G01X340643D02*
X340068Y270865D01*
G01X337735D02*
Y273965D01*
X338195Y273345D01*
G01Y270865D02*
X337275D01*
G01X334712D02*
X334635Y271537D01*
X334520Y272105D01*
X334367Y272622D01*
X334175Y273190D01*
X333868Y273965D01*
X335402D01*
G01X332378Y271485D02*
X332148Y271123D01*
X331842Y270917D01*
X331497Y270865D01*
X331190Y270917D01*
X330883Y271175D01*
X330692Y271485D01*
X330653Y271795D01*
X330730Y272157D01*
X330998Y272415D01*
X331267Y272518D01*
X331612D01*
G01X331267D02*
X331037Y272673D01*
X330845Y272932D01*
X330768Y273242D01*
X330845Y273552D01*
X331037Y273810D01*
X331382Y273965D01*
X331727Y273913D01*
X332072Y273707D01*
G01X325990Y313464D02*
Y310264D01*
G01D02*
X332190D01*
G01D02*
Y313464D01*
G01X332967Y323077D02*
Y326177D01*
X332008D01*
X331702Y326022D01*
X331510Y325815D01*
X331433Y325402D01*
X331510Y324989D01*
X331740Y324730D01*
X332008Y324575D01*
X332967D01*
G01X332008D02*
X331433Y323077D01*
G01X329100D02*
Y326177D01*
X329560Y325557D01*
G01Y323077D02*
X328640D01*
G01X326728Y324369D02*
X326460Y324730D01*
X326230Y324937D01*
X325923Y325040D01*
X325655Y324937D01*
X325463Y324730D01*
X325310Y324420D01*
X325272Y324059D01*
X325310Y323749D01*
X325463Y323439D01*
X325693Y323180D01*
X325962Y323077D01*
X326268Y323180D01*
X326537Y323490D01*
X326690Y323955D01*
X326728Y324472D01*
X326652Y325144D01*
X326537Y325505D01*
X326345Y325867D01*
X326077Y326125D01*
X325808Y326177D01*
X325540Y326074D01*
X325348Y325815D01*
G01X323552Y323439D02*
X323283Y323180D01*
X322977Y323077D01*
X322670Y323180D01*
X322402Y323490D01*
X322210Y323955D01*
X322133Y324420D01*
Y324989D01*
X322210Y325454D01*
X322402Y325867D01*
X322632Y326074D01*
X322900Y326177D01*
X323207Y326074D01*
X323437Y325867D01*
X323590Y325557D01*
X323667Y325144D01*
X323590Y324782D01*
X323398Y324420D01*
X323168Y324214D01*
X322900Y324162D01*
X322593Y324265D01*
X322363Y324524D01*
X322133Y324989D01*
G01X332190Y313464D02*
X325990D01*
G01X329342Y478493D02*
X329497Y478263D01*
X329600Y477995D01*
Y477688D01*
X329445Y477343D01*
X329187Y477075D01*
X328877Y476883D01*
X328360Y476730D01*
X327895Y476692D01*
X327430Y476768D01*
X327120Y476883D01*
X326810Y477113D01*
X326603Y477382D01*
X326500Y477650D01*
Y477918D01*
X326603Y478187D01*
X326758Y478417D01*
X326965Y478608D01*
G01X329083Y480022D02*
X329393Y480252D01*
X329548Y480520D01*
X329600Y480827D01*
X329497Y481210D01*
X329238Y481478D01*
X328928Y481555D01*
X328618Y481517D01*
X328360Y481363D01*
X327843Y480597D01*
X327482Y480252D01*
X326965Y480022D01*
X326500Y479945D01*
Y481555D01*
G01Y483850D02*
X326552Y484118D01*
X326707Y484425D01*
X326965Y484617D01*
X327327Y484693D01*
X327688Y484617D01*
X327998Y484387D01*
X328153Y484042D01*
Y483658D01*
X328257Y483428D01*
X328515Y483237D01*
X328877Y483160D01*
X329238Y483275D01*
X329497Y483543D01*
X329600Y483850D01*
X329497Y484157D01*
X329238Y484425D01*
X328877Y484540D01*
X328515Y484463D01*
X328257Y484272D01*
X328153Y484042D01*
Y483658D01*
X327998Y483313D01*
X327688Y483083D01*
X327327Y483007D01*
X326965Y483083D01*
X326707Y483275D01*
X326552Y483582D01*
X326500Y483850D01*
G01X327120Y486107D02*
X326758Y486337D01*
X326552Y486643D01*
X326500Y486988D01*
X326552Y487295D01*
X326810Y487602D01*
X327120Y487793D01*
X327430Y487832D01*
X327792Y487755D01*
X328050Y487487D01*
X328153Y487218D01*
Y486873D01*
G01Y487218D02*
X328308Y487448D01*
X328567Y487640D01*
X328877Y487717D01*
X329187Y487640D01*
X329445Y487448D01*
X329600Y487103D01*
X329548Y486758D01*
X329342Y486413D01*
G01X335510Y548510D02*
Y574170D01*
G01X375340Y548510D02*
X335510D01*
G01X323587Y534527D02*
Y540727D01*
G01X338420Y580960D02*
X335510D01*
G01Y577570D02*
Y580960D01*
G01X329390D02*
Y594370D01*
G01X335510Y580960D02*
X329390D01*
G01X332803Y588777D02*
X332550Y589027D01*
X332360Y589443D01*
X332233Y590027D01*
X332360Y590527D01*
X332613Y590860D01*
X333057Y591110D01*
X334767D01*
Y586110D01*
X332677D01*
X332233Y586443D01*
X331980Y586943D01*
X331853Y587527D01*
X331980Y588110D01*
X332360Y588610D01*
X332803Y588777D01*
X334767D01*
G01X329390Y594370D02*
X333700D01*
G01D02*
X375340D01*
G01X326068Y663562D02*
Y643362D01*
X341868D01*
Y663562D01*
X336268D01*
X333968Y661262D01*
X331668Y663562D01*
X326068D01*
G01X328940Y669156D02*
G02I-1000J0D01*
G01X333940Y669356D02*
X336240Y667056D01*
G01X331640D02*
X333940Y669356D01*
G01X326040Y667056D02*
X331640D01*
G01X326040Y698256D02*
Y667056D01*
G01X336240D02*
X341840D01*
G01X327357Y706683D02*
X327737Y706933D01*
X328180Y707100D01*
X328687D01*
X329257Y706850D01*
X329700Y706433D01*
X330017Y705933D01*
X330270Y705100D01*
X330333Y704350D01*
X330207Y703600D01*
X330017Y703100D01*
X329637Y702600D01*
X329193Y702267D01*
X328750Y702100D01*
X328307D01*
X327863Y702267D01*
X327483Y702517D01*
X327167Y702850D01*
G01X341840Y698256D02*
X326040D01*
G01X345284Y794193D02*
X344326Y797293D01*
X343368Y794193D01*
G01X343713Y795278D02*
X344939D01*
G01X341226Y794193D02*
Y797293D01*
X341686Y796673D01*
G01Y794193D02*
X340766D01*
G01X338126D02*
Y797293D01*
X338586Y796673D01*
G01Y794193D02*
X337666D01*
G01X340473Y115697D02*
Y118897D01*
G01X434417Y139644D02*
Y145944D01*
X432537D01*
X431910Y145629D01*
X431440Y144894D01*
X431283Y144054D01*
X431440Y143214D01*
X431832Y142584D01*
X432537Y142269D01*
X434417D01*
G01X427960Y139434D02*
X425140Y145944D01*
G01X422052Y139644D02*
Y145944D01*
X418448Y139644D01*
Y145944D01*
G01X413950Y139434D02*
X414107Y139539D01*
Y139749D01*
X413950Y139854D01*
X413793Y139749D01*
Y139539D01*
X413950Y139434D01*
G01Y142269D02*
X414107Y142374D01*
Y142584D01*
X413950Y142689D01*
X413793Y142584D01*
Y142374D01*
X413950Y142269D01*
G01X409373Y139644D02*
Y145944D01*
X407807D01*
X407180Y145629D01*
X406710Y145209D01*
X406318Y144579D01*
X406005Y143844D01*
X405927Y142794D01*
X406005Y141744D01*
X406318Y141009D01*
X406710Y140379D01*
X407180Y139959D01*
X407807Y139644D01*
X409373D01*
G01X403308D02*
X401350Y145944D01*
X399392Y139644D01*
G01X400097Y141849D02*
X402603D01*
G01X395050Y145944D02*
Y139644D01*
G01X396852Y145944D02*
X393248D01*
G01X390238Y142269D02*
X389690Y143004D01*
X389220Y143424D01*
X388593Y143634D01*
X388045Y143424D01*
X387653Y143004D01*
X387340Y142374D01*
X387262Y141639D01*
X387340Y141009D01*
X387653Y140379D01*
X388123Y139854D01*
X388672Y139644D01*
X389298Y139854D01*
X389847Y140484D01*
X390160Y141429D01*
X390238Y142479D01*
X390082Y143844D01*
X389847Y144579D01*
X389455Y145314D01*
X388907Y145839D01*
X388358Y145944D01*
X387810Y145734D01*
X387418Y145209D01*
G01X384487Y139644D02*
Y145944D01*
X382450Y140694D01*
X380413Y145944D01*
Y139644D01*
G01X376150Y145944D02*
Y139644D01*
G01X377952Y145944D02*
X374348D01*
G01X371495Y139644D02*
Y145944D01*
G01X368205D02*
Y139644D01*
G01Y142794D02*
X371495D01*
G01X365273Y140904D02*
X364803Y140169D01*
X364177Y139749D01*
X363472Y139644D01*
X362845Y139749D01*
X362218Y140274D01*
X361827Y140904D01*
X361748Y141534D01*
X361905Y142269D01*
X362453Y142794D01*
X363002Y143004D01*
X363707D01*
G01X363002D02*
X362532Y143319D01*
X362140Y143844D01*
X361983Y144474D01*
X362140Y145104D01*
X362532Y145629D01*
X363237Y145944D01*
X363942Y145839D01*
X364647Y145419D01*
G01X359208Y139644D02*
X357250Y145944D01*
X355292Y139644D01*
G01X355997Y141849D02*
X358503D01*
G01X352673Y139644D02*
Y145944D01*
X351107D01*
X350480Y145629D01*
X350010Y145209D01*
X349618Y144579D01*
X349305Y143844D01*
X349227Y142794D01*
X349305Y141744D01*
X349618Y141009D01*
X350010Y140379D01*
X350480Y139959D01*
X351107Y139644D01*
X352673D01*
G01X344650Y145944D02*
X345277Y145734D01*
X345747Y145209D01*
X346060Y144579D01*
X346295Y143739D01*
X346373Y142794D01*
X346295Y141849D01*
X346060Y141009D01*
X345747Y140379D01*
X345277Y139854D01*
X344650Y139644D01*
X344023Y139854D01*
X343553Y140379D01*
X343240Y141009D01*
X343005Y141849D01*
X342927Y142794D01*
X343005Y143739D01*
X343240Y144579D01*
X343553Y145209D01*
X344023Y145734D01*
X344650Y145944D01*
G01X363431Y247244D02*
G02I-9100J0D01*
G01X352625Y278501D02*
Y281701D01*
G01D02*
X346425D01*
G01D02*
Y278501D01*
G01D02*
X352625D01*
G01Y288501D02*
Y291701D01*
G01D02*
X346425D01*
G01D02*
Y288501D01*
G01D02*
X352625D01*
G01Y282501D02*
Y285701D01*
G01D02*
X346425D01*
G01D02*
Y282501D01*
G01D02*
X352625D01*
G01Y292501D02*
Y295701D01*
G01D02*
X346425D01*
G01D02*
Y292501D01*
G01D02*
X352625D01*
G01Y296501D02*
Y299701D01*
G01X346425Y296501D02*
X352625D01*
G01X346425Y299701D02*
Y296501D01*
G01X342995Y300283D02*
X349195D01*
G01D02*
Y303483D01*
G01D02*
X342995D01*
G01D02*
Y300283D01*
G01X352625Y299701D02*
X346425D01*
G01X352625Y304501D02*
Y307701D01*
G01D02*
X346425D01*
G01D02*
Y304501D01*
G01D02*
X352625D01*
G01X352397Y312502D02*
Y315702D01*
G01X346197D02*
Y312502D01*
G01D02*
X352397D01*
G01X352625Y308501D02*
Y311701D01*
G01X346425Y308501D02*
X352625D01*
G01Y311701D02*
X346425D01*
G01D02*
Y308501D01*
G01X348170Y327876D02*
Y334476D01*
G01X340670Y334576D02*
Y327776D01*
G01D02*
X355670D01*
G01X352867Y319830D02*
X346667D01*
G01D02*
Y316630D01*
G01D02*
X352867D01*
G01D02*
Y319830D01*
G01X352397Y315702D02*
X346197D01*
G01X363431Y349606D02*
G02I-9100J0D01*
G01X347245Y339156D02*
X347475Y339311D01*
X347743Y339414D01*
X348050D01*
X348395Y339259D01*
X348663Y339001D01*
X348855Y338691D01*
X349008Y338174D01*
X349046Y337709D01*
X348970Y337244D01*
X348855Y336934D01*
X348625Y336624D01*
X348356Y336417D01*
X348088Y336314D01*
X347820D01*
X347551Y336417D01*
X347321Y336572D01*
X347130Y336779D01*
G01X345831Y336934D02*
X345601Y336572D01*
X345295Y336366D01*
X344950Y336314D01*
X344643Y336366D01*
X344336Y336624D01*
X344145Y336934D01*
X344106Y337244D01*
X344183Y337606D01*
X344451Y337864D01*
X344720Y337967D01*
X345065D01*
G01X344720D02*
X344490Y338122D01*
X344298Y338381D01*
X344221Y338691D01*
X344298Y339001D01*
X344490Y339259D01*
X344835Y339414D01*
X345180Y339362D01*
X345525Y339156D01*
G01X341428Y336314D02*
Y339414D01*
X342846Y337192D01*
X340930D01*
G01X355670Y334576D02*
X340670D01*
G01X350375Y550538D02*
Y553638D01*
X349416D01*
X349110Y553483D01*
X348918Y553276D01*
X348841Y552863D01*
X348918Y552450D01*
X349148Y552191D01*
X349416Y552036D01*
X350375D01*
G01X349416D02*
X348841Y550538D01*
G01X346585D02*
X346508Y551210D01*
X346393Y551778D01*
X346240Y552295D01*
X346048Y552863D01*
X345741Y553638D01*
X347275D01*
G01X343408D02*
X343715Y553535D01*
X343945Y553276D01*
X344098Y552966D01*
X344213Y552553D01*
X344251Y552088D01*
X344213Y551623D01*
X344098Y551210D01*
X343945Y550900D01*
X343715Y550641D01*
X343408Y550538D01*
X343101Y550641D01*
X342871Y550900D01*
X342718Y551210D01*
X342603Y551623D01*
X342565Y552088D01*
X342603Y552553D01*
X342718Y552966D01*
X342871Y553276D01*
X343101Y553535D01*
X343408Y553638D01*
G01X341036Y553121D02*
X340806Y553431D01*
X340538Y553586D01*
X340231Y553638D01*
X339848Y553535D01*
X339580Y553276D01*
X339503Y552966D01*
X339541Y552656D01*
X339695Y552398D01*
X340461Y551881D01*
X340806Y551520D01*
X341036Y551003D01*
X341113Y550538D01*
X339503D01*
G01X350375Y558717D02*
Y561817D01*
X349416D01*
X349110Y561662D01*
X348918Y561455D01*
X348841Y561042D01*
X348918Y560629D01*
X349148Y560370D01*
X349416Y560215D01*
X350375D01*
G01X349416D02*
X348841Y558717D01*
G01X346585D02*
X346508Y559389D01*
X346393Y559957D01*
X346240Y560474D01*
X346048Y561042D01*
X345741Y561817D01*
X347275D01*
G01X343408Y558717D02*
Y561817D01*
X343868Y561197D01*
G01Y558717D02*
X342948D01*
G01X340308Y561817D02*
X340615Y561714D01*
X340845Y561455D01*
X340998Y561145D01*
X341113Y560732D01*
X341151Y560267D01*
X341113Y559802D01*
X340998Y559389D01*
X340845Y559079D01*
X340615Y558820D01*
X340308Y558717D01*
X340001Y558820D01*
X339771Y559079D01*
X339618Y559389D01*
X339503Y559802D01*
X339465Y560267D01*
X339503Y560732D01*
X339618Y561145D01*
X339771Y561455D01*
X340001Y561714D01*
X340308Y561817D01*
G01X350375Y554717D02*
Y557817D01*
X349416D01*
X349110Y557662D01*
X348918Y557455D01*
X348841Y557042D01*
X348918Y556629D01*
X349148Y556370D01*
X349416Y556215D01*
X350375D01*
G01X349416D02*
X348841Y554717D01*
G01X346585D02*
X346508Y555389D01*
X346393Y555957D01*
X346240Y556474D01*
X346048Y557042D01*
X345741Y557817D01*
X347275D01*
G01X343408Y554717D02*
Y557817D01*
X343868Y557197D01*
G01Y554717D02*
X342948D01*
G01X340308D02*
X340040Y554769D01*
X339733Y554924D01*
X339541Y555182D01*
X339465Y555544D01*
X339541Y555905D01*
X339771Y556215D01*
X340116Y556370D01*
X340500D01*
X340730Y556474D01*
X340921Y556732D01*
X340998Y557094D01*
X340883Y557455D01*
X340615Y557714D01*
X340308Y557817D01*
X340001Y557714D01*
X339733Y557455D01*
X339618Y557094D01*
X339695Y556732D01*
X339886Y556474D01*
X340116Y556370D01*
X340500D01*
X340845Y556215D01*
X341075Y555905D01*
X341151Y555544D01*
X341075Y555182D01*
X340883Y554924D01*
X340576Y554769D01*
X340308Y554717D01*
G01X350375Y562717D02*
Y565817D01*
X349416D01*
X349110Y565662D01*
X348918Y565455D01*
X348841Y565042D01*
X348918Y564629D01*
X349148Y564370D01*
X349416Y564215D01*
X350375D01*
G01X349416D02*
X348841Y562717D01*
G01X346585D02*
X346508Y563389D01*
X346393Y563957D01*
X346240Y564474D01*
X346048Y565042D01*
X345741Y565817D01*
X347275D01*
G01X343408Y562717D02*
Y565817D01*
X343868Y565197D01*
G01Y562717D02*
X342948D01*
G01X340308D02*
Y565817D01*
X340768Y565197D01*
G01Y562717D02*
X339848D01*
G01X338420Y594150D02*
Y580960D01*
G01X359833Y580922D02*
Y578700D01*
X359680Y578235D01*
X359373Y577925D01*
X358990Y577822D01*
X358607Y577925D01*
X358300Y578235D01*
X358147Y578700D01*
Y580922D01*
G01X356618Y579114D02*
X356350Y579475D01*
X356120Y579682D01*
X355813Y579785D01*
X355545Y579682D01*
X355353Y579475D01*
X355200Y579165D01*
X355162Y578804D01*
X355200Y578494D01*
X355353Y578184D01*
X355583Y577925D01*
X355852Y577822D01*
X356158Y577925D01*
X356427Y578235D01*
X356580Y578700D01*
X356618Y579217D01*
X356542Y579889D01*
X356427Y580250D01*
X356235Y580612D01*
X355967Y580870D01*
X355698Y580922D01*
X355430Y580819D01*
X355238Y580560D01*
G01X352330Y577822D02*
Y580922D01*
X353748Y578700D01*
X351832D01*
G01X350375Y578717D02*
Y581817D01*
X349416D01*
X349110Y581662D01*
X348918Y581455D01*
X348841Y581042D01*
X348918Y580629D01*
X349148Y580370D01*
X349416Y580215D01*
X350375D01*
G01X349416D02*
X348841Y578717D01*
G01X346585D02*
X346508Y579389D01*
X346393Y579957D01*
X346240Y580474D01*
X346048Y581042D01*
X345741Y581817D01*
X347275D01*
G01X343408Y578717D02*
Y581817D01*
X343868Y581197D01*
G01Y578717D02*
X342948D01*
G01X341151Y579182D02*
X340921Y578924D01*
X340653Y578769D01*
X340308Y578717D01*
X339963Y578820D01*
X339695Y579027D01*
X339503Y579389D01*
X339465Y579802D01*
X339541Y580215D01*
X339733Y580474D01*
X340001Y580680D01*
X340270Y580732D01*
X340538Y580680D01*
X340883Y580474D01*
X340768Y581817D01*
X339733D01*
G01X350375Y574717D02*
Y577817D01*
X349416D01*
X349110Y577662D01*
X348918Y577455D01*
X348841Y577042D01*
X348918Y576629D01*
X349148Y576370D01*
X349416Y576215D01*
X350375D01*
G01X349416D02*
X348841Y574717D01*
G01X346585D02*
X346508Y575389D01*
X346393Y575957D01*
X346240Y576474D01*
X346048Y577042D01*
X345741Y577817D01*
X347275D01*
G01X343408Y574717D02*
Y577817D01*
X343868Y577197D01*
G01Y574717D02*
X342948D01*
G01X339848D02*
Y577817D01*
X341266Y575595D01*
X339350D01*
G01X350375Y570717D02*
Y573817D01*
X349416D01*
X349110Y573662D01*
X348918Y573455D01*
X348841Y573042D01*
X348918Y572629D01*
X349148Y572370D01*
X349416Y572215D01*
X350375D01*
G01X349416D02*
X348841Y570717D01*
G01X346585D02*
X346508Y571389D01*
X346393Y571957D01*
X346240Y572474D01*
X346048Y573042D01*
X345741Y573817D01*
X347275D01*
G01X343408Y570717D02*
Y573817D01*
X343868Y573197D01*
G01Y570717D02*
X342948D01*
G01X341151Y571337D02*
X340921Y570975D01*
X340615Y570769D01*
X340270Y570717D01*
X339963Y570769D01*
X339656Y571027D01*
X339465Y571337D01*
X339426Y571647D01*
X339503Y572009D01*
X339771Y572267D01*
X340040Y572370D01*
X340385D01*
G01X340040D02*
X339810Y572525D01*
X339618Y572784D01*
X339541Y573094D01*
X339618Y573404D01*
X339810Y573662D01*
X340155Y573817D01*
X340500Y573765D01*
X340845Y573559D01*
G01X350375Y566717D02*
Y569817D01*
X349416D01*
X349110Y569662D01*
X348918Y569455D01*
X348841Y569042D01*
X348918Y568629D01*
X349148Y568370D01*
X349416Y568215D01*
X350375D01*
G01X349416D02*
X348841Y566717D01*
G01X346585D02*
X346508Y567389D01*
X346393Y567957D01*
X346240Y568474D01*
X346048Y569042D01*
X345741Y569817D01*
X347275D01*
G01X343408Y566717D02*
Y569817D01*
X343868Y569197D01*
G01Y566717D02*
X342948D01*
G01X341036Y569300D02*
X340806Y569610D01*
X340538Y569765D01*
X340231Y569817D01*
X339848Y569714D01*
X339580Y569455D01*
X339503Y569145D01*
X339541Y568835D01*
X339695Y568577D01*
X340461Y568060D01*
X340806Y567699D01*
X341036Y567182D01*
X341113Y566717D01*
X339503D01*
G01X338370Y594150D02*
X338420D01*
G01X350375Y582717D02*
Y585817D01*
X349416D01*
X349110Y585662D01*
X348918Y585455D01*
X348841Y585042D01*
X348918Y584629D01*
X349148Y584370D01*
X349416Y584215D01*
X350375D01*
G01X349416D02*
X348841Y582717D01*
G01X346585D02*
X346508Y583389D01*
X346393Y583957D01*
X346240Y584474D01*
X346048Y585042D01*
X345741Y585817D01*
X347275D01*
G01X343408Y582717D02*
Y585817D01*
X343868Y585197D01*
G01Y582717D02*
X342948D01*
G01X341036Y584009D02*
X340768Y584370D01*
X340538Y584577D01*
X340231Y584680D01*
X339963Y584577D01*
X339771Y584370D01*
X339618Y584060D01*
X339580Y583699D01*
X339618Y583389D01*
X339771Y583079D01*
X340001Y582820D01*
X340270Y582717D01*
X340576Y582820D01*
X340845Y583130D01*
X340998Y583595D01*
X341036Y584112D01*
X340960Y584784D01*
X340845Y585145D01*
X340653Y585507D01*
X340385Y585765D01*
X340116Y585817D01*
X339848Y585714D01*
X339656Y585455D01*
G01X350375Y586717D02*
Y589817D01*
X349416D01*
X349110Y589662D01*
X348918Y589455D01*
X348841Y589042D01*
X348918Y588629D01*
X349148Y588370D01*
X349416Y588215D01*
X350375D01*
G01X349416D02*
X348841Y586717D01*
G01X346585D02*
X346508Y587389D01*
X346393Y587957D01*
X346240Y588474D01*
X346048Y589042D01*
X345741Y589817D01*
X347275D01*
G01X343408Y586717D02*
Y589817D01*
X343868Y589197D01*
G01Y586717D02*
X342948D01*
G01X340385D02*
X340308Y587389D01*
X340193Y587957D01*
X340040Y588474D01*
X339848Y589042D01*
X339541Y589817D01*
X341075D01*
G01X350840Y590714D02*
Y593814D01*
X349881D01*
X349575Y593659D01*
X349383Y593452D01*
X349306Y593039D01*
X349383Y592626D01*
X349613Y592367D01*
X349881Y592212D01*
X350840D01*
G01X349881D02*
X349306Y590714D01*
G01X347625Y591076D02*
X347356Y590817D01*
X347050Y590714D01*
X346743Y590817D01*
X346475Y591127D01*
X346283Y591592D01*
X346206Y592057D01*
Y592626D01*
X346283Y593091D01*
X346475Y593504D01*
X346705Y593711D01*
X346973Y593814D01*
X347280Y593711D01*
X347510Y593504D01*
X347663Y593194D01*
X347740Y592781D01*
X347663Y592419D01*
X347471Y592057D01*
X347241Y591851D01*
X346973Y591799D01*
X346666Y591902D01*
X346436Y592161D01*
X346206Y592626D01*
G01X343950Y590714D02*
X343873Y591386D01*
X343758Y591954D01*
X343605Y592471D01*
X343413Y593039D01*
X343106Y593814D01*
X344640D01*
G01X340773D02*
X341080Y593711D01*
X341310Y593452D01*
X341463Y593142D01*
X341578Y592729D01*
X341616Y592264D01*
X341578Y591799D01*
X341463Y591386D01*
X341310Y591076D01*
X341080Y590817D01*
X340773Y590714D01*
X340466Y590817D01*
X340236Y591076D01*
X340083Y591386D01*
X339968Y591799D01*
X339930Y592264D01*
X339968Y592729D01*
X340083Y593142D01*
X340236Y593452D01*
X340466Y593711D01*
X340773Y593814D01*
G01X340968Y661462D02*
G02I-1000J0D01*
G01X341840Y667056D02*
Y698256D01*
G01X353250Y706987D02*
X356350D01*
Y707946D01*
X356195Y708252D01*
X355988Y708444D01*
X355575Y708521D01*
X355162Y708444D01*
X354903Y708214D01*
X354748Y707946D01*
Y706987D01*
G01Y707946D02*
X353250Y708521D01*
G01Y710854D02*
X356350D01*
X355730Y710394D01*
G01X353250D02*
Y711314D01*
G01Y713954D02*
X356350D01*
X355730Y713494D01*
G01X353250D02*
Y714414D01*
G01X353612Y716402D02*
X353353Y716671D01*
X353250Y716977D01*
X353353Y717284D01*
X353663Y717552D01*
X354128Y717744D01*
X354593Y717821D01*
X355162D01*
X355627Y717744D01*
X356040Y717552D01*
X356247Y717322D01*
X356350Y717054D01*
X356247Y716747D01*
X356040Y716517D01*
X355730Y716364D01*
X355317Y716287D01*
X354955Y716364D01*
X354593Y716556D01*
X354387Y716786D01*
X354335Y717054D01*
X354438Y717361D01*
X354697Y717591D01*
X355162Y717821D01*
G01X354542Y719426D02*
X354903Y719694D01*
X355110Y719924D01*
X355213Y720231D01*
X355110Y720499D01*
X354903Y720691D01*
X354593Y720844D01*
X354232Y720882D01*
X353922Y720844D01*
X353612Y720691D01*
X353353Y720461D01*
X353250Y720192D01*
X353353Y719886D01*
X353663Y719617D01*
X354128Y719464D01*
X354645Y719426D01*
X355317Y719502D01*
X355678Y719617D01*
X356040Y719809D01*
X356298Y720077D01*
X356350Y720346D01*
X356247Y720614D01*
X355988Y720806D01*
G01X346780Y709607D02*
X349880D01*
Y710566D01*
X349725Y710872D01*
X349518Y711064D01*
X349105Y711141D01*
X348692Y711064D01*
X348433Y710834D01*
X348278Y710566D01*
Y709607D01*
G01Y710566D02*
X346780Y711141D01*
G01Y713474D02*
X346832Y713742D01*
X346987Y714049D01*
X347245Y714241D01*
X347607Y714317D01*
X347968Y714241D01*
X348278Y714011D01*
X348433Y713666D01*
Y713282D01*
X348537Y713052D01*
X348795Y712861D01*
X349157Y712784D01*
X349518Y712899D01*
X349777Y713167D01*
X349880Y713474D01*
X349777Y713781D01*
X349518Y714049D01*
X349157Y714164D01*
X348795Y714087D01*
X348537Y713896D01*
X348433Y713666D01*
Y713282D01*
X348278Y712937D01*
X347968Y712707D01*
X347607Y712631D01*
X347245Y712707D01*
X346987Y712899D01*
X346832Y713206D01*
X346780Y713474D01*
G01Y716574D02*
X349880D01*
X349260Y716114D01*
G01X346780D02*
Y717034D01*
G01X349363Y718946D02*
X349673Y719176D01*
X349828Y719444D01*
X349880Y719751D01*
X349777Y720134D01*
X349518Y720402D01*
X349208Y720479D01*
X348898Y720441D01*
X348640Y720287D01*
X348123Y719521D01*
X347762Y719176D01*
X347245Y718946D01*
X346780Y718869D01*
Y720479D01*
G01X349027Y737972D02*
Y741072D01*
X348068D01*
X347762Y740917D01*
X347570Y740710D01*
X347493Y740297D01*
X347570Y739884D01*
X347800Y739625D01*
X348068Y739470D01*
X349027D01*
G01X348068D02*
X347493Y737972D01*
G01X345812Y738334D02*
X345543Y738075D01*
X345237Y737972D01*
X344930Y738075D01*
X344662Y738385D01*
X344470Y738850D01*
X344393Y739315D01*
Y739884D01*
X344470Y740349D01*
X344662Y740762D01*
X344892Y740969D01*
X345160Y741072D01*
X345467Y740969D01*
X345697Y740762D01*
X345850Y740452D01*
X345927Y740039D01*
X345850Y739677D01*
X345658Y739315D01*
X345428Y739109D01*
X345160Y739057D01*
X344853Y739160D01*
X344623Y739419D01*
X344393Y739884D01*
G01X342903Y738592D02*
X342673Y738230D01*
X342367Y738024D01*
X342022Y737972D01*
X341715Y738024D01*
X341408Y738282D01*
X341217Y738592D01*
X341178Y738902D01*
X341255Y739264D01*
X341523Y739522D01*
X341792Y739625D01*
X342137D01*
G01X341792D02*
X341562Y739780D01*
X341370Y740039D01*
X341293Y740349D01*
X341370Y740659D01*
X341562Y740917D01*
X341907Y741072D01*
X342252Y741020D01*
X342597Y740814D01*
G01X338960Y741072D02*
X339267Y740969D01*
X339497Y740710D01*
X339650Y740400D01*
X339765Y739987D01*
X339803Y739522D01*
X339765Y739057D01*
X339650Y738644D01*
X339497Y738334D01*
X339267Y738075D01*
X338960Y737972D01*
X338653Y738075D01*
X338423Y738334D01*
X338270Y738644D01*
X338155Y739057D01*
X338117Y739522D01*
X338155Y739987D01*
X338270Y740400D01*
X338423Y740710D01*
X338653Y740969D01*
X338960Y741072D01*
G01X347417Y753913D02*
X347647Y754068D01*
X347915Y754171D01*
X348222D01*
X348567Y754016D01*
X348835Y753758D01*
X349027Y753448D01*
X349180Y752931D01*
X349218Y752466D01*
X349142Y752001D01*
X349027Y751691D01*
X348797Y751381D01*
X348528Y751174D01*
X348260Y751071D01*
X347992D01*
X347723Y751174D01*
X347493Y751329D01*
X347302Y751536D01*
G01X345888Y752363D02*
X345620Y752724D01*
X345390Y752931D01*
X345083Y753034D01*
X344815Y752931D01*
X344623Y752724D01*
X344470Y752414D01*
X344432Y752053D01*
X344470Y751743D01*
X344623Y751433D01*
X344853Y751174D01*
X345122Y751071D01*
X345428Y751174D01*
X345697Y751484D01*
X345850Y751949D01*
X345888Y752466D01*
X345812Y753138D01*
X345697Y753499D01*
X345505Y753861D01*
X345237Y754119D01*
X344968Y754171D01*
X344700Y754068D01*
X344508Y753809D01*
G01X342137Y751071D02*
X342060Y751743D01*
X341945Y752311D01*
X341792Y752828D01*
X341600Y753396D01*
X341293Y754171D01*
X342827D01*
G01X339803Y751536D02*
X339573Y751278D01*
X339305Y751123D01*
X338960Y751071D01*
X338615Y751174D01*
X338347Y751381D01*
X338155Y751743D01*
X338117Y752156D01*
X338193Y752569D01*
X338385Y752828D01*
X338653Y753034D01*
X338922Y753086D01*
X339190Y753034D01*
X339535Y752828D01*
X339420Y754171D01*
X338385D01*
G01X349027Y746486D02*
Y749586D01*
X348068D01*
X347762Y749431D01*
X347570Y749224D01*
X347493Y748811D01*
X347570Y748398D01*
X347800Y748139D01*
X348068Y747984D01*
X349027D01*
G01X348068D02*
X347493Y746486D01*
G01X345812Y746848D02*
X345543Y746589D01*
X345237Y746486D01*
X344930Y746589D01*
X344662Y746899D01*
X344470Y747364D01*
X344393Y747829D01*
Y748398D01*
X344470Y748863D01*
X344662Y749276D01*
X344892Y749483D01*
X345160Y749586D01*
X345467Y749483D01*
X345697Y749276D01*
X345850Y748966D01*
X345927Y748553D01*
X345850Y748191D01*
X345658Y747829D01*
X345428Y747623D01*
X345160Y747571D01*
X344853Y747674D01*
X344623Y747933D01*
X344393Y748398D01*
G01X342788Y749069D02*
X342558Y749379D01*
X342290Y749534D01*
X341983Y749586D01*
X341600Y749483D01*
X341332Y749224D01*
X341255Y748914D01*
X341293Y748604D01*
X341447Y748346D01*
X342213Y747829D01*
X342558Y747468D01*
X342788Y746951D01*
X342865Y746486D01*
X341255D01*
G01X338960D02*
Y749586D01*
X339420Y748966D01*
G01Y746486D02*
X338500D01*
G01X349027Y742065D02*
Y745165D01*
X348068D01*
X347762Y745010D01*
X347570Y744803D01*
X347493Y744390D01*
X347570Y743977D01*
X347800Y743718D01*
X348068Y743563D01*
X349027D01*
G01X348068D02*
X347493Y742065D01*
G01X345812Y742427D02*
X345543Y742168D01*
X345237Y742065D01*
X344930Y742168D01*
X344662Y742478D01*
X344470Y742943D01*
X344393Y743408D01*
Y743977D01*
X344470Y744442D01*
X344662Y744855D01*
X344892Y745062D01*
X345160Y745165D01*
X345467Y745062D01*
X345697Y744855D01*
X345850Y744545D01*
X345927Y744132D01*
X345850Y743770D01*
X345658Y743408D01*
X345428Y743202D01*
X345160Y743150D01*
X344853Y743253D01*
X344623Y743512D01*
X344393Y743977D01*
G01X342788Y744648D02*
X342558Y744958D01*
X342290Y745113D01*
X341983Y745165D01*
X341600Y745062D01*
X341332Y744803D01*
X341255Y744493D01*
X341293Y744183D01*
X341447Y743925D01*
X342213Y743408D01*
X342558Y743047D01*
X342788Y742530D01*
X342865Y742065D01*
X341255D01*
G01X338500D02*
Y745165D01*
X339918Y742943D01*
X338002D01*
G01X349027Y755073D02*
Y758173D01*
X348068D01*
X347762Y758018D01*
X347570Y757811D01*
X347493Y757398D01*
X347570Y756985D01*
X347800Y756726D01*
X348068Y756571D01*
X349027D01*
G01X348068D02*
X347493Y755073D01*
G01X345812Y755435D02*
X345543Y755176D01*
X345237Y755073D01*
X344930Y755176D01*
X344662Y755486D01*
X344470Y755951D01*
X344393Y756416D01*
Y756985D01*
X344470Y757450D01*
X344662Y757863D01*
X344892Y758070D01*
X345160Y758173D01*
X345467Y758070D01*
X345697Y757863D01*
X345850Y757553D01*
X345927Y757140D01*
X345850Y756778D01*
X345658Y756416D01*
X345428Y756210D01*
X345160Y756158D01*
X344853Y756261D01*
X344623Y756520D01*
X344393Y756985D01*
G01X342060Y758173D02*
X342367Y758070D01*
X342597Y757811D01*
X342750Y757501D01*
X342865Y757088D01*
X342903Y756623D01*
X342865Y756158D01*
X342750Y755745D01*
X342597Y755435D01*
X342367Y755176D01*
X342060Y755073D01*
X341753Y755176D01*
X341523Y755435D01*
X341370Y755745D01*
X341255Y756158D01*
X341217Y756623D01*
X341255Y757088D01*
X341370Y757501D01*
X341523Y757811D01*
X341753Y758070D01*
X342060Y758173D01*
G01X339612Y755435D02*
X339343Y755176D01*
X339037Y755073D01*
X338730Y755176D01*
X338462Y755486D01*
X338270Y755951D01*
X338193Y756416D01*
Y756985D01*
X338270Y757450D01*
X338462Y757863D01*
X338692Y758070D01*
X338960Y758173D01*
X339267Y758070D01*
X339497Y757863D01*
X339650Y757553D01*
X339727Y757140D01*
X339650Y756778D01*
X339458Y756416D01*
X339228Y756210D01*
X338960Y756158D01*
X338653Y756261D01*
X338423Y756520D01*
X338193Y756985D01*
G01X359093Y-237697D02*
X359693Y-236897D01*
X360393Y-236497D01*
X361193Y-236364D01*
X362193Y-236631D01*
X362893Y-237297D01*
X363093Y-238097D01*
X362993Y-238898D01*
X362593Y-239564D01*
X360593Y-240897D01*
X359693Y-241831D01*
X359093Y-243164D01*
X358893Y-244364D01*
X363093D01*
G01X368993Y-236364D02*
X368193Y-236631D01*
X367593Y-237297D01*
X367193Y-238097D01*
X366893Y-239164D01*
X366793Y-240364D01*
X366893Y-241564D01*
X367193Y-242631D01*
X367593Y-243431D01*
X368193Y-244097D01*
X368993Y-244364D01*
X369793Y-244097D01*
X370393Y-243431D01*
X370793Y-242631D01*
X371093Y-241564D01*
X371193Y-240364D01*
X371093Y-239164D01*
X370793Y-238097D01*
X370393Y-237297D01*
X369793Y-236631D01*
X368993Y-236364D01*
G01X376993Y-244364D02*
Y-236364D01*
X375793Y-237964D01*
G01Y-244364D02*
X378193D01*
G01X383093Y-237697D02*
X383693Y-236897D01*
X384393Y-236497D01*
X385193Y-236364D01*
X386193Y-236631D01*
X386893Y-237297D01*
X387093Y-238097D01*
X386993Y-238898D01*
X386593Y-239564D01*
X384593Y-240897D01*
X383693Y-241831D01*
X383093Y-243164D01*
X382893Y-244364D01*
X387093D01*
G01X391193Y-244631D02*
X394793Y-236364D01*
G01X400993Y-244364D02*
Y-236364D01*
X399793Y-237964D01*
G01Y-244364D02*
X402193D01*
G01X408993Y-236364D02*
X408193Y-236631D01*
X407593Y-237297D01*
X407193Y-238097D01*
X406893Y-239164D01*
X406793Y-240364D01*
X406893Y-241564D01*
X407193Y-242631D01*
X407593Y-243431D01*
X408193Y-244097D01*
X408993Y-244364D01*
X409793Y-244097D01*
X410393Y-243431D01*
X410793Y-242631D01*
X411093Y-241564D01*
X411193Y-240364D01*
X411093Y-239164D01*
X410793Y-238097D01*
X410393Y-237297D01*
X409793Y-236631D01*
X408993Y-236364D01*
G01X415193Y-244631D02*
X418793Y-236364D01*
G01X422793Y-242764D02*
X423393Y-243697D01*
X424193Y-244231D01*
X425093Y-244364D01*
X425893Y-244231D01*
X426693Y-243564D01*
X427193Y-242764D01*
X427293Y-241964D01*
X427093Y-241031D01*
X426393Y-240364D01*
X425693Y-240097D01*
X424793D01*
G01X425693D02*
X426293Y-239697D01*
X426793Y-239031D01*
X426993Y-238231D01*
X426793Y-237431D01*
X426293Y-236764D01*
X425393Y-236364D01*
X424493Y-236497D01*
X423593Y-237031D01*
G01X432993Y-244364D02*
Y-236364D01*
X431793Y-237964D01*
G01Y-244364D02*
X434193D01*
G01X358793Y-219364D02*
Y-211364D01*
X360793D01*
X361593Y-211764D01*
X362193Y-212297D01*
X362693Y-213097D01*
X363093Y-214031D01*
X363193Y-215364D01*
X363093Y-216697D01*
X362693Y-217631D01*
X362193Y-218431D01*
X361593Y-218964D01*
X360793Y-219364D01*
X358793D01*
G01X366493D02*
X368993Y-211364D01*
X371493Y-219364D01*
G01X370593Y-216564D02*
X367393D01*
G01X376993Y-211364D02*
Y-219364D01*
G01X374693Y-211364D02*
X379293D01*
G01X383093Y-216031D02*
X383793Y-215097D01*
X384393Y-214564D01*
X385193Y-214297D01*
X385893Y-214564D01*
X386393Y-215097D01*
X386793Y-215897D01*
X386893Y-216831D01*
X386793Y-217631D01*
X386393Y-218431D01*
X385793Y-219097D01*
X385093Y-219364D01*
X384293Y-219097D01*
X383593Y-218298D01*
X383193Y-217097D01*
X383093Y-215764D01*
X383293Y-214031D01*
X383593Y-213097D01*
X384093Y-212164D01*
X384793Y-211497D01*
X385493Y-211364D01*
X386193Y-211631D01*
X386693Y-212297D01*
G01X390393Y-219364D02*
Y-211364D01*
X392993Y-218031D01*
X395593Y-211364D01*
Y-219364D01*
G01X400993Y-211364D02*
Y-219364D01*
G01X398693Y-211364D02*
X403293D01*
G01X406893Y-219364D02*
Y-211364D01*
G01X411093D02*
Y-219364D01*
G01Y-215364D02*
X406893D01*
G01X414793Y-217764D02*
X415393Y-218697D01*
X416193Y-219231D01*
X417093Y-219364D01*
X417893Y-219231D01*
X418693Y-218564D01*
X419193Y-217764D01*
X419293Y-216964D01*
X419093Y-216031D01*
X418393Y-215364D01*
X417693Y-215097D01*
X416793D01*
G01X417693D02*
X418293Y-214697D01*
X418793Y-214031D01*
X418993Y-213231D01*
X418793Y-212431D01*
X418293Y-211764D01*
X417393Y-211364D01*
X416493Y-211497D01*
X415593Y-212031D01*
G01X422493Y-219364D02*
X424993Y-211364D01*
X427493Y-219364D01*
G01X426593Y-216564D02*
X423393D01*
G01X430793Y-219364D02*
Y-211364D01*
X432793D01*
X433593Y-211764D01*
X434193Y-212297D01*
X434693Y-213097D01*
X435093Y-214031D01*
X435193Y-215364D01*
X435093Y-216697D01*
X434693Y-217631D01*
X434193Y-218431D01*
X433593Y-218964D01*
X432793Y-219364D01*
X430793D01*
G01X440993Y-211364D02*
X440193Y-211631D01*
X439593Y-212297D01*
X439193Y-213097D01*
X438893Y-214164D01*
X438793Y-215364D01*
X438893Y-216564D01*
X439193Y-217631D01*
X439593Y-218431D01*
X440193Y-219097D01*
X440993Y-219364D01*
X441793Y-219097D01*
X442393Y-218431D01*
X442793Y-217631D01*
X443093Y-216564D01*
X443193Y-215364D01*
X443093Y-214164D01*
X442793Y-213097D01*
X442393Y-212297D01*
X441793Y-211631D01*
X440993Y-211364D01*
G01X388107Y130689D02*
Y136989D01*
X386148D01*
X385522Y136674D01*
X385130Y136254D01*
X384973Y135414D01*
X385130Y134574D01*
X385600Y134049D01*
X386148Y133734D01*
X388107D01*
G01X386148D02*
X384973Y130689D01*
G01X381415Y133524D02*
X378908D01*
X379143Y134259D01*
X379535Y134679D01*
X380083Y134889D01*
X380632Y134784D01*
X381102Y134469D01*
X381415Y133734D01*
X381572Y133104D01*
Y132474D01*
X381415Y131844D01*
X381023Y131214D01*
X380553Y130794D01*
X380005Y130689D01*
X379457Y130899D01*
X378908Y131529D01*
G01X375350Y134889D02*
X373940Y130689D01*
X372530Y134889D01*
G01X367640Y130479D02*
X367797Y130584D01*
Y130794D01*
X367640Y130899D01*
X367483Y130794D01*
Y130584D01*
X367640Y130479D01*
G01Y133314D02*
X367797Y133419D01*
Y133629D01*
X367640Y133734D01*
X367483Y133629D01*
Y133419D01*
X367640Y133314D01*
G01X363063Y130689D02*
Y136989D01*
X361497D01*
X360870Y136674D01*
X360400Y136254D01*
X360008Y135624D01*
X359695Y134889D01*
X359617Y133839D01*
X359695Y132789D01*
X360008Y132054D01*
X360400Y131424D01*
X360870Y131004D01*
X361497Y130689D01*
X363063D01*
G01X375802Y280536D02*
Y283636D01*
X374843D01*
X374537Y283481D01*
X374345Y283274D01*
X374268Y282861D01*
X374345Y282448D01*
X374575Y282189D01*
X374843Y282034D01*
X375802D01*
G01X374843D02*
X374268Y280536D01*
G01X371935D02*
Y283636D01*
X372395Y283016D01*
G01Y280536D02*
X371475D01*
G01X369563Y281828D02*
X369295Y282189D01*
X369065Y282396D01*
X368758Y282499D01*
X368490Y282396D01*
X368298Y282189D01*
X368145Y281879D01*
X368107Y281518D01*
X368145Y281208D01*
X368298Y280898D01*
X368528Y280639D01*
X368797Y280536D01*
X369103Y280639D01*
X369372Y280949D01*
X369525Y281414D01*
X369563Y281931D01*
X369487Y282603D01*
X369372Y282964D01*
X369180Y283326D01*
X368912Y283584D01*
X368643Y283636D01*
X368375Y283533D01*
X368183Y283274D01*
G01X366578Y281001D02*
X366348Y280743D01*
X366080Y280588D01*
X365735Y280536D01*
X365390Y280639D01*
X365122Y280846D01*
X364930Y281208D01*
X364892Y281621D01*
X364968Y282034D01*
X365160Y282293D01*
X365428Y282499D01*
X365697Y282551D01*
X365965Y282499D01*
X366310Y282293D01*
X366195Y283636D01*
X365160D01*
G01X375802Y276536D02*
Y279636D01*
X374843D01*
X374537Y279481D01*
X374345Y279274D01*
X374268Y278861D01*
X374345Y278448D01*
X374575Y278189D01*
X374843Y278034D01*
X375802D01*
G01X374843D02*
X374268Y276536D01*
G01X371935D02*
Y279636D01*
X372395Y279016D01*
G01Y276536D02*
X371475D01*
G01X368912D02*
X368835Y277208D01*
X368720Y277776D01*
X368567Y278293D01*
X368375Y278861D01*
X368068Y279636D01*
X369602D01*
G01X366463Y279119D02*
X366233Y279429D01*
X365965Y279584D01*
X365658Y279636D01*
X365275Y279533D01*
X365007Y279274D01*
X364930Y278964D01*
X364968Y278654D01*
X365122Y278396D01*
X365888Y277879D01*
X366233Y277518D01*
X366463Y277001D01*
X366540Y276536D01*
X364930D01*
G01X357030Y281917D02*
Y278717D01*
G01D02*
X363230D01*
G01D02*
Y281917D01*
G01X375802Y286536D02*
Y289636D01*
X374843D01*
X374537Y289481D01*
X374345Y289274D01*
X374268Y288861D01*
X374345Y288448D01*
X374575Y288189D01*
X374843Y288034D01*
X375802D01*
G01X374843D02*
X374268Y286536D01*
G01X371935D02*
Y289636D01*
X372395Y289016D01*
G01Y286536D02*
X371475D01*
G01X369678Y287001D02*
X369448Y286743D01*
X369180Y286588D01*
X368835Y286536D01*
X368490Y286639D01*
X368222Y286846D01*
X368030Y287208D01*
X367992Y287621D01*
X368068Y288034D01*
X368260Y288293D01*
X368528Y288499D01*
X368797Y288551D01*
X369065Y288499D01*
X369410Y288293D01*
X369295Y289636D01*
X368260D01*
G01X365735Y286536D02*
X365467Y286588D01*
X365160Y286743D01*
X364968Y287001D01*
X364892Y287363D01*
X364968Y287724D01*
X365198Y288034D01*
X365543Y288189D01*
X365927D01*
X366157Y288293D01*
X366348Y288551D01*
X366425Y288913D01*
X366310Y289274D01*
X366042Y289533D01*
X365735Y289636D01*
X365428Y289533D01*
X365160Y289274D01*
X365045Y288913D01*
X365122Y288551D01*
X365313Y288293D01*
X365543Y288189D01*
X365927D01*
X366272Y288034D01*
X366502Y287724D01*
X366578Y287363D01*
X366502Y287001D01*
X366310Y286743D01*
X366003Y286588D01*
X365735Y286536D01*
G01X363230Y291917D02*
X357030D01*
G01D02*
Y288717D01*
G01D02*
X363230D01*
G01D02*
Y291917D01*
G01Y285917D02*
X357030D01*
G01D02*
Y282717D01*
G01D02*
X363230D01*
G01D02*
Y285917D01*
G01X375802Y290536D02*
Y293636D01*
X374843D01*
X374537Y293481D01*
X374345Y293274D01*
X374268Y292861D01*
X374345Y292448D01*
X374575Y292189D01*
X374843Y292034D01*
X375802D01*
G01X374843D02*
X374268Y290536D01*
G01X371935D02*
Y293636D01*
X372395Y293016D01*
G01Y290536D02*
X371475D01*
G01X369678Y291001D02*
X369448Y290743D01*
X369180Y290588D01*
X368835Y290536D01*
X368490Y290639D01*
X368222Y290846D01*
X368030Y291208D01*
X367992Y291621D01*
X368068Y292034D01*
X368260Y292293D01*
X368528Y292499D01*
X368797Y292551D01*
X369065Y292499D01*
X369410Y292293D01*
X369295Y293636D01*
X368260D01*
G01X366387Y290898D02*
X366118Y290639D01*
X365812Y290536D01*
X365505Y290639D01*
X365237Y290949D01*
X365045Y291414D01*
X364968Y291879D01*
Y292448D01*
X365045Y292913D01*
X365237Y293326D01*
X365467Y293533D01*
X365735Y293636D01*
X366042Y293533D01*
X366272Y293326D01*
X366425Y293016D01*
X366502Y292603D01*
X366425Y292241D01*
X366233Y291879D01*
X366003Y291673D01*
X365735Y291621D01*
X365428Y291724D01*
X365198Y291983D01*
X364968Y292448D01*
G01X363230Y295917D02*
X357030D01*
G01D02*
Y292717D01*
G01D02*
X363230D01*
G01D02*
Y295917D01*
G01X375802Y294536D02*
Y297636D01*
X374843D01*
X374537Y297481D01*
X374345Y297274D01*
X374268Y296861D01*
X374345Y296448D01*
X374575Y296189D01*
X374843Y296034D01*
X375802D01*
G01X374843D02*
X374268Y294536D01*
G01X371935D02*
Y297636D01*
X372395Y297016D01*
G01Y294536D02*
X371475D01*
G01X369563Y295828D02*
X369295Y296189D01*
X369065Y296396D01*
X368758Y296499D01*
X368490Y296396D01*
X368298Y296189D01*
X368145Y295879D01*
X368107Y295518D01*
X368145Y295208D01*
X368298Y294898D01*
X368528Y294639D01*
X368797Y294536D01*
X369103Y294639D01*
X369372Y294949D01*
X369525Y295414D01*
X369563Y295931D01*
X369487Y296603D01*
X369372Y296964D01*
X369180Y297326D01*
X368912Y297584D01*
X368643Y297636D01*
X368375Y297533D01*
X368183Y297274D01*
G01X365275Y294536D02*
Y297636D01*
X366693Y295414D01*
X364777D01*
G01X357030Y299917D02*
Y296717D01*
G01D02*
X363230D01*
G01D02*
Y299917D01*
G01Y281917D02*
X357030D01*
G01X363230Y299917D02*
X357030D01*
G01X355670Y327776D02*
Y334576D01*
G01X471286Y377165D02*
G02X383783Y426925I-57900J0D01*
G01X372453Y555847D02*
X372683Y556002D01*
X372951Y556105D01*
X373258D01*
X373603Y555950D01*
X373871Y555692D01*
X374063Y555382D01*
X374216Y554865D01*
X374254Y554400D01*
X374178Y553935D01*
X374063Y553625D01*
X373833Y553315D01*
X373564Y553108D01*
X373296Y553005D01*
X373028D01*
X372759Y553108D01*
X372529Y553263D01*
X372338Y553470D01*
G01X371039D02*
X370809Y553212D01*
X370541Y553057D01*
X370196Y553005D01*
X369851Y553108D01*
X369583Y553315D01*
X369391Y553677D01*
X369353Y554090D01*
X369429Y554503D01*
X369621Y554762D01*
X369889Y554968D01*
X370158Y555020D01*
X370426Y554968D01*
X370771Y554762D01*
X370656Y556105D01*
X369621D01*
G01X367173Y553005D02*
X367096Y553677D01*
X366981Y554245D01*
X366828Y554762D01*
X366636Y555330D01*
X366329Y556105D01*
X367863D01*
G01X363996D02*
X364303Y556002D01*
X364533Y555743D01*
X364686Y555433D01*
X364801Y555020D01*
X364839Y554555D01*
X364801Y554090D01*
X364686Y553677D01*
X364533Y553367D01*
X364303Y553108D01*
X363996Y553005D01*
X363689Y553108D01*
X363459Y553367D01*
X363306Y553677D01*
X363191Y554090D01*
X363153Y554555D01*
X363191Y555020D01*
X363306Y555433D01*
X363459Y555743D01*
X363689Y556002D01*
X363996Y556105D01*
G01X374063Y557149D02*
Y560249D01*
X373104D01*
X372798Y560094D01*
X372606Y559887D01*
X372529Y559474D01*
X372606Y559061D01*
X372836Y558802D01*
X373104Y558647D01*
X374063D01*
G01X373104D02*
X372529Y557149D01*
G01X370273D02*
X370196Y557821D01*
X370081Y558389D01*
X369928Y558906D01*
X369736Y559474D01*
X369429Y560249D01*
X370963D01*
G01X367096D02*
X367403Y560146D01*
X367633Y559887D01*
X367786Y559577D01*
X367901Y559164D01*
X367939Y558699D01*
X367901Y558234D01*
X367786Y557821D01*
X367633Y557511D01*
X367403Y557252D01*
X367096Y557149D01*
X366789Y557252D01*
X366559Y557511D01*
X366406Y557821D01*
X366291Y558234D01*
X366253Y558699D01*
X366291Y559164D01*
X366406Y559577D01*
X366559Y559887D01*
X366789Y560146D01*
X367096Y560249D01*
G01X364724Y558441D02*
X364456Y558802D01*
X364226Y559009D01*
X363919Y559112D01*
X363651Y559009D01*
X363459Y558802D01*
X363306Y558492D01*
X363268Y558131D01*
X363306Y557821D01*
X363459Y557511D01*
X363689Y557252D01*
X363958Y557149D01*
X364264Y557252D01*
X364533Y557562D01*
X364686Y558027D01*
X364724Y558544D01*
X364648Y559216D01*
X364533Y559577D01*
X364341Y559939D01*
X364073Y560197D01*
X363804Y560249D01*
X363536Y560146D01*
X363344Y559887D01*
G01X374063Y561162D02*
Y564262D01*
X373104D01*
X372798Y564107D01*
X372606Y563900D01*
X372529Y563487D01*
X372606Y563074D01*
X372836Y562815D01*
X373104Y562660D01*
X374063D01*
G01X373104D02*
X372529Y561162D01*
G01X370273D02*
X370196Y561834D01*
X370081Y562402D01*
X369928Y562919D01*
X369736Y563487D01*
X369429Y564262D01*
X370963D01*
G01X367824Y563745D02*
X367594Y564055D01*
X367326Y564210D01*
X367019Y564262D01*
X366636Y564159D01*
X366368Y563900D01*
X366291Y563590D01*
X366329Y563280D01*
X366483Y563022D01*
X367249Y562505D01*
X367594Y562144D01*
X367824Y561627D01*
X367901Y561162D01*
X366291D01*
G01X364073D02*
X363996Y561834D01*
X363881Y562402D01*
X363728Y562919D01*
X363536Y563487D01*
X363229Y564262D01*
X364763D01*
G01X374063Y565162D02*
Y568262D01*
X373104D01*
X372798Y568107D01*
X372606Y567900D01*
X372529Y567487D01*
X372606Y567074D01*
X372836Y566815D01*
X373104Y566660D01*
X374063D01*
G01X373104D02*
X372529Y565162D01*
G01X370273D02*
X370196Y565834D01*
X370081Y566402D01*
X369928Y566919D01*
X369736Y567487D01*
X369429Y568262D01*
X370963D01*
G01X367824Y567745D02*
X367594Y568055D01*
X367326Y568210D01*
X367019Y568262D01*
X366636Y568159D01*
X366368Y567900D01*
X366291Y567590D01*
X366329Y567280D01*
X366483Y567022D01*
X367249Y566505D01*
X367594Y566144D01*
X367824Y565627D01*
X367901Y565162D01*
X366291D01*
G01X364724Y566454D02*
X364456Y566815D01*
X364226Y567022D01*
X363919Y567125D01*
X363651Y567022D01*
X363459Y566815D01*
X363306Y566505D01*
X363268Y566144D01*
X363306Y565834D01*
X363459Y565524D01*
X363689Y565265D01*
X363958Y565162D01*
X364264Y565265D01*
X364533Y565575D01*
X364686Y566040D01*
X364724Y566557D01*
X364648Y567229D01*
X364533Y567590D01*
X364341Y567952D01*
X364073Y568210D01*
X363804Y568262D01*
X363536Y568159D01*
X363344Y567900D01*
G01X374063Y569162D02*
Y572262D01*
X373104D01*
X372798Y572107D01*
X372606Y571900D01*
X372529Y571487D01*
X372606Y571074D01*
X372836Y570815D01*
X373104Y570660D01*
X374063D01*
G01X373104D02*
X372529Y569162D01*
G01X370273D02*
X370196Y569834D01*
X370081Y570402D01*
X369928Y570919D01*
X369736Y571487D01*
X369429Y572262D01*
X370963D01*
G01X367824Y571745D02*
X367594Y572055D01*
X367326Y572210D01*
X367019Y572262D01*
X366636Y572159D01*
X366368Y571900D01*
X366291Y571590D01*
X366329Y571280D01*
X366483Y571022D01*
X367249Y570505D01*
X367594Y570144D01*
X367824Y569627D01*
X367901Y569162D01*
X366291D01*
G01X364839Y569627D02*
X364609Y569369D01*
X364341Y569214D01*
X363996Y569162D01*
X363651Y569265D01*
X363383Y569472D01*
X363191Y569834D01*
X363153Y570247D01*
X363229Y570660D01*
X363421Y570919D01*
X363689Y571125D01*
X363958Y571177D01*
X364226Y571125D01*
X364571Y570919D01*
X364456Y572262D01*
X363421D01*
G01X374063Y573162D02*
Y576262D01*
X373104D01*
X372798Y576107D01*
X372606Y575900D01*
X372529Y575487D01*
X372606Y575074D01*
X372836Y574815D01*
X373104Y574660D01*
X374063D01*
G01X373104D02*
X372529Y573162D01*
G01X370273D02*
X370196Y573834D01*
X370081Y574402D01*
X369928Y574919D01*
X369736Y575487D01*
X369429Y576262D01*
X370963D01*
G01X367824Y575745D02*
X367594Y576055D01*
X367326Y576210D01*
X367019Y576262D01*
X366636Y576159D01*
X366368Y575900D01*
X366291Y575590D01*
X366329Y575280D01*
X366483Y575022D01*
X367249Y574505D01*
X367594Y574144D01*
X367824Y573627D01*
X367901Y573162D01*
X366291D01*
G01X363536D02*
Y576262D01*
X364954Y574040D01*
X363038D01*
G01X367554Y675441D02*
X367742D01*
Y653139D01*
X370199D01*
Y637255D01*
X380351D01*
Y618096D01*
X366514D01*
Y637173D01*
X370199D01*
G01X378705Y628034D02*
Y631134D01*
X377746D01*
X377440Y630979D01*
X377248Y630772D01*
X377171Y630359D01*
X377248Y629946D01*
X377478Y629687D01*
X377746Y629532D01*
X378705D01*
G01X377746D02*
X377171Y628034D01*
G01X374915D02*
X374838Y628706D01*
X374723Y629274D01*
X374570Y629791D01*
X374378Y630359D01*
X374071Y631134D01*
X375605D01*
G01X371738D02*
X372045Y631031D01*
X372275Y630772D01*
X372428Y630462D01*
X372543Y630049D01*
X372581Y629584D01*
X372543Y629119D01*
X372428Y628706D01*
X372275Y628396D01*
X372045Y628137D01*
X371738Y628034D01*
X371431Y628137D01*
X371201Y628396D01*
X371048Y628706D01*
X370933Y629119D01*
X370895Y629584D01*
X370933Y630049D01*
X371048Y630462D01*
X371201Y630772D01*
X371431Y631031D01*
X371738Y631134D01*
G01X368638Y628034D02*
X368370Y628086D01*
X368063Y628241D01*
X367871Y628499D01*
X367795Y628861D01*
X367871Y629222D01*
X368101Y629532D01*
X368446Y629687D01*
X368830D01*
X369060Y629791D01*
X369251Y630049D01*
X369328Y630411D01*
X369213Y630772D01*
X368945Y631031D01*
X368638Y631134D01*
X368331Y631031D01*
X368063Y630772D01*
X367948Y630411D01*
X368025Y630049D01*
X368216Y629791D01*
X368446Y629687D01*
X368830D01*
X369175Y629532D01*
X369405Y629222D01*
X369481Y628861D01*
X369405Y628499D01*
X369213Y628241D01*
X368906Y628086D01*
X368638Y628034D01*
G01X378705Y623707D02*
Y626807D01*
X377746D01*
X377440Y626652D01*
X377248Y626445D01*
X377171Y626032D01*
X377248Y625619D01*
X377478Y625360D01*
X377746Y625205D01*
X378705D01*
G01X377746D02*
X377171Y623707D01*
G01X374915D02*
X374838Y624379D01*
X374723Y624947D01*
X374570Y625464D01*
X374378Y626032D01*
X374071Y626807D01*
X375605D01*
G01X371738Y623707D02*
Y626807D01*
X372198Y626187D01*
G01Y623707D02*
X371278D01*
G01X369290Y624069D02*
X369021Y623810D01*
X368715Y623707D01*
X368408Y623810D01*
X368140Y624120D01*
X367948Y624585D01*
X367871Y625050D01*
Y625619D01*
X367948Y626084D01*
X368140Y626497D01*
X368370Y626704D01*
X368638Y626807D01*
X368945Y626704D01*
X369175Y626497D01*
X369328Y626187D01*
X369405Y625774D01*
X369328Y625412D01*
X369136Y625050D01*
X368906Y624844D01*
X368638Y624792D01*
X368331Y624895D01*
X368101Y625154D01*
X367871Y625619D01*
G01X378705Y619609D02*
Y622709D01*
X377746D01*
X377440Y622554D01*
X377248Y622347D01*
X377171Y621934D01*
X377248Y621521D01*
X377478Y621262D01*
X377746Y621107D01*
X378705D01*
G01X377746D02*
X377171Y619609D01*
G01X374915D02*
X374838Y620281D01*
X374723Y620849D01*
X374570Y621366D01*
X374378Y621934D01*
X374071Y622709D01*
X375605D01*
G01X371738D02*
X372045Y622606D01*
X372275Y622347D01*
X372428Y622037D01*
X372543Y621624D01*
X372581Y621159D01*
X372543Y620694D01*
X372428Y620281D01*
X372275Y619971D01*
X372045Y619712D01*
X371738Y619609D01*
X371431Y619712D01*
X371201Y619971D01*
X371048Y620281D01*
X370933Y620694D01*
X370895Y621159D01*
X370933Y621624D01*
X371048Y622037D01*
X371201Y622347D01*
X371431Y622606D01*
X371738Y622709D01*
G01X368638Y619609D02*
Y622709D01*
X369098Y622089D01*
G01Y619609D02*
X368178D01*
G01X360630Y635528D02*
Y638728D01*
G01X354430Y635528D02*
X360630D01*
G01X354430Y638728D02*
Y635528D01*
G01X360630Y638728D02*
X354430D01*
G01X360630Y643575D02*
Y646775D01*
G01X354430Y643575D02*
X360630D01*
G01X354430Y646775D02*
Y643575D01*
G01X360630Y639528D02*
Y642728D01*
G01X354430Y639528D02*
X360630D01*
G01X354430Y642728D02*
Y639528D01*
G01X360630Y642728D02*
X354430D01*
G01X360630Y659528D02*
Y662728D01*
G01X354430Y659528D02*
X360630D01*
G01X354430Y662728D02*
Y659528D01*
G01X360630Y655528D02*
Y658728D01*
G01X354430Y655528D02*
X360630D01*
G01X354430Y658728D02*
Y655528D01*
G01X360630Y658728D02*
X354430D01*
G01X360630Y651528D02*
Y654728D01*
G01X354430Y651528D02*
X360630D01*
G01X354430Y654728D02*
Y651528D01*
G01X360630Y654728D02*
X354430D01*
G01X360630Y647528D02*
Y650728D01*
G01X354430Y647528D02*
X360630D01*
G01X354430Y650728D02*
Y647528D01*
G01X360630Y650728D02*
X354430D01*
G01X360630Y646775D02*
X354430D01*
G01X373885Y688794D02*
X367554D01*
Y675441D01*
X376142D01*
Y688794D01*
X373885D01*
G01X357530Y666628D02*
Y663628D01*
G01X354430Y666728D02*
Y663528D01*
G01X360630D02*
Y666728D01*
G01X354430Y663528D02*
X360630D01*
G01Y666728D02*
X354430D01*
G01X360630Y671528D02*
Y674728D01*
G01X354430Y671528D02*
X360630D01*
G01X354430Y674728D02*
Y671528D01*
G01X360630Y674728D02*
X354430D01*
G01X360630Y667528D02*
Y670728D01*
G01X354430Y667528D02*
X360630D01*
G01X354430Y670728D02*
Y667528D01*
G01X360630Y670728D02*
X354430D01*
G01X360630Y662728D02*
X354430D01*
G01X360630Y687528D02*
Y690728D01*
G01X354430Y687528D02*
X360630D01*
G01X354430Y690728D02*
Y687528D01*
G01X360630Y690728D02*
X354430D01*
G01X360630Y683528D02*
Y686728D01*
G01X354430Y683528D02*
X360630D01*
G01X354430Y686728D02*
Y683528D01*
G01X360630Y686728D02*
X354430D01*
G01X360630Y679528D02*
Y682728D01*
G01X354430Y679528D02*
X360630D01*
G01X354430Y682728D02*
Y679528D01*
G01X360630Y682728D02*
X354430D01*
G01X360630Y675528D02*
Y678728D01*
G01X354430Y675528D02*
X360630D01*
G01X354430Y678728D02*
Y675528D01*
G01X360630Y678728D02*
X354430D01*
G01X368758Y684056D02*
X374958D01*
G01X368758Y687256D02*
Y684056D01*
G01X374958Y687256D02*
X368758D01*
G01Y683256D02*
Y680056D01*
G01X374958Y683256D02*
X368758D01*
G01Y680056D02*
X374958D01*
G01X368758Y676056D02*
X374958D01*
G01X368758Y679256D02*
Y676056D01*
G01X374958Y679256D02*
X368758D01*
G01X373497Y707349D02*
Y710449D01*
X372538D01*
X372232Y710294D01*
X372040Y710087D01*
X371963Y709674D01*
X372040Y709261D01*
X372270Y709002D01*
X372538Y708847D01*
X373497D01*
G01X372538D02*
X371963Y707349D01*
G01X369630D02*
Y710449D01*
X370090Y709829D01*
G01Y707349D02*
X369170D01*
G01X366070D02*
Y710449D01*
X367488Y708227D01*
X365572D01*
G01X364273Y707814D02*
X364043Y707556D01*
X363775Y707401D01*
X363430Y707349D01*
X363085Y707452D01*
X362817Y707659D01*
X362625Y708021D01*
X362587Y708434D01*
X362663Y708847D01*
X362855Y709106D01*
X363123Y709312D01*
X363392Y709364D01*
X363660Y709312D01*
X364005Y709106D01*
X363890Y710449D01*
X362855D01*
G01X360630Y699528D02*
Y702728D01*
G01X354430Y699528D02*
X360630D01*
G01X354430Y702728D02*
Y699528D01*
G01X360630Y702728D02*
X354430D01*
G01X360630Y695528D02*
Y698728D01*
G01X354430Y695528D02*
X360630D01*
G01X354430Y698728D02*
Y695528D01*
G01X360630Y698728D02*
X354430D01*
G01X360630Y691528D02*
Y694728D01*
G01X354430Y691528D02*
X360630D01*
G01X354430Y694728D02*
Y691528D01*
G01X360630Y694728D02*
X354430D01*
G01X355571Y725137D02*
Y721937D01*
G01X361771D02*
Y725137D01*
G01X355571Y721937D02*
X361771D01*
G01X367320Y715384D02*
X370520D01*
G01X367320Y721584D02*
Y715384D01*
G01X370520Y721584D02*
X367320D01*
G01X363320Y715384D02*
X366520D01*
G01D02*
Y721584D01*
G01X363320D02*
Y715384D01*
G01X366520Y721584D02*
X363320D01*
G01X361771Y737937D02*
Y741137D01*
G01X355571Y737937D02*
X361771D01*
G01X355571Y741137D02*
Y737937D01*
G01X358671Y738037D02*
Y741037D01*
G01X367903Y729222D02*
Y726022D01*
G01X374103Y729222D02*
X367903D01*
G01Y726022D02*
X374103D01*
G01X367811Y737859D02*
X374011D01*
G01X367811Y741059D02*
Y737859D01*
G01X374011Y737059D02*
X367811D01*
G01Y733859D02*
X374011D01*
G01X367811Y737059D02*
Y733859D01*
G01X361771Y737137D02*
X355571D01*
G01X361771Y733937D02*
Y737137D01*
G01X355571Y733937D02*
X361771D01*
G01X355571Y737137D02*
Y733937D01*
G01X374011Y733058D02*
X367811D01*
G01Y729860D02*
X374011D01*
G01X367811Y733058D02*
Y729860D01*
G01X355571Y729137D02*
Y725937D01*
G01X361771Y729137D02*
X355571D01*
G01X361771Y725937D02*
Y729137D01*
G01X355571Y725937D02*
X361771D01*
G01Y725137D02*
X355571D01*
G01X361771Y741137D02*
X355571D01*
G01X367811Y745059D02*
Y741859D01*
G01X374011Y745059D02*
X367811D01*
G01Y741859D02*
X374011D01*
G01X374097Y752440D02*
X374327Y752595D01*
X374595Y752698D01*
X374902D01*
X375247Y752543D01*
X375515Y752285D01*
X375707Y751975D01*
X375860Y751458D01*
X375898Y750993D01*
X375822Y750528D01*
X375707Y750218D01*
X375477Y749908D01*
X375208Y749701D01*
X374940Y749598D01*
X374672D01*
X374403Y749701D01*
X374173Y749856D01*
X373982Y750063D01*
G01X372568Y750890D02*
X372300Y751251D01*
X372070Y751458D01*
X371763Y751561D01*
X371495Y751458D01*
X371303Y751251D01*
X371150Y750941D01*
X371112Y750580D01*
X371150Y750270D01*
X371303Y749960D01*
X371533Y749701D01*
X371802Y749598D01*
X372108Y749701D01*
X372377Y750011D01*
X372530Y750476D01*
X372568Y750993D01*
X372492Y751665D01*
X372377Y752026D01*
X372185Y752388D01*
X371917Y752646D01*
X371648Y752698D01*
X371380Y752595D01*
X371188Y752336D01*
G01X369468Y750890D02*
X369200Y751251D01*
X368970Y751458D01*
X368663Y751561D01*
X368395Y751458D01*
X368203Y751251D01*
X368050Y750941D01*
X368012Y750580D01*
X368050Y750270D01*
X368203Y749960D01*
X368433Y749701D01*
X368702Y749598D01*
X369008Y749701D01*
X369277Y750011D01*
X369430Y750476D01*
X369468Y750993D01*
X369392Y751665D01*
X369277Y752026D01*
X369085Y752388D01*
X368817Y752646D01*
X368548Y752698D01*
X368280Y752595D01*
X368088Y752336D01*
G01X366483Y750063D02*
X366253Y749805D01*
X365985Y749650D01*
X365640Y749598D01*
X365295Y749701D01*
X365027Y749908D01*
X364835Y750270D01*
X364797Y750683D01*
X364873Y751096D01*
X365065Y751355D01*
X365333Y751561D01*
X365602Y751613D01*
X365870Y751561D01*
X366215Y751355D01*
X366100Y752698D01*
X365065D01*
G01X374011Y741059D02*
X367811D01*
G01X375707Y753697D02*
Y756797D01*
X374748D01*
X374442Y756642D01*
X374250Y756435D01*
X374173Y756022D01*
X374250Y755609D01*
X374480Y755350D01*
X374748Y755195D01*
X375707D01*
G01X374748D02*
X374173Y753697D01*
G01X372492Y754059D02*
X372223Y753800D01*
X371917Y753697D01*
X371610Y753800D01*
X371342Y754110D01*
X371150Y754575D01*
X371073Y755040D01*
Y755609D01*
X371150Y756074D01*
X371342Y756487D01*
X371572Y756694D01*
X371840Y756797D01*
X372147Y756694D01*
X372377Y756487D01*
X372530Y756177D01*
X372607Y755764D01*
X372530Y755402D01*
X372338Y755040D01*
X372108Y754834D01*
X371840Y754782D01*
X371533Y754885D01*
X371303Y755144D01*
X371073Y755609D01*
G01X369468Y756280D02*
X369238Y756590D01*
X368970Y756745D01*
X368663Y756797D01*
X368280Y756694D01*
X368012Y756435D01*
X367935Y756125D01*
X367973Y755815D01*
X368127Y755557D01*
X368893Y755040D01*
X369238Y754679D01*
X369468Y754162D01*
X369545Y753697D01*
X367935D01*
G01X365717D02*
X365640Y754369D01*
X365525Y754937D01*
X365372Y755454D01*
X365180Y756022D01*
X364873Y756797D01*
X366407D01*
G01X355571Y745137D02*
Y741937D01*
G01X361771Y745137D02*
X355571D01*
G01X361771Y741937D02*
Y745137D01*
G01X355571Y741937D02*
X361771D01*
G01X374097Y768560D02*
X374327Y768715D01*
X374595Y768818D01*
X374902D01*
X375247Y768663D01*
X375515Y768405D01*
X375707Y768095D01*
X375860Y767578D01*
X375898Y767113D01*
X375822Y766648D01*
X375707Y766338D01*
X375477Y766028D01*
X375208Y765821D01*
X374940Y765718D01*
X374672D01*
X374403Y765821D01*
X374173Y765976D01*
X373982Y766183D01*
G01X371917Y765718D02*
X371840Y766390D01*
X371725Y766958D01*
X371572Y767475D01*
X371380Y768043D01*
X371073Y768818D01*
X372607D01*
G01X368740D02*
X369047Y768715D01*
X369277Y768456D01*
X369430Y768146D01*
X369545Y767733D01*
X369583Y767268D01*
X369545Y766803D01*
X369430Y766390D01*
X369277Y766080D01*
X369047Y765821D01*
X368740Y765718D01*
X368433Y765821D01*
X368203Y766080D01*
X368050Y766390D01*
X367935Y766803D01*
X367897Y767268D01*
X367935Y767733D01*
X368050Y768146D01*
X368203Y768456D01*
X368433Y768715D01*
X368740Y768818D01*
G01X366368Y768301D02*
X366138Y768611D01*
X365870Y768766D01*
X365563Y768818D01*
X365180Y768715D01*
X364912Y768456D01*
X364835Y768146D01*
X364873Y767836D01*
X365027Y767578D01*
X365793Y767061D01*
X366138Y766700D01*
X366368Y766183D01*
X366445Y765718D01*
X364835D01*
G01X374097Y764469D02*
X374327Y764624D01*
X374595Y764727D01*
X374902D01*
X375247Y764572D01*
X375515Y764314D01*
X375707Y764004D01*
X375860Y763487D01*
X375898Y763022D01*
X375822Y762557D01*
X375707Y762247D01*
X375477Y761937D01*
X375208Y761730D01*
X374940Y761627D01*
X374672D01*
X374403Y761730D01*
X374173Y761885D01*
X373982Y762092D01*
G01X372568Y762919D02*
X372300Y763280D01*
X372070Y763487D01*
X371763Y763590D01*
X371495Y763487D01*
X371303Y763280D01*
X371150Y762970D01*
X371112Y762609D01*
X371150Y762299D01*
X371303Y761989D01*
X371533Y761730D01*
X371802Y761627D01*
X372108Y761730D01*
X372377Y762040D01*
X372530Y762505D01*
X372568Y763022D01*
X372492Y763694D01*
X372377Y764055D01*
X372185Y764417D01*
X371917Y764675D01*
X371648Y764727D01*
X371380Y764624D01*
X371188Y764365D01*
G01X369468Y762919D02*
X369200Y763280D01*
X368970Y763487D01*
X368663Y763590D01*
X368395Y763487D01*
X368203Y763280D01*
X368050Y762970D01*
X368012Y762609D01*
X368050Y762299D01*
X368203Y761989D01*
X368433Y761730D01*
X368702Y761627D01*
X369008Y761730D01*
X369277Y762040D01*
X369430Y762505D01*
X369468Y763022D01*
X369392Y763694D01*
X369277Y764055D01*
X369085Y764417D01*
X368817Y764675D01*
X368548Y764727D01*
X368280Y764624D01*
X368088Y764365D01*
G01X365640Y761627D02*
X365372Y761679D01*
X365065Y761834D01*
X364873Y762092D01*
X364797Y762454D01*
X364873Y762815D01*
X365103Y763125D01*
X365448Y763280D01*
X365832D01*
X366062Y763384D01*
X366253Y763642D01*
X366330Y764004D01*
X366215Y764365D01*
X365947Y764624D01*
X365640Y764727D01*
X365333Y764624D01*
X365065Y764365D01*
X364950Y764004D01*
X365027Y763642D01*
X365218Y763384D01*
X365448Y763280D01*
X365832D01*
X366177Y763125D01*
X366407Y762815D01*
X366483Y762454D01*
X366407Y762092D01*
X366215Y761834D01*
X365908Y761679D01*
X365640Y761627D01*
G01X375707Y757507D02*
Y760607D01*
X374748D01*
X374442Y760452D01*
X374250Y760245D01*
X374173Y759832D01*
X374250Y759419D01*
X374480Y759160D01*
X374748Y759005D01*
X375707D01*
G01X374748D02*
X374173Y757507D01*
G01X372492Y757869D02*
X372223Y757610D01*
X371917Y757507D01*
X371610Y757610D01*
X371342Y757920D01*
X371150Y758385D01*
X371073Y758850D01*
Y759419D01*
X371150Y759884D01*
X371342Y760297D01*
X371572Y760504D01*
X371840Y760607D01*
X372147Y760504D01*
X372377Y760297D01*
X372530Y759987D01*
X372607Y759574D01*
X372530Y759212D01*
X372338Y758850D01*
X372108Y758644D01*
X371840Y758592D01*
X371533Y758695D01*
X371303Y758954D01*
X371073Y759419D01*
G01X368740Y757507D02*
Y760607D01*
X369200Y759987D01*
G01Y757507D02*
X368280D01*
G01X366483Y757972D02*
X366253Y757714D01*
X365985Y757559D01*
X365640Y757507D01*
X365295Y757610D01*
X365027Y757817D01*
X364835Y758179D01*
X364797Y758592D01*
X364873Y759005D01*
X365065Y759264D01*
X365333Y759470D01*
X365602Y759522D01*
X365870Y759470D01*
X366215Y759264D01*
X366100Y760607D01*
X365065D01*
G01X380993Y-186364D02*
Y-194364D01*
G01X378693Y-186364D02*
X383293D01*
G01X387093Y-191031D02*
X387793Y-190097D01*
X388393Y-189564D01*
X389193Y-189297D01*
X389893Y-189564D01*
X390393Y-190097D01*
X390793Y-190897D01*
X390893Y-191831D01*
X390793Y-192631D01*
X390393Y-193431D01*
X389793Y-194097D01*
X389093Y-194364D01*
X388293Y-194097D01*
X387593Y-193298D01*
X387193Y-192097D01*
X387093Y-190764D01*
X387293Y-189031D01*
X387593Y-188097D01*
X388093Y-187164D01*
X388793Y-186497D01*
X389493Y-186364D01*
X390193Y-186631D01*
X390693Y-187297D01*
G01X394393Y-194364D02*
Y-186364D01*
X396993Y-193031D01*
X399593Y-186364D01*
Y-194364D01*
G01X401993Y-197031D02*
X407993D01*
G01X415193Y-187031D02*
X414593Y-186631D01*
X413893Y-186364D01*
X413093D01*
X412193Y-186764D01*
X411493Y-187431D01*
X410993Y-188231D01*
X410593Y-189564D01*
X410493Y-190764D01*
X410693Y-191964D01*
X410993Y-192764D01*
X411593Y-193564D01*
X412293Y-194097D01*
X412993Y-194364D01*
X413693D01*
X414393Y-194097D01*
X414993Y-193697D01*
X415493Y-193164D01*
G01X418393Y-194364D02*
Y-186364D01*
X420993Y-193031D01*
X423593Y-186364D01*
Y-194364D01*
G01X425993Y-197031D02*
X431993D01*
G01X434793Y-194364D02*
Y-186364D01*
X436793D01*
X437593Y-186764D01*
X438193Y-187297D01*
X438693Y-188097D01*
X439093Y-189031D01*
X439193Y-190364D01*
X439093Y-191697D01*
X438693Y-192631D01*
X438193Y-193431D01*
X437593Y-193964D01*
X436793Y-194364D01*
X434793D01*
G01X383679Y112137D02*
Y115237D01*
X382720D01*
X382414Y115082D01*
X382222Y114875D01*
X382145Y114462D01*
X382222Y114049D01*
X382452Y113790D01*
X382720Y113635D01*
X383679D01*
G01X382720D02*
X382145Y112137D01*
G01X380540Y114720D02*
X380310Y115030D01*
X380042Y115185D01*
X379735Y115237D01*
X379352Y115134D01*
X379084Y114875D01*
X379007Y114565D01*
X379045Y114255D01*
X379199Y113997D01*
X379965Y113480D01*
X380310Y113119D01*
X380540Y112602D01*
X380617Y112137D01*
X379007D01*
G01X376712Y115237D02*
X377019Y115134D01*
X377249Y114875D01*
X377402Y114565D01*
X377517Y114152D01*
X377555Y113687D01*
X377517Y113222D01*
X377402Y112809D01*
X377249Y112499D01*
X377019Y112240D01*
X376712Y112137D01*
X376405Y112240D01*
X376175Y112499D01*
X376022Y112809D01*
X375907Y113222D01*
X375869Y113687D01*
X375907Y114152D01*
X376022Y114565D01*
X376175Y114875D01*
X376405Y115134D01*
X376712Y115237D01*
G01X374340Y113429D02*
X374072Y113790D01*
X373842Y113997D01*
X373535Y114100D01*
X373267Y113997D01*
X373075Y113790D01*
X372922Y113480D01*
X372884Y113119D01*
X372922Y112809D01*
X373075Y112499D01*
X373305Y112240D01*
X373574Y112137D01*
X373880Y112240D01*
X374149Y112550D01*
X374302Y113015D01*
X374340Y113532D01*
X374264Y114204D01*
X374149Y114565D01*
X373957Y114927D01*
X373689Y115185D01*
X373420Y115237D01*
X373152Y115134D01*
X372960Y114875D01*
G01X373833Y119417D02*
Y116217D01*
G01X380033Y119417D02*
X373833D01*
G01Y116217D02*
X380033D01*
G01D02*
Y119417D01*
G01X392356Y247563D02*
Y250663D01*
X391397D01*
X391091Y250508D01*
X390899Y250301D01*
X390822Y249888D01*
X390899Y249475D01*
X391129Y249216D01*
X391397Y249061D01*
X392356D01*
G01X391397D02*
X390822Y247563D01*
G01X389217Y250146D02*
X388987Y250456D01*
X388719Y250611D01*
X388412Y250663D01*
X388029Y250560D01*
X387761Y250301D01*
X387684Y249991D01*
X387722Y249681D01*
X387876Y249423D01*
X388642Y248906D01*
X388987Y248545D01*
X389217Y248028D01*
X389294Y247563D01*
X387684D01*
G01X386117Y250146D02*
X385887Y250456D01*
X385619Y250611D01*
X385312Y250663D01*
X384929Y250560D01*
X384661Y250301D01*
X384584Y249991D01*
X384622Y249681D01*
X384776Y249423D01*
X385542Y248906D01*
X385887Y248545D01*
X386117Y248028D01*
X386194Y247563D01*
X384584D01*
G01X383017Y250146D02*
X382787Y250456D01*
X382519Y250611D01*
X382212Y250663D01*
X381829Y250560D01*
X381561Y250301D01*
X381484Y249991D01*
X381522Y249681D01*
X381676Y249423D01*
X382442Y248906D01*
X382787Y248545D01*
X383017Y248028D01*
X383094Y247563D01*
X381484D01*
G01X392152Y260337D02*
Y263437D01*
X391193D01*
X390887Y263282D01*
X390695Y263075D01*
X390618Y262662D01*
X390695Y262249D01*
X390925Y261990D01*
X391193Y261835D01*
X392152D01*
G01X391193D02*
X390618Y260337D01*
G01X389013Y262920D02*
X388783Y263230D01*
X388515Y263385D01*
X388208Y263437D01*
X387825Y263334D01*
X387557Y263075D01*
X387480Y262765D01*
X387518Y262455D01*
X387672Y262197D01*
X388438Y261680D01*
X388783Y261319D01*
X389013Y260802D01*
X389090Y260337D01*
X387480D01*
G01X385913Y262920D02*
X385683Y263230D01*
X385415Y263385D01*
X385108Y263437D01*
X384725Y263334D01*
X384457Y263075D01*
X384380Y262765D01*
X384418Y262455D01*
X384572Y262197D01*
X385338Y261680D01*
X385683Y261319D01*
X385913Y260802D01*
X385990Y260337D01*
X384380D01*
G01X382813Y261629D02*
X382545Y261990D01*
X382315Y262197D01*
X382008Y262300D01*
X381740Y262197D01*
X381548Y261990D01*
X381395Y261680D01*
X381357Y261319D01*
X381395Y261009D01*
X381548Y260699D01*
X381778Y260440D01*
X382047Y260337D01*
X382353Y260440D01*
X382622Y260750D01*
X382775Y261215D01*
X382813Y261732D01*
X382737Y262404D01*
X382622Y262765D01*
X382430Y263127D01*
X382162Y263385D01*
X381893Y263437D01*
X381625Y263334D01*
X381433Y263075D01*
G01X392150Y264476D02*
Y267576D01*
X391191D01*
X390885Y267421D01*
X390693Y267214D01*
X390616Y266801D01*
X390693Y266388D01*
X390923Y266129D01*
X391191Y265974D01*
X392150D01*
G01X391191D02*
X390616Y264476D01*
G01X389011Y267059D02*
X388781Y267369D01*
X388513Y267524D01*
X388206Y267576D01*
X387823Y267473D01*
X387555Y267214D01*
X387478Y266904D01*
X387516Y266594D01*
X387670Y266336D01*
X388436Y265819D01*
X388781Y265458D01*
X389011Y264941D01*
X389088Y264476D01*
X387478D01*
G01X385911Y267059D02*
X385681Y267369D01*
X385413Y267524D01*
X385106Y267576D01*
X384723Y267473D01*
X384455Y267214D01*
X384378Y266904D01*
X384416Y266594D01*
X384570Y266336D01*
X385336Y265819D01*
X385681Y265458D01*
X385911Y264941D01*
X385988Y264476D01*
X384378D01*
G01X382160D02*
X382083Y265148D01*
X381968Y265716D01*
X381815Y266233D01*
X381623Y266801D01*
X381316Y267576D01*
X382850D01*
G01X392224Y255951D02*
Y259051D01*
X391265D01*
X390959Y258896D01*
X390767Y258689D01*
X390690Y258276D01*
X390767Y257863D01*
X390997Y257604D01*
X391265Y257449D01*
X392224D01*
G01X391265D02*
X390690Y255951D01*
G01X389085Y258534D02*
X388855Y258844D01*
X388587Y258999D01*
X388280Y259051D01*
X387897Y258948D01*
X387629Y258689D01*
X387552Y258379D01*
X387590Y258069D01*
X387744Y257811D01*
X388510Y257294D01*
X388855Y256933D01*
X389085Y256416D01*
X389162Y255951D01*
X387552D01*
G01X385257D02*
Y259051D01*
X385717Y258431D01*
G01Y255951D02*
X384797D01*
G01X382809Y256313D02*
X382540Y256054D01*
X382234Y255951D01*
X381927Y256054D01*
X381659Y256364D01*
X381467Y256829D01*
X381390Y257294D01*
Y257863D01*
X381467Y258328D01*
X381659Y258741D01*
X381889Y258948D01*
X382157Y259051D01*
X382464Y258948D01*
X382694Y258741D01*
X382847Y258431D01*
X382924Y258018D01*
X382847Y257656D01*
X382655Y257294D01*
X382425Y257088D01*
X382157Y257036D01*
X381850Y257139D01*
X381620Y257398D01*
X381390Y257863D01*
G01X392382Y251634D02*
Y254734D01*
X391423D01*
X391117Y254579D01*
X390925Y254372D01*
X390848Y253959D01*
X390925Y253546D01*
X391155Y253287D01*
X391423Y253132D01*
X392382D01*
G01X391423D02*
X390848Y251634D01*
G01X389243Y254217D02*
X389013Y254527D01*
X388745Y254682D01*
X388438Y254734D01*
X388055Y254631D01*
X387787Y254372D01*
X387710Y254062D01*
X387748Y253752D01*
X387902Y253494D01*
X388668Y252977D01*
X389013Y252616D01*
X389243Y252099D01*
X389320Y251634D01*
X387710D01*
G01X386143Y254217D02*
X385913Y254527D01*
X385645Y254682D01*
X385338Y254734D01*
X384955Y254631D01*
X384687Y254372D01*
X384610Y254062D01*
X384648Y253752D01*
X384802Y253494D01*
X385568Y252977D01*
X385913Y252616D01*
X386143Y252099D01*
X386220Y251634D01*
X384610D01*
G01X382315Y254734D02*
X382622Y254631D01*
X382852Y254372D01*
X383005Y254062D01*
X383120Y253649D01*
X383158Y253184D01*
X383120Y252719D01*
X383005Y252306D01*
X382852Y251996D01*
X382622Y251737D01*
X382315Y251634D01*
X382008Y251737D01*
X381778Y251996D01*
X381625Y252306D01*
X381510Y252719D01*
X381472Y253184D01*
X381510Y253649D01*
X381625Y254062D01*
X381778Y254372D01*
X382008Y254631D01*
X382315Y254734D01*
G01X390540Y271548D02*
X390770Y271703D01*
X391038Y271806D01*
X391345D01*
X391690Y271651D01*
X391958Y271393D01*
X392150Y271083D01*
X392303Y270566D01*
X392341Y270101D01*
X392265Y269636D01*
X392150Y269326D01*
X391920Y269016D01*
X391651Y268809D01*
X391383Y268706D01*
X391115D01*
X390846Y268809D01*
X390616Y268964D01*
X390425Y269171D01*
G01X388283Y268706D02*
Y271806D01*
X388743Y271186D01*
G01Y268706D02*
X387823D01*
G01X385183D02*
X384915Y268758D01*
X384608Y268913D01*
X384416Y269171D01*
X384340Y269533D01*
X384416Y269894D01*
X384646Y270204D01*
X384991Y270359D01*
X385375D01*
X385605Y270463D01*
X385796Y270721D01*
X385873Y271083D01*
X385758Y271444D01*
X385490Y271703D01*
X385183Y271806D01*
X384876Y271703D01*
X384608Y271444D01*
X384493Y271083D01*
X384570Y270721D01*
X384761Y270463D01*
X384991Y270359D01*
X385375D01*
X385720Y270204D01*
X385950Y269894D01*
X386026Y269533D01*
X385950Y269171D01*
X385758Y268913D01*
X385451Y268758D01*
X385183Y268706D01*
G01X381623D02*
Y271806D01*
X383041Y269584D01*
X381125D01*
G01X444882Y377165D02*
G02I-31496J0D01*
G01X396279Y451370D02*
Y454470D01*
X395359D01*
X395052Y454315D01*
X394822Y453953D01*
X394745Y453540D01*
X394822Y453127D01*
X395014Y452817D01*
X395359Y452662D01*
X396279D01*
G01X391569Y454212D02*
X391799Y454367D01*
X392067Y454470D01*
X392374D01*
X392719Y454315D01*
X392987Y454057D01*
X393179Y453747D01*
X393332Y453230D01*
X393370Y452765D01*
X393294Y452300D01*
X393179Y451990D01*
X392949Y451680D01*
X392680Y451473D01*
X392412Y451370D01*
X392144D01*
X391875Y451473D01*
X391645Y451628D01*
X391454Y451835D01*
G01X389312Y451370D02*
Y454470D01*
X389772Y453850D01*
G01Y451370D02*
X388852D01*
G01X386212D02*
Y454470D01*
X386672Y453850D01*
G01Y451370D02*
X385752D01*
G01X383955Y451990D02*
X383725Y451628D01*
X383419Y451422D01*
X383074Y451370D01*
X382767Y451422D01*
X382460Y451680D01*
X382269Y451990D01*
X382230Y452300D01*
X382307Y452662D01*
X382575Y452920D01*
X382844Y453023D01*
X383189D01*
G01X382844D02*
X382614Y453178D01*
X382422Y453437D01*
X382345Y453747D01*
X382422Y454057D01*
X382614Y454315D01*
X382959Y454470D01*
X383304Y454418D01*
X383649Y454212D01*
G01X396279Y459143D02*
Y462243D01*
X395359D01*
X395052Y462088D01*
X394822Y461726D01*
X394745Y461313D01*
X394822Y460900D01*
X395014Y460590D01*
X395359Y460435D01*
X396279D01*
G01X391569Y461985D02*
X391799Y462140D01*
X392067Y462243D01*
X392374D01*
X392719Y462088D01*
X392987Y461830D01*
X393179Y461520D01*
X393332Y461003D01*
X393370Y460538D01*
X393294Y460073D01*
X393179Y459763D01*
X392949Y459453D01*
X392680Y459246D01*
X392412Y459143D01*
X392144D01*
X391875Y459246D01*
X391645Y459401D01*
X391454Y459608D01*
G01X389312Y459143D02*
Y462243D01*
X389772Y461623D01*
G01Y459143D02*
X388852D01*
G01X386940Y461726D02*
X386710Y462036D01*
X386442Y462191D01*
X386135Y462243D01*
X385752Y462140D01*
X385484Y461881D01*
X385407Y461571D01*
X385445Y461261D01*
X385599Y461003D01*
X386365Y460486D01*
X386710Y460125D01*
X386940Y459608D01*
X387017Y459143D01*
X385407D01*
G01X382652D02*
Y462243D01*
X384070Y460021D01*
X382154D01*
G01X375340Y594370D02*
Y548510D01*
G01X372230Y649218D02*
X375330D01*
Y650177D01*
X375175Y650483D01*
X374968Y650675D01*
X374555Y650752D01*
X374142Y650675D01*
X373883Y650445D01*
X373728Y650177D01*
Y649218D01*
G01Y650177D02*
X372230Y650752D01*
G01Y653008D02*
X372902Y653085D01*
X373470Y653200D01*
X373987Y653353D01*
X374555Y653545D01*
X375330Y653852D01*
Y652318D01*
G01X373522Y655457D02*
X373883Y655725D01*
X374090Y655955D01*
X374193Y656262D01*
X374090Y656530D01*
X373883Y656722D01*
X373573Y656875D01*
X373212Y656913D01*
X372902Y656875D01*
X372592Y656722D01*
X372333Y656492D01*
X372230Y656223D01*
X372333Y655917D01*
X372643Y655648D01*
X373108Y655495D01*
X373625Y655457D01*
X374297Y655533D01*
X374658Y655648D01*
X375020Y655840D01*
X375278Y656108D01*
X375330Y656377D01*
X375227Y656645D01*
X374968Y656837D01*
G01X373522Y658557D02*
X373883Y658825D01*
X374090Y659055D01*
X374193Y659362D01*
X374090Y659630D01*
X373883Y659822D01*
X373573Y659975D01*
X373212Y660013D01*
X372902Y659975D01*
X372592Y659822D01*
X372333Y659592D01*
X372230Y659323D01*
X372333Y659017D01*
X372643Y658748D01*
X373108Y658595D01*
X373625Y658557D01*
X374297Y658633D01*
X374658Y658748D01*
X375020Y658940D01*
X375278Y659208D01*
X375330Y659477D01*
X375227Y659745D01*
X374968Y659937D01*
G01X382260Y656564D02*
X385460D01*
G01X382260Y662764D02*
Y656564D01*
G01X383968Y664966D02*
X384123Y664736D01*
X384226Y664468D01*
Y664161D01*
X384071Y663816D01*
X383813Y663548D01*
X383503Y663356D01*
X382986Y663203D01*
X382521Y663165D01*
X382056Y663241D01*
X381746Y663356D01*
X381436Y663586D01*
X381229Y663855D01*
X381126Y664123D01*
Y664391D01*
X381229Y664660D01*
X381384Y664890D01*
X381591Y665081D01*
G01X381126Y667146D02*
X381798Y667223D01*
X382366Y667338D01*
X382883Y667491D01*
X383451Y667683D01*
X384226Y667990D01*
Y666456D01*
G01X382418Y669595D02*
X382779Y669863D01*
X382986Y670093D01*
X383089Y670400D01*
X382986Y670668D01*
X382779Y670860D01*
X382469Y671013D01*
X382108Y671051D01*
X381798Y671013D01*
X381488Y670860D01*
X381229Y670630D01*
X381126Y670361D01*
X381229Y670055D01*
X381539Y669786D01*
X382004Y669633D01*
X382521Y669595D01*
X383193Y669671D01*
X383554Y669786D01*
X383916Y669978D01*
X384174Y670246D01*
X384226Y670515D01*
X384123Y670783D01*
X383864Y670975D01*
G01X382418Y672695D02*
X382779Y672963D01*
X382986Y673193D01*
X383089Y673500D01*
X382986Y673768D01*
X382779Y673960D01*
X382469Y674113D01*
X382108Y674151D01*
X381798Y674113D01*
X381488Y673960D01*
X381229Y673730D01*
X381126Y673461D01*
X381229Y673155D01*
X381539Y672886D01*
X382004Y672733D01*
X382521Y672695D01*
X383193Y672771D01*
X383554Y672886D01*
X383916Y673078D01*
X384174Y673346D01*
X384226Y673615D01*
X384123Y673883D01*
X383864Y674075D01*
G01X385460Y662764D02*
X382260D01*
G01X374958Y684056D02*
Y687256D01*
G01Y680056D02*
Y683256D01*
G01Y676056D02*
Y679256D01*
G01X375480Y694241D02*
X373258D01*
X372793Y694394D01*
X372483Y694701D01*
X372380Y695084D01*
X372483Y695467D01*
X372793Y695774D01*
X373258Y695927D01*
X375480D01*
G01X373672Y697456D02*
X374033Y697724D01*
X374240Y697954D01*
X374343Y698261D01*
X374240Y698529D01*
X374033Y698721D01*
X373723Y698874D01*
X373362Y698912D01*
X373052Y698874D01*
X372742Y698721D01*
X372483Y698491D01*
X372380Y698222D01*
X372483Y697916D01*
X372793Y697647D01*
X373258Y697494D01*
X373775Y697456D01*
X374447Y697532D01*
X374808Y697647D01*
X375170Y697839D01*
X375428Y698107D01*
X375480Y698376D01*
X375377Y698644D01*
X375118Y698836D01*
G01X372845Y700441D02*
X372587Y700671D01*
X372432Y700939D01*
X372380Y701284D01*
X372483Y701629D01*
X372690Y701897D01*
X373052Y702089D01*
X373465Y702127D01*
X373878Y702051D01*
X374137Y701859D01*
X374343Y701591D01*
X374395Y701322D01*
X374343Y701054D01*
X374137Y700709D01*
X375480Y700824D01*
Y701859D01*
G01X370520Y715384D02*
Y721584D01*
G01X371960Y716626D02*
Y713426D01*
G01X378160Y716626D02*
X371960D01*
G01Y713426D02*
X378160D01*
G01D02*
Y716626D01*
G01X390887Y717824D02*
Y720924D01*
X389928D01*
X389622Y720769D01*
X389430Y720562D01*
X389353Y720149D01*
X389430Y719736D01*
X389660Y719477D01*
X389928Y719322D01*
X390887D01*
G01X389928D02*
X389353Y717824D01*
G01X387097D02*
X387020Y718496D01*
X386905Y719064D01*
X386752Y719581D01*
X386560Y720149D01*
X386253Y720924D01*
X387787D01*
G01X384763Y718289D02*
X384533Y718031D01*
X384265Y717876D01*
X383920Y717824D01*
X383575Y717927D01*
X383307Y718134D01*
X383115Y718496D01*
X383077Y718909D01*
X383153Y719322D01*
X383345Y719581D01*
X383613Y719787D01*
X383882Y719839D01*
X384150Y719787D01*
X384495Y719581D01*
X384380Y720924D01*
X383345D01*
G01X381663Y718289D02*
X381433Y718031D01*
X381165Y717876D01*
X380820Y717824D01*
X380475Y717927D01*
X380207Y718134D01*
X380015Y718496D01*
X379977Y718909D01*
X380053Y719322D01*
X380245Y719581D01*
X380513Y719787D01*
X380782Y719839D01*
X381050Y719787D01*
X381395Y719581D01*
X381280Y720924D01*
X380245D01*
G01X382808Y713648D02*
X389008D01*
G01Y716848D02*
X382808D01*
G01D02*
Y713648D01*
G01X374103Y726022D02*
Y729222D01*
G01X371003Y729122D02*
Y726122D01*
G01X374011Y737859D02*
Y741059D01*
G01X370911Y737959D02*
Y740959D01*
G01X374011Y733859D02*
Y737059D01*
G01Y729860D02*
Y733058D01*
G01X370911Y744959D02*
Y741959D01*
G01X374011Y741859D02*
Y745059D01*
G01X378814Y795098D02*
X377856Y798198D01*
X376898Y795098D01*
G01X377243Y796183D02*
X378469D01*
G01X374756Y795098D02*
Y798198D01*
X375216Y797578D01*
G01Y795098D02*
X374296D01*
G01X401477Y412998D02*
Y416098D01*
X400557D01*
X400250Y415943D01*
X400020Y415581D01*
X399943Y415168D01*
X400020Y414755D01*
X400212Y414445D01*
X400557Y414290D01*
X401477D01*
G01X396767Y415840D02*
X396997Y415995D01*
X397265Y416098D01*
X397572D01*
X397917Y415943D01*
X398185Y415685D01*
X398377Y415375D01*
X398530Y414858D01*
X398568Y414393D01*
X398492Y413928D01*
X398377Y413618D01*
X398147Y413308D01*
X397878Y413101D01*
X397610Y412998D01*
X397342D01*
X397073Y413101D01*
X396843Y413256D01*
X396652Y413463D01*
G01X394510Y412998D02*
Y416098D01*
X394970Y415478D01*
G01Y412998D02*
X394050D01*
G01X391410D02*
Y416098D01*
X391870Y415478D01*
G01Y412998D02*
X390950D01*
G01X389038Y414290D02*
X388770Y414651D01*
X388540Y414858D01*
X388233Y414961D01*
X387965Y414858D01*
X387773Y414651D01*
X387620Y414341D01*
X387582Y413980D01*
X387620Y413670D01*
X387773Y413360D01*
X388003Y413101D01*
X388272Y412998D01*
X388578Y413101D01*
X388847Y413411D01*
X389000Y413876D01*
X389038Y414393D01*
X388962Y415065D01*
X388847Y415426D01*
X388655Y415788D01*
X388387Y416046D01*
X388118Y416098D01*
X387850Y415995D01*
X387658Y415736D01*
G01X401477Y418646D02*
Y421746D01*
X400557D01*
X400250Y421591D01*
X400020Y421229D01*
X399943Y420816D01*
X400020Y420403D01*
X400212Y420093D01*
X400557Y419938D01*
X401477D01*
G01X396767Y421488D02*
X396997Y421643D01*
X397265Y421746D01*
X397572D01*
X397917Y421591D01*
X398185Y421333D01*
X398377Y421023D01*
X398530Y420506D01*
X398568Y420041D01*
X398492Y419576D01*
X398377Y419266D01*
X398147Y418956D01*
X397878Y418749D01*
X397610Y418646D01*
X397342D01*
X397073Y418749D01*
X396843Y418904D01*
X396652Y419111D01*
G01X394510Y418646D02*
Y421746D01*
X394970Y421126D01*
G01Y418646D02*
X394050D01*
G01X391410D02*
Y421746D01*
X391870Y421126D01*
G01Y418646D02*
X390950D01*
G01X387850D02*
Y421746D01*
X389268Y419524D01*
X387352D01*
G01X401477Y428363D02*
Y431463D01*
X400557D01*
X400250Y431308D01*
X400020Y430946D01*
X399943Y430533D01*
X400020Y430120D01*
X400212Y429810D01*
X400557Y429655D01*
X401477D01*
G01X396767Y431205D02*
X396997Y431360D01*
X397265Y431463D01*
X397572D01*
X397917Y431308D01*
X398185Y431050D01*
X398377Y430740D01*
X398530Y430223D01*
X398568Y429758D01*
X398492Y429293D01*
X398377Y428983D01*
X398147Y428673D01*
X397878Y428466D01*
X397610Y428363D01*
X397342D01*
X397073Y428466D01*
X396843Y428621D01*
X396652Y428828D01*
G01X394510Y428363D02*
Y431463D01*
X394970Y430843D01*
G01Y428363D02*
X394050D01*
G01X391410Y431463D02*
X391717Y431360D01*
X391947Y431101D01*
X392100Y430791D01*
X392215Y430378D01*
X392253Y429913D01*
X392215Y429448D01*
X392100Y429035D01*
X391947Y428725D01*
X391717Y428466D01*
X391410Y428363D01*
X391103Y428466D01*
X390873Y428725D01*
X390720Y429035D01*
X390605Y429448D01*
X390567Y429913D01*
X390605Y430378D01*
X390720Y430791D01*
X390873Y431101D01*
X391103Y431360D01*
X391410Y431463D01*
G01X389153Y428828D02*
X388923Y428570D01*
X388655Y428415D01*
X388310Y428363D01*
X387965Y428466D01*
X387697Y428673D01*
X387505Y429035D01*
X387467Y429448D01*
X387543Y429861D01*
X387735Y430120D01*
X388003Y430326D01*
X388272Y430378D01*
X388540Y430326D01*
X388885Y430120D01*
X388770Y431463D01*
X387735D01*
G01X401477Y435321D02*
Y438421D01*
X400557D01*
X400250Y438266D01*
X400020Y437904D01*
X399943Y437491D01*
X400020Y437078D01*
X400212Y436768D01*
X400557Y436613D01*
X401477D01*
G01X396767Y438163D02*
X396997Y438318D01*
X397265Y438421D01*
X397572D01*
X397917Y438266D01*
X398185Y438008D01*
X398377Y437698D01*
X398530Y437181D01*
X398568Y436716D01*
X398492Y436251D01*
X398377Y435941D01*
X398147Y435631D01*
X397878Y435424D01*
X397610Y435321D01*
X397342D01*
X397073Y435424D01*
X396843Y435579D01*
X396652Y435786D01*
G01X394510Y435321D02*
Y438421D01*
X394970Y437801D01*
G01Y435321D02*
X394050D01*
G01X392138Y437904D02*
X391908Y438214D01*
X391640Y438369D01*
X391333Y438421D01*
X390950Y438318D01*
X390682Y438059D01*
X390605Y437749D01*
X390643Y437439D01*
X390797Y437181D01*
X391563Y436664D01*
X391908Y436303D01*
X392138Y435786D01*
X392215Y435321D01*
X390605D01*
G01X389153Y435786D02*
X388923Y435528D01*
X388655Y435373D01*
X388310Y435321D01*
X387965Y435424D01*
X387697Y435631D01*
X387505Y435993D01*
X387467Y436406D01*
X387543Y436819D01*
X387735Y437078D01*
X388003Y437284D01*
X388272Y437336D01*
X388540Y437284D01*
X388885Y437078D01*
X388770Y438421D01*
X387735D01*
G01X399311Y449430D02*
X414311D01*
G01X399311Y456230D02*
Y449430D01*
G01X401477Y442718D02*
Y445818D01*
X400557D01*
X400250Y445663D01*
X400020Y445301D01*
X399943Y444888D01*
X400020Y444475D01*
X400212Y444165D01*
X400557Y444010D01*
X401477D01*
G01X396767Y445560D02*
X396997Y445715D01*
X397265Y445818D01*
X397572D01*
X397917Y445663D01*
X398185Y445405D01*
X398377Y445095D01*
X398530Y444578D01*
X398568Y444113D01*
X398492Y443648D01*
X398377Y443338D01*
X398147Y443028D01*
X397878Y442821D01*
X397610Y442718D01*
X397342D01*
X397073Y442821D01*
X396843Y442976D01*
X396652Y443183D01*
G01X394510Y442718D02*
Y445818D01*
X394970Y445198D01*
G01Y442718D02*
X394050D01*
G01X391410D02*
Y445818D01*
X391870Y445198D01*
G01Y442718D02*
X390950D01*
G01X389038Y445301D02*
X388808Y445611D01*
X388540Y445766D01*
X388233Y445818D01*
X387850Y445715D01*
X387582Y445456D01*
X387505Y445146D01*
X387543Y444836D01*
X387697Y444578D01*
X388463Y444061D01*
X388808Y443700D01*
X389038Y443183D01*
X389115Y442718D01*
X387505D01*
G01X414311Y456230D02*
X399311D01*
G01Y457174D02*
X414311D01*
G01X399311Y463974D02*
Y457174D01*
G01X414311Y463974D02*
X399311D01*
G01X397863Y583015D02*
Y586115D01*
X396943D01*
X396636Y585960D01*
X396406Y585598D01*
X396329Y585185D01*
X396406Y584772D01*
X396598Y584462D01*
X396943Y584307D01*
X397863D01*
G01X393153Y585857D02*
X393383Y586012D01*
X393651Y586115D01*
X393958D01*
X394303Y585960D01*
X394571Y585702D01*
X394763Y585392D01*
X394916Y584875D01*
X394954Y584410D01*
X394878Y583945D01*
X394763Y583635D01*
X394533Y583325D01*
X394264Y583118D01*
X393996Y583015D01*
X393728D01*
X393459Y583118D01*
X393229Y583273D01*
X393038Y583480D01*
G01X391739Y583635D02*
X391509Y583273D01*
X391203Y583067D01*
X390858Y583015D01*
X390551Y583067D01*
X390244Y583325D01*
X390053Y583635D01*
X390014Y583945D01*
X390091Y584307D01*
X390359Y584565D01*
X390628Y584668D01*
X390973D01*
G01X390628D02*
X390398Y584823D01*
X390206Y585082D01*
X390129Y585392D01*
X390206Y585702D01*
X390398Y585960D01*
X390743Y586115D01*
X391088Y586063D01*
X391433Y585857D01*
G01X387336Y583015D02*
Y586115D01*
X388754Y583893D01*
X386838D01*
G01X384777Y595521D02*
Y588121D01*
G01D02*
X402177D01*
G01X393477D02*
Y595521D01*
G01X402177D02*
X384777D01*
G01X401650Y641902D02*
Y639680D01*
X401497Y639215D01*
X401190Y638905D01*
X400807Y638802D01*
X400424Y638905D01*
X400117Y639215D01*
X399964Y639680D01*
Y641902D01*
G01X397784Y638802D02*
X397707Y639474D01*
X397592Y640042D01*
X397439Y640559D01*
X397247Y641127D01*
X396940Y641902D01*
X398474D01*
G01X394607Y638802D02*
Y641902D01*
X395067Y641282D01*
G01Y638802D02*
X394147D01*
G01X398006Y647838D02*
X404606D01*
G01X396506Y650338D02*
X398006Y647838D01*
G01X395006D02*
X396506Y650338D01*
G01X388406Y647838D02*
X395006D01*
G01X388406Y660838D02*
Y647838D01*
G01X385460Y656564D02*
Y662764D01*
G01X392570Y662410D02*
Y671043D01*
G01X399200Y671537D02*
X400200Y669937D01*
G01X393500Y671537D02*
Y662737D01*
G01Y671537D02*
X399200D01*
G01X393500Y662737D02*
X406900D01*
G01X400200Y669937D02*
X401200Y671537D01*
G01X404606Y660838D02*
X388406D01*
G01X388399Y663753D02*
X391599D01*
G01X388399Y669953D02*
Y663753D01*
G01X391599Y669953D02*
X388399D01*
G01X391599Y663753D02*
Y669953D01*
G01X388499Y666853D02*
X391499D01*
G01X399541Y674613D02*
Y677813D01*
G01X393341Y674613D02*
X399541D01*
G01X393341Y677813D02*
Y674613D01*
G01X390440Y681656D02*
G02I-1000J0D01*
G01X397740Y679556D02*
X403340D01*
G01X395440Y681856D02*
X397740Y679556D01*
G01X393140D02*
X395440Y681856D01*
G01X387540Y679556D02*
X393140D01*
G01X387540Y710756D02*
Y679556D01*
G01X399541Y677813D02*
X393341D01*
G01X403340Y710756D02*
X387540D01*
G01X404118Y717854D02*
X397918D01*
G01Y714654D02*
X404118D01*
G01X397918Y717854D02*
Y714654D01*
G01X389008Y713648D02*
Y716848D01*
G01X407956Y263079D02*
X414156D01*
G01X411056Y263179D02*
Y266179D01*
G01X407956Y266279D02*
Y263079D01*
G01X414156D02*
Y266279D01*
G01X407956Y258889D02*
X414156D01*
G01D02*
Y262089D01*
G01D02*
X407956D01*
G01D02*
Y258889D01*
G01X414156Y258089D02*
X407956D01*
G01D02*
Y254889D01*
G01D02*
X414156D01*
G01D02*
Y258089D01*
G01X407956Y250889D02*
X414156D01*
G01D02*
Y254089D01*
G01D02*
X407956D01*
G01D02*
Y250889D01*
G01X414156Y266279D02*
X407956D01*
G01X414156Y274331D02*
X407956D01*
G01D02*
Y271131D01*
G01D02*
X414156D01*
G01D02*
Y274331D01*
G01X407956Y267079D02*
X414156D01*
G01D02*
Y270279D01*
G01D02*
X407956D01*
G01D02*
Y267079D01*
G01X421641Y416230D02*
X406641D01*
G01D02*
Y409430D01*
G01X414141Y409530D02*
Y416130D01*
G01X406641Y409430D02*
X421641D01*
G01X406641Y417430D02*
X421641D01*
G01X406641Y424230D02*
Y417430D01*
G01X414141Y417530D02*
Y424130D01*
G01X421641Y424230D02*
X406641D01*
G01X414141Y425530D02*
Y432130D01*
G01X421641Y432230D02*
X406641D01*
G01D02*
Y425430D01*
G01D02*
X421641D01*
G01X406641Y433430D02*
X421641D01*
G01X406641Y440230D02*
Y433430D01*
G01X414141Y433530D02*
Y440130D01*
G01X406811Y449530D02*
Y456130D01*
G01X414311Y449430D02*
Y456230D01*
G01X421641Y440230D02*
X406641D01*
G01X421641Y448230D02*
X406641D01*
G01D02*
Y441430D01*
G01X414141Y441530D02*
Y448130D01*
G01X406641Y441430D02*
X421641D01*
G01X406811Y457274D02*
Y463874D01*
G01X414311Y457174D02*
Y463974D01*
G01X402177Y588121D02*
Y595521D01*
G01X418322Y645166D02*
X418477Y644936D01*
X418580Y644668D01*
Y644361D01*
X418425Y644016D01*
X418167Y643748D01*
X417857Y643556D01*
X417340Y643403D01*
X416875Y643365D01*
X416410Y643441D01*
X416100Y643556D01*
X415790Y643786D01*
X415583Y644055D01*
X415480Y644323D01*
Y644591D01*
X415583Y644860D01*
X415738Y645090D01*
X415945Y645281D01*
G01Y646580D02*
X415687Y646810D01*
X415532Y647078D01*
X415480Y647423D01*
X415583Y647768D01*
X415790Y648036D01*
X416152Y648228D01*
X416565Y648266D01*
X416978Y648190D01*
X417237Y647998D01*
X417443Y647730D01*
X417495Y647461D01*
X417443Y647193D01*
X417237Y646848D01*
X418580Y646963D01*
Y647998D01*
G01X415480Y650446D02*
X416152Y650523D01*
X416720Y650638D01*
X417237Y650791D01*
X417805Y650983D01*
X418580Y651290D01*
Y649756D01*
G01X416772Y652895D02*
X417133Y653163D01*
X417340Y653393D01*
X417443Y653700D01*
X417340Y653968D01*
X417133Y654160D01*
X416823Y654313D01*
X416462Y654351D01*
X416152Y654313D01*
X415842Y654160D01*
X415583Y653930D01*
X415480Y653661D01*
X415583Y653355D01*
X415893Y653086D01*
X416358Y652933D01*
X416875Y652895D01*
X417547Y652971D01*
X417908Y653086D01*
X418270Y653278D01*
X418528Y653546D01*
X418580Y653815D01*
X418477Y654083D01*
X418218Y654275D01*
G01X425123Y662337D02*
Y660115D01*
X424970Y659650D01*
X424663Y659340D01*
X424280Y659237D01*
X423897Y659340D01*
X423590Y659650D01*
X423437Y660115D01*
Y662337D01*
G01X421180Y659237D02*
Y662337D01*
X421640Y661717D01*
G01Y659237D02*
X420720D01*
G01X418923Y659857D02*
X418693Y659495D01*
X418387Y659289D01*
X418042Y659237D01*
X417735Y659289D01*
X417428Y659547D01*
X417237Y659857D01*
X417198Y660167D01*
X417275Y660529D01*
X417543Y660787D01*
X417812Y660890D01*
X418157D01*
G01X417812D02*
X417582Y661045D01*
X417390Y661304D01*
X417313Y661614D01*
X417390Y661924D01*
X417582Y662182D01*
X417927Y662337D01*
X418272Y662285D01*
X418617Y662079D01*
G01X415823Y659857D02*
X415593Y659495D01*
X415287Y659289D01*
X414942Y659237D01*
X414635Y659289D01*
X414328Y659547D01*
X414137Y659857D01*
X414098Y660167D01*
X414175Y660529D01*
X414443Y660787D01*
X414712Y660890D01*
X415057D01*
G01X414712D02*
X414482Y661045D01*
X414290Y661304D01*
X414213Y661614D01*
X414290Y661924D01*
X414482Y662182D01*
X414827Y662337D01*
X415172Y662285D01*
X415517Y662079D01*
G01X404606Y647838D02*
Y660838D01*
G01X409006Y651838D02*
X406006D01*
G01X409106Y654938D02*
X405906D01*
G01X409106Y648738D02*
Y654938D01*
G01X405906Y648738D02*
X409106D01*
G01X405906Y654938D02*
Y648738D01*
G01X406900Y662737D02*
Y671537D01*
G01X401200D02*
X406900D01*
G01X423550Y678660D02*
X423780Y678815D01*
X424048Y678918D01*
X424355D01*
X424700Y678763D01*
X424968Y678505D01*
X425160Y678195D01*
X425313Y677678D01*
X425351Y677213D01*
X425275Y676748D01*
X425160Y676438D01*
X424930Y676128D01*
X424661Y675921D01*
X424393Y675818D01*
X424125D01*
X423856Y675921D01*
X423626Y676076D01*
X423435Y676283D01*
G01X422136D02*
X421906Y676025D01*
X421638Y675870D01*
X421293Y675818D01*
X420948Y675921D01*
X420680Y676128D01*
X420488Y676490D01*
X420450Y676903D01*
X420526Y677316D01*
X420718Y677575D01*
X420986Y677781D01*
X421255Y677833D01*
X421523Y677781D01*
X421868Y677575D01*
X421753Y678918D01*
X420718D01*
G01X418270Y675818D02*
X418193Y676490D01*
X418078Y677058D01*
X417925Y677575D01*
X417733Y678143D01*
X417426Y678918D01*
X418960D01*
G01X415093Y675818D02*
Y678918D01*
X415553Y678298D01*
G01Y675818D02*
X414633D01*
G01X406868Y674583D02*
Y677783D01*
G01X400668Y674583D02*
X406868D01*
G01X400668Y677783D02*
Y674583D01*
G01X424598Y670969D02*
Y674069D01*
X423639D01*
X423333Y673914D01*
X423141Y673707D01*
X423064Y673294D01*
X423141Y672881D01*
X423371Y672622D01*
X423639Y672467D01*
X424598D01*
G01X423639D02*
X423064Y670969D01*
G01X420808D02*
X420731Y671641D01*
X420616Y672209D01*
X420463Y672726D01*
X420271Y673294D01*
X419964Y674069D01*
X421498D01*
G01X417708Y670969D02*
X417631Y671641D01*
X417516Y672209D01*
X417363Y672726D01*
X417171Y673294D01*
X416864Y674069D01*
X418398D01*
G01X414531Y670969D02*
X414263Y671021D01*
X413956Y671176D01*
X413764Y671434D01*
X413688Y671796D01*
X413764Y672157D01*
X413994Y672467D01*
X414339Y672622D01*
X414723D01*
X414953Y672726D01*
X415144Y672984D01*
X415221Y673346D01*
X415106Y673707D01*
X414838Y673966D01*
X414531Y674069D01*
X414224Y673966D01*
X413956Y673707D01*
X413841Y673346D01*
X413918Y672984D01*
X414109Y672726D01*
X414339Y672622D01*
X414723D01*
X415068Y672467D01*
X415298Y672157D01*
X415374Y671796D01*
X415298Y671434D01*
X415106Y671176D01*
X414799Y671021D01*
X414531Y670969D01*
G01X403340Y679556D02*
Y710756D01*
G01X406868Y677783D02*
X400668D01*
G01X417025Y702823D02*
X420125D01*
Y703782D01*
X419970Y704088D01*
X419763Y704280D01*
X419350Y704357D01*
X418937Y704280D01*
X418678Y704050D01*
X418523Y703782D01*
Y702823D01*
G01Y703782D02*
X417025Y704357D01*
G01Y706690D02*
X417077Y706958D01*
X417232Y707265D01*
X417490Y707457D01*
X417852Y707533D01*
X418213Y707457D01*
X418523Y707227D01*
X418678Y706882D01*
Y706498D01*
X418782Y706268D01*
X419040Y706077D01*
X419402Y706000D01*
X419763Y706115D01*
X420022Y706383D01*
X420125Y706690D01*
X420022Y706997D01*
X419763Y707265D01*
X419402Y707380D01*
X419040Y707303D01*
X418782Y707112D01*
X418678Y706882D01*
Y706498D01*
X418523Y706153D01*
X418213Y705923D01*
X417852Y705847D01*
X417490Y705923D01*
X417232Y706115D01*
X417077Y706422D01*
X417025Y706690D01*
G01X420125Y709790D02*
X420022Y709483D01*
X419763Y709253D01*
X419453Y709100D01*
X419040Y708985D01*
X418575Y708947D01*
X418110Y708985D01*
X417697Y709100D01*
X417387Y709253D01*
X417128Y709483D01*
X417025Y709790D01*
X417128Y710097D01*
X417387Y710327D01*
X417697Y710480D01*
X418110Y710595D01*
X418575Y710633D01*
X419040Y710595D01*
X419453Y710480D01*
X419763Y710327D01*
X420022Y710097D01*
X420125Y709790D01*
G01X417645Y712047D02*
X417283Y712277D01*
X417077Y712583D01*
X417025Y712928D01*
X417077Y713235D01*
X417335Y713542D01*
X417645Y713733D01*
X417955Y713772D01*
X418317Y713695D01*
X418575Y713427D01*
X418678Y713158D01*
Y712813D01*
G01Y713158D02*
X418833Y713388D01*
X419092Y713580D01*
X419402Y713657D01*
X419712Y713580D01*
X419970Y713388D01*
X420125Y713043D01*
X420073Y712698D01*
X419867Y712353D01*
G01X420057Y715484D02*
Y718584D01*
X419098D01*
X418792Y718429D01*
X418600Y718222D01*
X418523Y717809D01*
X418600Y717396D01*
X418830Y717137D01*
X419098Y716982D01*
X420057D01*
G01X419098D02*
X418523Y715484D01*
G01X416190D02*
Y718584D01*
X416650Y717964D01*
G01Y715484D02*
X415730D01*
G01X413090Y718584D02*
X413397Y718481D01*
X413627Y718222D01*
X413780Y717912D01*
X413895Y717499D01*
X413933Y717034D01*
X413895Y716569D01*
X413780Y716156D01*
X413627Y715846D01*
X413397Y715587D01*
X413090Y715484D01*
X412783Y715587D01*
X412553Y715846D01*
X412400Y716156D01*
X412285Y716569D01*
X412247Y717034D01*
X412285Y717499D01*
X412400Y717912D01*
X412553Y718222D01*
X412783Y718481D01*
X413090Y718584D01*
G01X410718Y716776D02*
X410450Y717137D01*
X410220Y717344D01*
X409913Y717447D01*
X409645Y717344D01*
X409453Y717137D01*
X409300Y716827D01*
X409262Y716466D01*
X409300Y716156D01*
X409453Y715846D01*
X409683Y715587D01*
X409952Y715484D01*
X410258Y715587D01*
X410527Y715897D01*
X410680Y716362D01*
X410718Y716879D01*
X410642Y717551D01*
X410527Y717912D01*
X410335Y718274D01*
X410067Y718532D01*
X409798Y718584D01*
X409530Y718481D01*
X409338Y718222D01*
G01X406890Y718584D02*
X407197Y718481D01*
X407427Y718222D01*
X407580Y717912D01*
X407695Y717499D01*
X407733Y717034D01*
X407695Y716569D01*
X407580Y716156D01*
X407427Y715846D01*
X407197Y715587D01*
X406890Y715484D01*
X406583Y715587D01*
X406353Y715846D01*
X406200Y716156D01*
X406085Y716569D01*
X406047Y717034D01*
X406085Y717499D01*
X406200Y717912D01*
X406353Y718222D01*
X406583Y718481D01*
X406890Y718584D01*
G01X404118Y714654D02*
Y717854D01*
G01X412340Y737556D02*
X415540D01*
G01X412340Y743756D02*
Y737556D01*
G01X415540D02*
Y743756D01*
G01Y732256D02*
X412340D01*
G01Y726056D02*
X415540D01*
G01X412340Y732256D02*
Y726056D01*
G01X415540D02*
Y732256D01*
G01Y743756D02*
X412340D01*
G01X412440Y740656D02*
X415440D01*
G01X410818Y744413D02*
X413918D01*
Y745372D01*
X413763Y745678D01*
X413556Y745870D01*
X413143Y745947D01*
X412730Y745870D01*
X412471Y745640D01*
X412316Y745372D01*
Y744413D01*
G01Y745372D02*
X410818Y745947D01*
G01Y748280D02*
X410870Y748548D01*
X411025Y748855D01*
X411283Y749047D01*
X411645Y749123D01*
X412006Y749047D01*
X412316Y748817D01*
X412471Y748472D01*
Y748088D01*
X412575Y747858D01*
X412833Y747667D01*
X413195Y747590D01*
X413556Y747705D01*
X413815Y747973D01*
X413918Y748280D01*
X413815Y748587D01*
X413556Y748855D01*
X413195Y748970D01*
X412833Y748893D01*
X412575Y748702D01*
X412471Y748472D01*
Y748088D01*
X412316Y747743D01*
X412006Y747513D01*
X411645Y747437D01*
X411283Y747513D01*
X411025Y747705D01*
X410870Y748012D01*
X410818Y748280D01*
G01X411180Y750728D02*
X410921Y750997D01*
X410818Y751303D01*
X410921Y751610D01*
X411231Y751878D01*
X411696Y752070D01*
X412161Y752147D01*
X412730D01*
X413195Y752070D01*
X413608Y751878D01*
X413815Y751648D01*
X413918Y751380D01*
X413815Y751073D01*
X413608Y750843D01*
X413298Y750690D01*
X412885Y750613D01*
X412523Y750690D01*
X412161Y750882D01*
X411955Y751112D01*
X411903Y751380D01*
X412006Y751687D01*
X412265Y751917D01*
X412730Y752147D01*
G01X411180Y753828D02*
X410921Y754097D01*
X410818Y754403D01*
X410921Y754710D01*
X411231Y754978D01*
X411696Y755170D01*
X412161Y755247D01*
X412730D01*
X413195Y755170D01*
X413608Y754978D01*
X413815Y754748D01*
X413918Y754480D01*
X413815Y754173D01*
X413608Y753943D01*
X413298Y753790D01*
X412885Y753713D01*
X412523Y753790D01*
X412161Y753982D01*
X411955Y754212D01*
X411903Y754480D01*
X412006Y754787D01*
X412265Y755017D01*
X412730Y755247D01*
G01X419295Y758804D02*
X419450Y758574D01*
X419553Y758306D01*
Y757999D01*
X419398Y757654D01*
X419140Y757386D01*
X418830Y757194D01*
X418313Y757041D01*
X417848Y757003D01*
X417383Y757079D01*
X417073Y757194D01*
X416763Y757424D01*
X416556Y757693D01*
X416453Y757961D01*
Y758229D01*
X416556Y758498D01*
X416711Y758728D01*
X416918Y758919D01*
G01X417745Y760333D02*
X418106Y760601D01*
X418313Y760831D01*
X418416Y761138D01*
X418313Y761406D01*
X418106Y761598D01*
X417796Y761751D01*
X417435Y761789D01*
X417125Y761751D01*
X416815Y761598D01*
X416556Y761368D01*
X416453Y761099D01*
X416556Y760793D01*
X416866Y760524D01*
X417331Y760371D01*
X417848Y760333D01*
X418520Y760409D01*
X418881Y760524D01*
X419243Y760716D01*
X419501Y760984D01*
X419553Y761253D01*
X419450Y761521D01*
X419191Y761713D01*
G01X416918Y763318D02*
X416660Y763548D01*
X416505Y763816D01*
X416453Y764161D01*
X416556Y764506D01*
X416763Y764774D01*
X417125Y764966D01*
X417538Y765004D01*
X417951Y764928D01*
X418210Y764736D01*
X418416Y764468D01*
X418468Y764199D01*
X418416Y763931D01*
X418210Y763586D01*
X419553Y763701D01*
Y764736D01*
G01X416815Y766609D02*
X416556Y766878D01*
X416453Y767184D01*
X416556Y767491D01*
X416866Y767759D01*
X417331Y767951D01*
X417796Y768028D01*
X418365D01*
X418830Y767951D01*
X419243Y767759D01*
X419450Y767529D01*
X419553Y767261D01*
X419450Y766954D01*
X419243Y766724D01*
X418933Y766571D01*
X418520Y766494D01*
X418158Y766571D01*
X417796Y766763D01*
X417590Y766993D01*
X417538Y767261D01*
X417641Y767568D01*
X417900Y767798D01*
X418365Y768028D01*
G01X415110Y758804D02*
X415265Y758574D01*
X415368Y758306D01*
Y757999D01*
X415213Y757654D01*
X414955Y757386D01*
X414645Y757194D01*
X414128Y757041D01*
X413663Y757003D01*
X413198Y757079D01*
X412888Y757194D01*
X412578Y757424D01*
X412371Y757693D01*
X412268Y757961D01*
Y758229D01*
X412371Y758498D01*
X412526Y758728D01*
X412733Y758919D01*
G01X413560Y760333D02*
X413921Y760601D01*
X414128Y760831D01*
X414231Y761138D01*
X414128Y761406D01*
X413921Y761598D01*
X413611Y761751D01*
X413250Y761789D01*
X412940Y761751D01*
X412630Y761598D01*
X412371Y761368D01*
X412268Y761099D01*
X412371Y760793D01*
X412681Y760524D01*
X413146Y760371D01*
X413663Y760333D01*
X414335Y760409D01*
X414696Y760524D01*
X415058Y760716D01*
X415316Y760984D01*
X415368Y761253D01*
X415265Y761521D01*
X415006Y761713D01*
G01X413560Y763433D02*
X413921Y763701D01*
X414128Y763931D01*
X414231Y764238D01*
X414128Y764506D01*
X413921Y764698D01*
X413611Y764851D01*
X413250Y764889D01*
X412940Y764851D01*
X412630Y764698D01*
X412371Y764468D01*
X412268Y764199D01*
X412371Y763893D01*
X412681Y763624D01*
X413146Y763471D01*
X413663Y763433D01*
X414335Y763509D01*
X414696Y763624D01*
X415058Y763816D01*
X415316Y764084D01*
X415368Y764353D01*
X415265Y764621D01*
X415006Y764813D01*
G01X414851Y766533D02*
X415161Y766763D01*
X415316Y767031D01*
X415368Y767338D01*
X415265Y767721D01*
X415006Y767989D01*
X414696Y768066D01*
X414386Y768028D01*
X414128Y767874D01*
X413611Y767108D01*
X413250Y766763D01*
X412733Y766533D01*
X412268Y766456D01*
Y768066D01*
G01X500800Y782281D02*
X406951D01*
G01X416116Y793279D02*
X415158Y796379D01*
X414200Y793279D01*
G01X414545Y794364D02*
X415771D01*
G01X412058Y793279D02*
X411790Y793331D01*
X411483Y793486D01*
X411291Y793744D01*
X411215Y794106D01*
X411291Y794467D01*
X411521Y794777D01*
X411866Y794932D01*
X412250D01*
X412480Y795036D01*
X412671Y795294D01*
X412748Y795656D01*
X412633Y796017D01*
X412365Y796276D01*
X412058Y796379D01*
X411751Y796276D01*
X411483Y796017D01*
X411368Y795656D01*
X411445Y795294D01*
X411636Y795036D01*
X411866Y794932D01*
X412250D01*
X412595Y794777D01*
X412825Y794467D01*
X412901Y794106D01*
X412825Y793744D01*
X412633Y793486D01*
X412326Y793331D01*
X412058Y793279D01*
G01X409686Y795862D02*
X409456Y796172D01*
X409188Y796327D01*
X408881Y796379D01*
X408498Y796276D01*
X408230Y796017D01*
X408153Y795707D01*
X408191Y795397D01*
X408345Y795139D01*
X409111Y794622D01*
X409456Y794261D01*
X409686Y793744D01*
X409763Y793279D01*
X408153D01*
G01X421641Y409430D02*
Y416230D01*
G01Y417430D02*
Y424230D01*
G01Y425430D02*
Y432230D01*
G01Y433430D02*
Y440230D01*
G01Y441430D02*
Y448230D01*
G01X426456Y504248D02*
X429556D01*
Y505168D01*
X429401Y505475D01*
X429039Y505705D01*
X428626Y505782D01*
X428213Y505705D01*
X427903Y505513D01*
X427748Y505168D01*
Y504248D01*
G01X426456Y507348D02*
X429556D01*
Y508307D01*
X429401Y508613D01*
X429194Y508805D01*
X428781Y508882D01*
X428368Y508805D01*
X428109Y508575D01*
X427954Y508307D01*
Y507348D01*
G01Y508307D02*
X426456Y508882D01*
G01X426921Y510372D02*
X426663Y510602D01*
X426508Y510870D01*
X426456Y511215D01*
X426559Y511560D01*
X426766Y511828D01*
X427128Y512020D01*
X427541Y512058D01*
X427954Y511982D01*
X428213Y511790D01*
X428419Y511522D01*
X428471Y511253D01*
X428419Y510985D01*
X428213Y510640D01*
X429556Y510755D01*
Y511790D01*
G01X427076Y513472D02*
X426714Y513702D01*
X426508Y514008D01*
X426456Y514353D01*
X426508Y514660D01*
X426766Y514967D01*
X427076Y515158D01*
X427386Y515197D01*
X427748Y515120D01*
X428006Y514852D01*
X428109Y514583D01*
Y514238D01*
G01Y514583D02*
X428264Y514813D01*
X428523Y515005D01*
X428833Y515082D01*
X429143Y515005D01*
X429401Y514813D01*
X429556Y514468D01*
X429504Y514123D01*
X429298Y513778D01*
G01X428679Y517729D02*
Y523929D01*
G01X425479Y517729D02*
X428679D01*
G01X425479Y523929D02*
Y517729D01*
G01X428679Y523929D02*
X425479D01*
G01X436655Y532523D02*
Y535623D01*
X435735D01*
X435428Y535468D01*
X435198Y535106D01*
X435121Y534693D01*
X435198Y534280D01*
X435390Y533970D01*
X435735Y533815D01*
X436655D01*
G01X433555Y532523D02*
Y535623D01*
X432596D01*
X432290Y535468D01*
X432098Y535261D01*
X432021Y534848D01*
X432098Y534435D01*
X432328Y534176D01*
X432596Y534021D01*
X433555D01*
G01X432596D02*
X432021Y532523D01*
G01X429228D02*
Y535623D01*
X430646Y533401D01*
X428730D01*
G01X426588Y532523D02*
Y535623D01*
X427048Y535003D01*
G01Y532523D02*
X426128D01*
G01X432400Y543307D02*
X422200D01*
G01D02*
Y538707D01*
G01D02*
X432400D01*
G01X455818Y555958D02*
X457009D01*
Y628112D01*
X447481D01*
Y632569D01*
X418399D01*
Y559844D01*
X441463D01*
Y555707D01*
X451493D01*
G01X430276Y563392D02*
Y566492D01*
X429317D01*
X429011Y566337D01*
X428819Y566130D01*
X428742Y565717D01*
X428819Y565304D01*
X429049Y565045D01*
X429317Y564890D01*
X430276D01*
G01X429317D02*
X428742Y563392D01*
G01X426486D02*
X426409Y564064D01*
X426294Y564632D01*
X426141Y565149D01*
X425949Y565717D01*
X425642Y566492D01*
X427176D01*
G01X423309Y563392D02*
X423041Y563444D01*
X422734Y563599D01*
X422542Y563857D01*
X422466Y564219D01*
X422542Y564580D01*
X422772Y564890D01*
X423117Y565045D01*
X423501D01*
X423731Y565149D01*
X423922Y565407D01*
X423999Y565769D01*
X423884Y566130D01*
X423616Y566389D01*
X423309Y566492D01*
X423002Y566389D01*
X422734Y566130D01*
X422619Y565769D01*
X422696Y565407D01*
X422887Y565149D01*
X423117Y565045D01*
X423501D01*
X423846Y564890D01*
X424076Y564580D01*
X424152Y564219D01*
X424076Y563857D01*
X423884Y563599D01*
X423577Y563444D01*
X423309Y563392D01*
G01X421052Y564012D02*
X420822Y563650D01*
X420516Y563444D01*
X420171Y563392D01*
X419864Y563444D01*
X419557Y563702D01*
X419366Y564012D01*
X419327Y564322D01*
X419404Y564684D01*
X419672Y564942D01*
X419941Y565045D01*
X420286D01*
G01X419941D02*
X419711Y565200D01*
X419519Y565459D01*
X419442Y565769D01*
X419519Y566079D01*
X419711Y566337D01*
X420056Y566492D01*
X420401Y566440D01*
X420746Y566234D01*
G01X430276Y567352D02*
Y570452D01*
X429317D01*
X429011Y570297D01*
X428819Y570090D01*
X428742Y569677D01*
X428819Y569264D01*
X429049Y569005D01*
X429317Y568850D01*
X430276D01*
G01X429317D02*
X428742Y567352D01*
G01X426486D02*
X426409Y568024D01*
X426294Y568592D01*
X426141Y569109D01*
X425949Y569677D01*
X425642Y570452D01*
X427176D01*
G01X423309Y567352D02*
X423041Y567404D01*
X422734Y567559D01*
X422542Y567817D01*
X422466Y568179D01*
X422542Y568540D01*
X422772Y568850D01*
X423117Y569005D01*
X423501D01*
X423731Y569109D01*
X423922Y569367D01*
X423999Y569729D01*
X423884Y570090D01*
X423616Y570349D01*
X423309Y570452D01*
X423002Y570349D01*
X422734Y570090D01*
X422619Y569729D01*
X422696Y569367D01*
X422887Y569109D01*
X423117Y569005D01*
X423501D01*
X423846Y568850D01*
X424076Y568540D01*
X424152Y568179D01*
X424076Y567817D01*
X423884Y567559D01*
X423577Y567404D01*
X423309Y567352D01*
G01X420937Y569935D02*
X420707Y570245D01*
X420439Y570400D01*
X420132Y570452D01*
X419749Y570349D01*
X419481Y570090D01*
X419404Y569780D01*
X419442Y569470D01*
X419596Y569212D01*
X420362Y568695D01*
X420707Y568334D01*
X420937Y567817D01*
X421014Y567352D01*
X419404D01*
G01X430464Y576162D02*
Y579262D01*
X429505D01*
X429199Y579107D01*
X429007Y578900D01*
X428930Y578487D01*
X429007Y578074D01*
X429237Y577815D01*
X429505Y577660D01*
X430464D01*
G01X429505D02*
X428930Y576162D01*
G01X426674D02*
X426597Y576834D01*
X426482Y577402D01*
X426329Y577919D01*
X426137Y578487D01*
X425830Y579262D01*
X427364D01*
G01X424149Y576524D02*
X423880Y576265D01*
X423574Y576162D01*
X423267Y576265D01*
X422999Y576575D01*
X422807Y577040D01*
X422730Y577505D01*
Y578074D01*
X422807Y578539D01*
X422999Y578952D01*
X423229Y579159D01*
X423497Y579262D01*
X423804Y579159D01*
X424034Y578952D01*
X424187Y578642D01*
X424264Y578229D01*
X424187Y577867D01*
X423995Y577505D01*
X423765Y577299D01*
X423497Y577247D01*
X423190Y577350D01*
X422960Y577609D01*
X422730Y578074D01*
G01X420397Y579262D02*
X420704Y579159D01*
X420934Y578900D01*
X421087Y578590D01*
X421202Y578177D01*
X421240Y577712D01*
X421202Y577247D01*
X421087Y576834D01*
X420934Y576524D01*
X420704Y576265D01*
X420397Y576162D01*
X420090Y576265D01*
X419860Y576524D01*
X419707Y576834D01*
X419592Y577247D01*
X419554Y577712D01*
X419592Y578177D01*
X419707Y578590D01*
X419860Y578900D01*
X420090Y579159D01*
X420397Y579262D01*
G01X430464Y580123D02*
Y583223D01*
X429505D01*
X429199Y583068D01*
X429007Y582861D01*
X428930Y582448D01*
X429007Y582035D01*
X429237Y581776D01*
X429505Y581621D01*
X430464D01*
G01X429505D02*
X428930Y580123D01*
G01X426674D02*
X426597Y580795D01*
X426482Y581363D01*
X426329Y581880D01*
X426137Y582448D01*
X425830Y583223D01*
X427364D01*
G01X423574Y580123D02*
X423497Y580795D01*
X423382Y581363D01*
X423229Y581880D01*
X423037Y582448D01*
X422730Y583223D01*
X424264D01*
G01X421049Y580485D02*
X420780Y580226D01*
X420474Y580123D01*
X420167Y580226D01*
X419899Y580536D01*
X419707Y581001D01*
X419630Y581466D01*
Y582035D01*
X419707Y582500D01*
X419899Y582913D01*
X420129Y583120D01*
X420397Y583223D01*
X420704Y583120D01*
X420934Y582913D01*
X421087Y582603D01*
X421164Y582190D01*
X421087Y581828D01*
X420895Y581466D01*
X420665Y581260D01*
X420397Y581208D01*
X420090Y581311D01*
X419860Y581570D01*
X419630Y582035D01*
G01X430276Y571404D02*
Y574504D01*
X429317D01*
X429011Y574349D01*
X428819Y574142D01*
X428742Y573729D01*
X428819Y573316D01*
X429049Y573057D01*
X429317Y572902D01*
X430276D01*
G01X429317D02*
X428742Y571404D01*
G01X426486D02*
X426409Y572076D01*
X426294Y572644D01*
X426141Y573161D01*
X425949Y573729D01*
X425642Y574504D01*
X427176D01*
G01X423961Y571766D02*
X423692Y571507D01*
X423386Y571404D01*
X423079Y571507D01*
X422811Y571817D01*
X422619Y572282D01*
X422542Y572747D01*
Y573316D01*
X422619Y573781D01*
X422811Y574194D01*
X423041Y574401D01*
X423309Y574504D01*
X423616Y574401D01*
X423846Y574194D01*
X423999Y573884D01*
X424076Y573471D01*
X423999Y573109D01*
X423807Y572747D01*
X423577Y572541D01*
X423309Y572489D01*
X423002Y572592D01*
X422772Y572851D01*
X422542Y573316D01*
G01X420209Y571404D02*
Y574504D01*
X420669Y573884D01*
G01Y571404D02*
X419749D01*
G01X430464Y592467D02*
Y595567D01*
X429505D01*
X429199Y595412D01*
X429007Y595205D01*
X428930Y594792D01*
X429007Y594379D01*
X429237Y594120D01*
X429505Y593965D01*
X430464D01*
G01X429505D02*
X428930Y592467D01*
G01X427325Y593759D02*
X427057Y594120D01*
X426827Y594327D01*
X426520Y594430D01*
X426252Y594327D01*
X426060Y594120D01*
X425907Y593810D01*
X425869Y593449D01*
X425907Y593139D01*
X426060Y592829D01*
X426290Y592570D01*
X426559Y592467D01*
X426865Y592570D01*
X427134Y592880D01*
X427287Y593345D01*
X427325Y593862D01*
X427249Y594534D01*
X427134Y594895D01*
X426942Y595257D01*
X426674Y595515D01*
X426405Y595567D01*
X426137Y595464D01*
X425945Y595205D01*
G01X424149Y592829D02*
X423880Y592570D01*
X423574Y592467D01*
X423267Y592570D01*
X422999Y592880D01*
X422807Y593345D01*
X422730Y593810D01*
Y594379D01*
X422807Y594844D01*
X422999Y595257D01*
X423229Y595464D01*
X423497Y595567D01*
X423804Y595464D01*
X424034Y595257D01*
X424187Y594947D01*
X424264Y594534D01*
X424187Y594172D01*
X423995Y593810D01*
X423765Y593604D01*
X423497Y593552D01*
X423190Y593655D01*
X422960Y593914D01*
X422730Y594379D01*
G01X420397Y595567D02*
X420704Y595464D01*
X420934Y595205D01*
X421087Y594895D01*
X421202Y594482D01*
X421240Y594017D01*
X421202Y593552D01*
X421087Y593139D01*
X420934Y592829D01*
X420704Y592570D01*
X420397Y592467D01*
X420090Y592570D01*
X419860Y592829D01*
X419707Y593139D01*
X419592Y593552D01*
X419554Y594017D01*
X419592Y594482D01*
X419707Y594895D01*
X419860Y595205D01*
X420090Y595464D01*
X420397Y595567D01*
G01X430699Y584494D02*
Y587594D01*
X429740D01*
X429434Y587439D01*
X429242Y587232D01*
X429165Y586819D01*
X429242Y586406D01*
X429472Y586147D01*
X429740Y585992D01*
X430699D01*
G01X429740D02*
X429165Y584494D01*
G01X427560Y585786D02*
X427292Y586147D01*
X427062Y586354D01*
X426755Y586457D01*
X426487Y586354D01*
X426295Y586147D01*
X426142Y585837D01*
X426104Y585476D01*
X426142Y585166D01*
X426295Y584856D01*
X426525Y584597D01*
X426794Y584494D01*
X427100Y584597D01*
X427369Y584907D01*
X427522Y585372D01*
X427560Y585889D01*
X427484Y586561D01*
X427369Y586922D01*
X427177Y587284D01*
X426909Y587542D01*
X426640Y587594D01*
X426372Y587491D01*
X426180Y587232D01*
G01X423732Y584494D02*
X423464Y584546D01*
X423157Y584701D01*
X422965Y584959D01*
X422889Y585321D01*
X422965Y585682D01*
X423195Y585992D01*
X423540Y586147D01*
X423924D01*
X424154Y586251D01*
X424345Y586509D01*
X424422Y586871D01*
X424307Y587232D01*
X424039Y587491D01*
X423732Y587594D01*
X423425Y587491D01*
X423157Y587232D01*
X423042Y586871D01*
X423119Y586509D01*
X423310Y586251D01*
X423540Y586147D01*
X423924D01*
X424269Y585992D01*
X424499Y585682D01*
X424575Y585321D01*
X424499Y584959D01*
X424307Y584701D01*
X424000Y584546D01*
X423732Y584494D01*
G01X421284Y584856D02*
X421015Y584597D01*
X420709Y584494D01*
X420402Y584597D01*
X420134Y584907D01*
X419942Y585372D01*
X419865Y585837D01*
Y586406D01*
X419942Y586871D01*
X420134Y587284D01*
X420364Y587491D01*
X420632Y587594D01*
X420939Y587491D01*
X421169Y587284D01*
X421322Y586974D01*
X421399Y586561D01*
X421322Y586199D01*
X421130Y585837D01*
X420900Y585631D01*
X420632Y585579D01*
X420325Y585682D01*
X420095Y585941D01*
X419865Y586406D01*
G01X431419Y588494D02*
Y591594D01*
X430460D01*
X430154Y591439D01*
X429962Y591232D01*
X429885Y590819D01*
X429962Y590406D01*
X430192Y590147D01*
X430460Y589992D01*
X431419D01*
G01X430460D02*
X429885Y588494D01*
G01X428280Y589786D02*
X428012Y590147D01*
X427782Y590354D01*
X427475Y590457D01*
X427207Y590354D01*
X427015Y590147D01*
X426862Y589837D01*
X426824Y589476D01*
X426862Y589166D01*
X427015Y588856D01*
X427245Y588597D01*
X427514Y588494D01*
X427820Y588597D01*
X428089Y588907D01*
X428242Y589372D01*
X428280Y589889D01*
X428204Y590561D01*
X428089Y590922D01*
X427897Y591284D01*
X427629Y591542D01*
X427360Y591594D01*
X427092Y591491D01*
X426900Y591232D01*
G01X424452Y588494D02*
X424184Y588546D01*
X423877Y588701D01*
X423685Y588959D01*
X423609Y589321D01*
X423685Y589682D01*
X423915Y589992D01*
X424260Y590147D01*
X424644D01*
X424874Y590251D01*
X425065Y590509D01*
X425142Y590871D01*
X425027Y591232D01*
X424759Y591491D01*
X424452Y591594D01*
X424145Y591491D01*
X423877Y591232D01*
X423762Y590871D01*
X423839Y590509D01*
X424030Y590251D01*
X424260Y590147D01*
X424644D01*
X424989Y589992D01*
X425219Y589682D01*
X425295Y589321D01*
X425219Y588959D01*
X425027Y588701D01*
X424720Y588546D01*
X424452Y588494D01*
G01X422195Y588959D02*
X421965Y588701D01*
X421697Y588546D01*
X421352Y588494D01*
X421007Y588597D01*
X420739Y588804D01*
X420547Y589166D01*
X420509Y589579D01*
X420585Y589992D01*
X420777Y590251D01*
X421045Y590457D01*
X421314Y590509D01*
X421582Y590457D01*
X421927Y590251D01*
X421812Y591594D01*
X420777D01*
G01X430301Y602595D02*
Y605695D01*
X429342D01*
X429036Y605540D01*
X428844Y605333D01*
X428767Y604920D01*
X428844Y604507D01*
X429074Y604248D01*
X429342Y604093D01*
X430301D01*
G01X429342D02*
X428767Y602595D01*
G01X427162Y603887D02*
X426894Y604248D01*
X426664Y604455D01*
X426357Y604558D01*
X426089Y604455D01*
X425897Y604248D01*
X425744Y603938D01*
X425706Y603577D01*
X425744Y603267D01*
X425897Y602957D01*
X426127Y602698D01*
X426396Y602595D01*
X426702Y602698D01*
X426971Y603008D01*
X427124Y603473D01*
X427162Y603990D01*
X427086Y604662D01*
X426971Y605023D01*
X426779Y605385D01*
X426511Y605643D01*
X426242Y605695D01*
X425974Y605592D01*
X425782Y605333D01*
G01X423986Y602957D02*
X423717Y602698D01*
X423411Y602595D01*
X423104Y602698D01*
X422836Y603008D01*
X422644Y603473D01*
X422567Y603938D01*
Y604507D01*
X422644Y604972D01*
X422836Y605385D01*
X423066Y605592D01*
X423334Y605695D01*
X423641Y605592D01*
X423871Y605385D01*
X424024Y605075D01*
X424101Y604662D01*
X424024Y604300D01*
X423832Y603938D01*
X423602Y603732D01*
X423334Y603680D01*
X423027Y603783D01*
X422797Y604042D01*
X422567Y604507D01*
G01X420962Y605178D02*
X420732Y605488D01*
X420464Y605643D01*
X420157Y605695D01*
X419774Y605592D01*
X419506Y605333D01*
X419429Y605023D01*
X419467Y604713D01*
X419621Y604455D01*
X420387Y603938D01*
X420732Y603577D01*
X420962Y603060D01*
X421039Y602595D01*
X419429D01*
G01X430301Y606595D02*
Y609695D01*
X429342D01*
X429036Y609540D01*
X428844Y609333D01*
X428767Y608920D01*
X428844Y608507D01*
X429074Y608248D01*
X429342Y608093D01*
X430301D01*
G01X429342D02*
X428767Y606595D01*
G01X427162Y607887D02*
X426894Y608248D01*
X426664Y608455D01*
X426357Y608558D01*
X426089Y608455D01*
X425897Y608248D01*
X425744Y607938D01*
X425706Y607577D01*
X425744Y607267D01*
X425897Y606957D01*
X426127Y606698D01*
X426396Y606595D01*
X426702Y606698D01*
X426971Y607008D01*
X427124Y607473D01*
X427162Y607990D01*
X427086Y608662D01*
X426971Y609023D01*
X426779Y609385D01*
X426511Y609643D01*
X426242Y609695D01*
X425974Y609592D01*
X425782Y609333D01*
G01X423986Y606957D02*
X423717Y606698D01*
X423411Y606595D01*
X423104Y606698D01*
X422836Y607008D01*
X422644Y607473D01*
X422567Y607938D01*
Y608507D01*
X422644Y608972D01*
X422836Y609385D01*
X423066Y609592D01*
X423334Y609695D01*
X423641Y609592D01*
X423871Y609385D01*
X424024Y609075D01*
X424101Y608662D01*
X424024Y608300D01*
X423832Y607938D01*
X423602Y607732D01*
X423334Y607680D01*
X423027Y607783D01*
X422797Y608042D01*
X422567Y608507D01*
G01X421077Y607215D02*
X420847Y606853D01*
X420541Y606647D01*
X420196Y606595D01*
X419889Y606647D01*
X419582Y606905D01*
X419391Y607215D01*
X419352Y607525D01*
X419429Y607887D01*
X419697Y608145D01*
X419966Y608248D01*
X420311D01*
G01X419966D02*
X419736Y608403D01*
X419544Y608662D01*
X419467Y608972D01*
X419544Y609282D01*
X419736Y609540D01*
X420081Y609695D01*
X420426Y609643D01*
X420771Y609437D01*
G01X430301Y610595D02*
Y613695D01*
X429342D01*
X429036Y613540D01*
X428844Y613333D01*
X428767Y612920D01*
X428844Y612507D01*
X429074Y612248D01*
X429342Y612093D01*
X430301D01*
G01X429342D02*
X428767Y610595D01*
G01X427162Y611887D02*
X426894Y612248D01*
X426664Y612455D01*
X426357Y612558D01*
X426089Y612455D01*
X425897Y612248D01*
X425744Y611938D01*
X425706Y611577D01*
X425744Y611267D01*
X425897Y610957D01*
X426127Y610698D01*
X426396Y610595D01*
X426702Y610698D01*
X426971Y611008D01*
X427124Y611473D01*
X427162Y611990D01*
X427086Y612662D01*
X426971Y613023D01*
X426779Y613385D01*
X426511Y613643D01*
X426242Y613695D01*
X425974Y613592D01*
X425782Y613333D01*
G01X423986Y610957D02*
X423717Y610698D01*
X423411Y610595D01*
X423104Y610698D01*
X422836Y611008D01*
X422644Y611473D01*
X422567Y611938D01*
Y612507D01*
X422644Y612972D01*
X422836Y613385D01*
X423066Y613592D01*
X423334Y613695D01*
X423641Y613592D01*
X423871Y613385D01*
X424024Y613075D01*
X424101Y612662D01*
X424024Y612300D01*
X423832Y611938D01*
X423602Y611732D01*
X423334Y611680D01*
X423027Y611783D01*
X422797Y612042D01*
X422567Y612507D01*
G01X419774Y610595D02*
Y613695D01*
X421192Y611473D01*
X419276D01*
G01X430301Y598595D02*
Y601695D01*
X429342D01*
X429036Y601540D01*
X428844Y601333D01*
X428767Y600920D01*
X428844Y600507D01*
X429074Y600248D01*
X429342Y600093D01*
X430301D01*
G01X429342D02*
X428767Y598595D01*
G01X427162Y599887D02*
X426894Y600248D01*
X426664Y600455D01*
X426357Y600558D01*
X426089Y600455D01*
X425897Y600248D01*
X425744Y599938D01*
X425706Y599577D01*
X425744Y599267D01*
X425897Y598957D01*
X426127Y598698D01*
X426396Y598595D01*
X426702Y598698D01*
X426971Y599008D01*
X427124Y599473D01*
X427162Y599990D01*
X427086Y600662D01*
X426971Y601023D01*
X426779Y601385D01*
X426511Y601643D01*
X426242Y601695D01*
X425974Y601592D01*
X425782Y601333D01*
G01X423986Y598957D02*
X423717Y598698D01*
X423411Y598595D01*
X423104Y598698D01*
X422836Y599008D01*
X422644Y599473D01*
X422567Y599938D01*
Y600507D01*
X422644Y600972D01*
X422836Y601385D01*
X423066Y601592D01*
X423334Y601695D01*
X423641Y601592D01*
X423871Y601385D01*
X424024Y601075D01*
X424101Y600662D01*
X424024Y600300D01*
X423832Y599938D01*
X423602Y599732D01*
X423334Y599680D01*
X423027Y599783D01*
X422797Y600042D01*
X422567Y600507D01*
G01X420234Y598595D02*
Y601695D01*
X420694Y601075D01*
G01Y598595D02*
X419774D01*
G01X430301Y618595D02*
Y621695D01*
X429342D01*
X429036Y621540D01*
X428844Y621333D01*
X428767Y620920D01*
X428844Y620507D01*
X429074Y620248D01*
X429342Y620093D01*
X430301D01*
G01X429342D02*
X428767Y618595D01*
G01X427162Y619887D02*
X426894Y620248D01*
X426664Y620455D01*
X426357Y620558D01*
X426089Y620455D01*
X425897Y620248D01*
X425744Y619938D01*
X425706Y619577D01*
X425744Y619267D01*
X425897Y618957D01*
X426127Y618698D01*
X426396Y618595D01*
X426702Y618698D01*
X426971Y619008D01*
X427124Y619473D01*
X427162Y619990D01*
X427086Y620662D01*
X426971Y621023D01*
X426779Y621385D01*
X426511Y621643D01*
X426242Y621695D01*
X425974Y621592D01*
X425782Y621333D01*
G01X423986Y618957D02*
X423717Y618698D01*
X423411Y618595D01*
X423104Y618698D01*
X422836Y619008D01*
X422644Y619473D01*
X422567Y619938D01*
Y620507D01*
X422644Y620972D01*
X422836Y621385D01*
X423066Y621592D01*
X423334Y621695D01*
X423641Y621592D01*
X423871Y621385D01*
X424024Y621075D01*
X424101Y620662D01*
X424024Y620300D01*
X423832Y619938D01*
X423602Y619732D01*
X423334Y619680D01*
X423027Y619783D01*
X422797Y620042D01*
X422567Y620507D01*
G01X420962Y619887D02*
X420694Y620248D01*
X420464Y620455D01*
X420157Y620558D01*
X419889Y620455D01*
X419697Y620248D01*
X419544Y619938D01*
X419506Y619577D01*
X419544Y619267D01*
X419697Y618957D01*
X419927Y618698D01*
X420196Y618595D01*
X420502Y618698D01*
X420771Y619008D01*
X420924Y619473D01*
X420962Y619990D01*
X420886Y620662D01*
X420771Y621023D01*
X420579Y621385D01*
X420311Y621643D01*
X420042Y621695D01*
X419774Y621592D01*
X419582Y621333D01*
G01X430301Y614595D02*
Y617695D01*
X429342D01*
X429036Y617540D01*
X428844Y617333D01*
X428767Y616920D01*
X428844Y616507D01*
X429074Y616248D01*
X429342Y616093D01*
X430301D01*
G01X429342D02*
X428767Y614595D01*
G01X427162Y615887D02*
X426894Y616248D01*
X426664Y616455D01*
X426357Y616558D01*
X426089Y616455D01*
X425897Y616248D01*
X425744Y615938D01*
X425706Y615577D01*
X425744Y615267D01*
X425897Y614957D01*
X426127Y614698D01*
X426396Y614595D01*
X426702Y614698D01*
X426971Y615008D01*
X427124Y615473D01*
X427162Y615990D01*
X427086Y616662D01*
X426971Y617023D01*
X426779Y617385D01*
X426511Y617643D01*
X426242Y617695D01*
X425974Y617592D01*
X425782Y617333D01*
G01X423986Y614957D02*
X423717Y614698D01*
X423411Y614595D01*
X423104Y614698D01*
X422836Y615008D01*
X422644Y615473D01*
X422567Y615938D01*
Y616507D01*
X422644Y616972D01*
X422836Y617385D01*
X423066Y617592D01*
X423334Y617695D01*
X423641Y617592D01*
X423871Y617385D01*
X424024Y617075D01*
X424101Y616662D01*
X424024Y616300D01*
X423832Y615938D01*
X423602Y615732D01*
X423334Y615680D01*
X423027Y615783D01*
X422797Y616042D01*
X422567Y616507D01*
G01X421077Y615060D02*
X420847Y614802D01*
X420579Y614647D01*
X420234Y614595D01*
X419889Y614698D01*
X419621Y614905D01*
X419429Y615267D01*
X419391Y615680D01*
X419467Y616093D01*
X419659Y616352D01*
X419927Y616558D01*
X420196Y616610D01*
X420464Y616558D01*
X420809Y616352D01*
X420694Y617695D01*
X419659D01*
G01X444197Y656958D02*
Y660058D01*
X443238D01*
X442932Y659903D01*
X442740Y659696D01*
X442663Y659283D01*
X442740Y658870D01*
X442970Y658611D01*
X443238Y658456D01*
X444197D01*
G01X443238D02*
X442663Y656958D01*
G01X440330D02*
Y660058D01*
X440790Y659438D01*
G01Y656958D02*
X439870D01*
G01X437958Y659541D02*
X437728Y659851D01*
X437460Y660006D01*
X437153Y660058D01*
X436770Y659955D01*
X436502Y659696D01*
X436425Y659386D01*
X436463Y659076D01*
X436617Y658818D01*
X437383Y658301D01*
X437728Y657940D01*
X437958Y657423D01*
X438035Y656958D01*
X436425D01*
G01X433670D02*
Y660058D01*
X435088Y657836D01*
X433172D01*
G01X431873Y657578D02*
X431643Y657216D01*
X431337Y657010D01*
X430992Y656958D01*
X430685Y657010D01*
X430378Y657268D01*
X430187Y657578D01*
X430148Y657888D01*
X430225Y658250D01*
X430493Y658508D01*
X430762Y658611D01*
X431107D01*
G01X430762D02*
X430532Y658766D01*
X430340Y659025D01*
X430263Y659335D01*
X430340Y659645D01*
X430532Y659903D01*
X430877Y660058D01*
X431222Y660006D01*
X431567Y659800D01*
G01X437700Y670746D02*
Y673846D01*
X436741D01*
X436435Y673691D01*
X436243Y673484D01*
X436166Y673071D01*
X436243Y672658D01*
X436473Y672399D01*
X436741Y672244D01*
X437700D01*
G01X436741D02*
X436166Y670746D01*
G01X433910D02*
X433833Y671418D01*
X433718Y671986D01*
X433565Y672503D01*
X433373Y673071D01*
X433066Y673846D01*
X434600D01*
G01X431385Y671108D02*
X431116Y670849D01*
X430810Y670746D01*
X430503Y670849D01*
X430235Y671159D01*
X430043Y671624D01*
X429966Y672089D01*
Y672658D01*
X430043Y673123D01*
X430235Y673536D01*
X430465Y673743D01*
X430733Y673846D01*
X431040Y673743D01*
X431270Y673536D01*
X431423Y673226D01*
X431500Y672813D01*
X431423Y672451D01*
X431231Y672089D01*
X431001Y671883D01*
X430733Y671831D01*
X430426Y671934D01*
X430196Y672193D01*
X429966Y672658D01*
G01X428285Y671108D02*
X428016Y670849D01*
X427710Y670746D01*
X427403Y670849D01*
X427135Y671159D01*
X426943Y671624D01*
X426866Y672089D01*
Y672658D01*
X426943Y673123D01*
X427135Y673536D01*
X427365Y673743D01*
X427633Y673846D01*
X427940Y673743D01*
X428170Y673536D01*
X428323Y673226D01*
X428400Y672813D01*
X428323Y672451D01*
X428131Y672089D01*
X427901Y671883D01*
X427633Y671831D01*
X427326Y671934D01*
X427096Y672193D01*
X426866Y672658D01*
G01X447900Y720370D02*
X441327D01*
Y721895D01*
X431322D01*
Y717323D01*
X430395D01*
Y676230D01*
X464640D01*
G01X419638Y683069D02*
Y680069D01*
G01X416538Y683169D02*
Y679969D01*
G01X422738Y683169D02*
X416538D01*
G01X422738Y679969D02*
Y683169D01*
G01X416538Y679969D02*
X422738D01*
G01X425981Y683339D02*
X429081D01*
Y684298D01*
X428926Y684604D01*
X428719Y684796D01*
X428306Y684873D01*
X427893Y684796D01*
X427634Y684566D01*
X427479Y684298D01*
Y683339D01*
G01Y684298D02*
X425981Y684873D01*
G01Y687129D02*
X426653Y687206D01*
X427221Y687321D01*
X427738Y687474D01*
X428306Y687666D01*
X429081Y687973D01*
Y686439D01*
G01Y690306D02*
X428978Y689999D01*
X428719Y689769D01*
X428409Y689616D01*
X427996Y689501D01*
X427531Y689463D01*
X427066Y689501D01*
X426653Y689616D01*
X426343Y689769D01*
X426084Y689999D01*
X425981Y690306D01*
X426084Y690613D01*
X426343Y690843D01*
X426653Y690996D01*
X427066Y691111D01*
X427531Y691149D01*
X427996Y691111D01*
X428409Y690996D01*
X428719Y690843D01*
X428978Y690613D01*
X429081Y690306D01*
G01X425981Y693866D02*
X429081D01*
X426859Y692448D01*
Y694364D01*
G01X417327Y687254D02*
Y684054D01*
G01X423527Y687254D02*
X417327D01*
G01X423527Y684054D02*
Y687254D01*
G01X417327Y684054D02*
X423527D01*
G01X431740Y688756D02*
Y685556D01*
G01X437940Y688756D02*
X431740D01*
G01Y685556D02*
X437940D01*
G01X431740Y677556D02*
X437940D01*
G01X431740Y680756D02*
Y677556D01*
G01X437940Y680756D02*
X431740D01*
G01Y684756D02*
Y681556D01*
G01X437940Y684756D02*
X431740D01*
G01Y681556D02*
X437940D01*
G01X431740Y692756D02*
Y689556D01*
G01D02*
X437940D01*
G01X418689Y695985D02*
X421889D01*
G01X418689Y702185D02*
Y695985D01*
G01X421889D02*
Y702185D01*
G01D02*
X418689D01*
G01X431740Y708756D02*
Y705556D01*
G01D02*
X437940D01*
G01X431740Y704756D02*
Y701556D01*
G01X437940Y704756D02*
X431740D01*
G01Y701556D02*
X437940D01*
G01X431740Y700756D02*
Y697556D01*
G01X437940Y700756D02*
X431740D01*
G01Y697556D02*
X437940D01*
G01X431740Y696756D02*
Y693556D01*
G01X437940Y696756D02*
X431740D01*
G01Y693556D02*
X437940D01*
G01Y692756D02*
X431740D01*
G01Y712756D02*
Y709556D01*
G01X437940Y712756D02*
X431740D01*
G01Y709556D02*
X437940D01*
G01X431740Y716756D02*
Y713556D01*
G01X437940Y716756D02*
X431740D01*
G01Y713556D02*
X437940D01*
G01Y708756D02*
X431740D01*
G01X421341Y726056D02*
X424539D01*
G01X421341Y732256D02*
Y726056D01*
G01X424539Y732256D02*
X421341D01*
G01X421440Y729156D02*
X424440D01*
G01X424539Y726056D02*
Y732256D01*
G01X425340Y737556D02*
X428540D01*
G01X425340Y743756D02*
Y737556D01*
G01X428540D02*
Y743756D01*
G01X425840Y726056D02*
X429040D01*
G01X425840Y732256D02*
Y726056D01*
G01X429040Y732256D02*
X425840D01*
G01X425940Y729156D02*
X428940D01*
G01X429040Y726056D02*
Y732256D01*
G01X416840Y737556D02*
X420040D01*
G01X416840Y743756D02*
Y737556D01*
G01X420040D02*
Y743756D01*
G01X421340Y737556D02*
X424540D01*
G01X421340Y743756D02*
Y737556D01*
G01X424540D02*
Y743756D01*
G01X429840Y737556D02*
X433040D01*
G01X429840Y743756D02*
Y737556D01*
G01X420040Y732256D02*
X416840D01*
G01X420040Y726056D02*
Y732256D01*
G01X416840Y726056D02*
X420040D01*
G01X416840Y732256D02*
Y726056D01*
G01X425507Y746731D02*
X425662Y746501D01*
X425765Y746233D01*
Y745926D01*
X425610Y745581D01*
X425352Y745313D01*
X425042Y745121D01*
X424525Y744968D01*
X424060Y744930D01*
X423595Y745006D01*
X423285Y745121D01*
X422975Y745351D01*
X422768Y745620D01*
X422665Y745888D01*
Y746156D01*
X422768Y746425D01*
X422923Y746655D01*
X423130Y746846D01*
G01X423957Y748260D02*
X424318Y748528D01*
X424525Y748758D01*
X424628Y749065D01*
X424525Y749333D01*
X424318Y749525D01*
X424008Y749678D01*
X423647Y749716D01*
X423337Y749678D01*
X423027Y749525D01*
X422768Y749295D01*
X422665Y749026D01*
X422768Y748720D01*
X423078Y748451D01*
X423543Y748298D01*
X424060Y748260D01*
X424732Y748336D01*
X425093Y748451D01*
X425455Y748643D01*
X425713Y748911D01*
X425765Y749180D01*
X425662Y749448D01*
X425403Y749640D01*
G01X425765Y752088D02*
X425662Y751781D01*
X425403Y751551D01*
X425093Y751398D01*
X424680Y751283D01*
X424215Y751245D01*
X423750Y751283D01*
X423337Y751398D01*
X423027Y751551D01*
X422768Y751781D01*
X422665Y752088D01*
X422768Y752395D01*
X423027Y752625D01*
X423337Y752778D01*
X423750Y752893D01*
X424215Y752931D01*
X424680Y752893D01*
X425093Y752778D01*
X425403Y752625D01*
X425662Y752395D01*
X425765Y752088D01*
G01X422665Y755111D02*
X423337Y755188D01*
X423905Y755303D01*
X424422Y755456D01*
X424990Y755648D01*
X425765Y755955D01*
Y754421D01*
G01X428540Y743756D02*
X425340D01*
G01X425440Y740656D02*
X428440D01*
G01X430527Y746731D02*
X430682Y746501D01*
X430785Y746233D01*
Y745926D01*
X430630Y745581D01*
X430372Y745313D01*
X430062Y745121D01*
X429545Y744968D01*
X429080Y744930D01*
X428615Y745006D01*
X428305Y745121D01*
X427995Y745351D01*
X427788Y745620D01*
X427685Y745888D01*
Y746156D01*
X427788Y746425D01*
X427943Y746655D01*
X428150Y746846D01*
G01X427685Y748911D02*
X428357Y748988D01*
X428925Y749103D01*
X429442Y749256D01*
X430010Y749448D01*
X430785Y749755D01*
Y748221D01*
G01X428305Y751245D02*
X427943Y751475D01*
X427737Y751781D01*
X427685Y752126D01*
X427737Y752433D01*
X427995Y752740D01*
X428305Y752931D01*
X428615Y752970D01*
X428977Y752893D01*
X429235Y752625D01*
X429338Y752356D01*
Y752011D01*
G01Y752356D02*
X429493Y752586D01*
X429752Y752778D01*
X430062Y752855D01*
X430372Y752778D01*
X430630Y752586D01*
X430785Y752241D01*
X430733Y751896D01*
X430527Y751551D01*
G01X428977Y754460D02*
X429338Y754728D01*
X429545Y754958D01*
X429648Y755265D01*
X429545Y755533D01*
X429338Y755725D01*
X429028Y755878D01*
X428667Y755916D01*
X428357Y755878D01*
X428047Y755725D01*
X427788Y755495D01*
X427685Y755226D01*
X427788Y754920D01*
X428098Y754651D01*
X428563Y754498D01*
X429080Y754460D01*
X429752Y754536D01*
X430113Y754651D01*
X430475Y754843D01*
X430733Y755111D01*
X430785Y755380D01*
X430682Y755648D01*
X430423Y755840D01*
G01X420040Y743756D02*
X416840D01*
G01X416940Y740656D02*
X419940D01*
G01X424540Y743756D02*
X421340D01*
G01X433040D02*
X429840D01*
G01X418597Y745121D02*
X421697D01*
Y746080D01*
X421542Y746386D01*
X421335Y746578D01*
X420922Y746655D01*
X420509Y746578D01*
X420250Y746348D01*
X420095Y746080D01*
Y745121D01*
G01Y746080D02*
X418597Y746655D01*
G01Y748988D02*
X418649Y749256D01*
X418804Y749563D01*
X419062Y749755D01*
X419424Y749831D01*
X419785Y749755D01*
X420095Y749525D01*
X420250Y749180D01*
Y748796D01*
X420354Y748566D01*
X420612Y748375D01*
X420974Y748298D01*
X421335Y748413D01*
X421594Y748681D01*
X421697Y748988D01*
X421594Y749295D01*
X421335Y749563D01*
X420974Y749678D01*
X420612Y749601D01*
X420354Y749410D01*
X420250Y749180D01*
Y748796D01*
X420095Y748451D01*
X419785Y748221D01*
X419424Y748145D01*
X419062Y748221D01*
X418804Y748413D01*
X418649Y748720D01*
X418597Y748988D01*
G01X418959Y751436D02*
X418700Y751705D01*
X418597Y752011D01*
X418700Y752318D01*
X419010Y752586D01*
X419475Y752778D01*
X419940Y752855D01*
X420509D01*
X420974Y752778D01*
X421387Y752586D01*
X421594Y752356D01*
X421697Y752088D01*
X421594Y751781D01*
X421387Y751551D01*
X421077Y751398D01*
X420664Y751321D01*
X420302Y751398D01*
X419940Y751590D01*
X419734Y751820D01*
X419682Y752088D01*
X419785Y752395D01*
X420044Y752625D01*
X420509Y752855D01*
G01X419889Y754460D02*
X420250Y754728D01*
X420457Y754958D01*
X420560Y755265D01*
X420457Y755533D01*
X420250Y755725D01*
X419940Y755878D01*
X419579Y755916D01*
X419269Y755878D01*
X418959Y755725D01*
X418700Y755495D01*
X418597Y755226D01*
X418700Y754920D01*
X419010Y754651D01*
X419475Y754498D01*
X419992Y754460D01*
X420664Y754536D01*
X421025Y754651D01*
X421387Y754843D01*
X421645Y755111D01*
X421697Y755380D01*
X421594Y755648D01*
X421335Y755840D01*
G01X430877Y758713D02*
X431032Y758483D01*
X431135Y758215D01*
Y757908D01*
X430980Y757563D01*
X430722Y757295D01*
X430412Y757103D01*
X429895Y756950D01*
X429430Y756912D01*
X428965Y756988D01*
X428655Y757103D01*
X428345Y757333D01*
X428138Y757602D01*
X428035Y757870D01*
Y758138D01*
X428138Y758407D01*
X428293Y758637D01*
X428500Y758828D01*
G01X428035Y760893D02*
X428707Y760970D01*
X429275Y761085D01*
X429792Y761238D01*
X430360Y761430D01*
X431135Y761737D01*
Y760203D01*
G01X428655Y763227D02*
X428293Y763457D01*
X428087Y763763D01*
X428035Y764108D01*
X428087Y764415D01*
X428345Y764722D01*
X428655Y764913D01*
X428965Y764952D01*
X429327Y764875D01*
X429585Y764607D01*
X429688Y764338D01*
Y763993D01*
G01Y764338D02*
X429843Y764568D01*
X430102Y764760D01*
X430412Y764837D01*
X430722Y764760D01*
X430980Y764568D01*
X431135Y764223D01*
X431083Y763878D01*
X430877Y763533D01*
G01X428397Y766518D02*
X428138Y766787D01*
X428035Y767093D01*
X428138Y767400D01*
X428448Y767668D01*
X428913Y767860D01*
X429378Y767937D01*
X429947D01*
X430412Y767860D01*
X430825Y767668D01*
X431032Y767438D01*
X431135Y767170D01*
X431032Y766863D01*
X430825Y766633D01*
X430515Y766480D01*
X430102Y766403D01*
X429740Y766480D01*
X429378Y766672D01*
X429172Y766902D01*
X429120Y767170D01*
X429223Y767477D01*
X429482Y767707D01*
X429947Y767937D01*
G01X424163Y757103D02*
X427263D01*
Y758062D01*
X427108Y758368D01*
X426901Y758560D01*
X426488Y758637D01*
X426075Y758560D01*
X425816Y758330D01*
X425661Y758062D01*
Y757103D01*
G01Y758062D02*
X424163Y758637D01*
G01Y760970D02*
X424215Y761238D01*
X424370Y761545D01*
X424628Y761737D01*
X424990Y761813D01*
X425351Y761737D01*
X425661Y761507D01*
X425816Y761162D01*
Y760778D01*
X425920Y760548D01*
X426178Y760357D01*
X426540Y760280D01*
X426901Y760395D01*
X427160Y760663D01*
X427263Y760970D01*
X427160Y761277D01*
X426901Y761545D01*
X426540Y761660D01*
X426178Y761583D01*
X425920Y761392D01*
X425816Y761162D01*
Y760778D01*
X425661Y760433D01*
X425351Y760203D01*
X424990Y760127D01*
X424628Y760203D01*
X424370Y760395D01*
X424215Y760702D01*
X424163Y760970D01*
G01X424783Y763227D02*
X424421Y763457D01*
X424215Y763763D01*
X424163Y764108D01*
X424215Y764415D01*
X424473Y764722D01*
X424783Y764913D01*
X425093Y764952D01*
X425455Y764875D01*
X425713Y764607D01*
X425816Y764338D01*
Y763993D01*
G01Y764338D02*
X425971Y764568D01*
X426230Y764760D01*
X426540Y764837D01*
X426850Y764760D01*
X427108Y764568D01*
X427263Y764223D01*
X427211Y763878D01*
X427005Y763533D01*
G01X424163Y767170D02*
X424215Y767438D01*
X424370Y767745D01*
X424628Y767937D01*
X424990Y768013D01*
X425351Y767937D01*
X425661Y767707D01*
X425816Y767362D01*
Y766978D01*
X425920Y766748D01*
X426178Y766557D01*
X426540Y766480D01*
X426901Y766595D01*
X427160Y766863D01*
X427263Y767170D01*
X427160Y767477D01*
X426901Y767745D01*
X426540Y767860D01*
X426178Y767783D01*
X425920Y767592D01*
X425816Y767362D01*
Y766978D01*
X425661Y766633D01*
X425351Y766403D01*
X424990Y766327D01*
X424628Y766403D01*
X424370Y766595D01*
X424215Y766902D01*
X424163Y767170D01*
G01X432588Y757103D02*
X435688D01*
Y758062D01*
X435533Y758368D01*
X435326Y758560D01*
X434913Y758637D01*
X434500Y758560D01*
X434241Y758330D01*
X434086Y758062D01*
Y757103D01*
G01Y758062D02*
X432588Y758637D01*
G01X432950Y760318D02*
X432691Y760587D01*
X432588Y760893D01*
X432691Y761200D01*
X433001Y761468D01*
X433466Y761660D01*
X433931Y761737D01*
X434500D01*
X434965Y761660D01*
X435378Y761468D01*
X435585Y761238D01*
X435688Y760970D01*
X435585Y760663D01*
X435378Y760433D01*
X435068Y760280D01*
X434655Y760203D01*
X434293Y760280D01*
X433931Y760472D01*
X433725Y760702D01*
X433673Y760970D01*
X433776Y761277D01*
X434035Y761507D01*
X434500Y761737D01*
G01X432588Y763993D02*
X433260Y764070D01*
X433828Y764185D01*
X434345Y764338D01*
X434913Y764530D01*
X435688Y764837D01*
Y763303D01*
G01X433208Y766327D02*
X432846Y766557D01*
X432640Y766863D01*
X432588Y767208D01*
X432640Y767515D01*
X432898Y767822D01*
X433208Y768013D01*
X433518Y768052D01*
X433880Y767975D01*
X434138Y767707D01*
X434241Y767438D01*
Y767093D01*
G01Y767438D02*
X434396Y767668D01*
X434655Y767860D01*
X434965Y767937D01*
X435275Y767860D01*
X435533Y767668D01*
X435688Y767323D01*
X435636Y766978D01*
X435430Y766633D01*
G01X447000Y135383D02*
X450100D01*
Y136342D01*
X449945Y136648D01*
X449738Y136840D01*
X449325Y136917D01*
X448912Y136840D01*
X448653Y136610D01*
X448498Y136342D01*
Y135383D01*
G01Y136342D02*
X447000Y136917D01*
G01Y139250D02*
X450100D01*
X449480Y138790D01*
G01X447000D02*
Y139710D01*
G01X449583Y141622D02*
X449893Y141852D01*
X450048Y142120D01*
X450100Y142427D01*
X449997Y142810D01*
X449738Y143078D01*
X449428Y143155D01*
X449118Y143117D01*
X448860Y142963D01*
X448343Y142197D01*
X447982Y141852D01*
X447465Y141622D01*
X447000Y141545D01*
Y143155D01*
G01X447362Y144798D02*
X447103Y145067D01*
X447000Y145373D01*
X447103Y145680D01*
X447413Y145948D01*
X447878Y146140D01*
X448343Y146217D01*
X448912D01*
X449377Y146140D01*
X449790Y145948D01*
X449997Y145718D01*
X450100Y145450D01*
X449997Y145143D01*
X449790Y144913D01*
X449480Y144760D01*
X449067Y144683D01*
X448705Y144760D01*
X448343Y144952D01*
X448137Y145182D01*
X448085Y145450D01*
X448188Y145757D01*
X448447Y145987D01*
X448912Y146217D01*
G01X447000Y148550D02*
X450100D01*
X449480Y148090D01*
G01X447000D02*
Y149010D01*
G01X437166Y239780D02*
X437321Y239550D01*
X437424Y239282D01*
Y238975D01*
X437269Y238630D01*
X437011Y238362D01*
X436701Y238170D01*
X436184Y238017D01*
X435719Y237979D01*
X435254Y238055D01*
X434944Y238170D01*
X434634Y238400D01*
X434427Y238669D01*
X434324Y238937D01*
Y239205D01*
X434427Y239474D01*
X434582Y239704D01*
X434789Y239895D01*
G01X434324Y242037D02*
X437424D01*
X436804Y241577D01*
G01X434324D02*
Y242497D01*
G01Y245137D02*
X434376Y245405D01*
X434531Y245712D01*
X434789Y245904D01*
X435151Y245980D01*
X435512Y245904D01*
X435822Y245674D01*
X435977Y245329D01*
Y244945D01*
X436081Y244715D01*
X436339Y244524D01*
X436701Y244447D01*
X437062Y244562D01*
X437321Y244830D01*
X437424Y245137D01*
X437321Y245444D01*
X437062Y245712D01*
X436701Y245827D01*
X436339Y245750D01*
X436081Y245559D01*
X435977Y245329D01*
Y244945D01*
X435822Y244600D01*
X435512Y244370D01*
X435151Y244294D01*
X434789Y244370D01*
X434531Y244562D01*
X434376Y244869D01*
X434324Y245137D01*
G01X436907Y247509D02*
X437217Y247739D01*
X437372Y248007D01*
X437424Y248314D01*
X437321Y248697D01*
X437062Y248965D01*
X436752Y249042D01*
X436442Y249004D01*
X436184Y248850D01*
X435667Y248084D01*
X435306Y247739D01*
X434789Y247509D01*
X434324Y247432D01*
Y249042D01*
G01X433151Y259925D02*
Y249725D01*
G01D02*
X437751D01*
G01D02*
Y259925D01*
G01D02*
X433151D01*
G01Y254825D02*
X437751D01*
G01X434173Y266978D02*
Y260778D01*
G01D02*
X437373D01*
G01D02*
Y266978D01*
G01X434224Y268299D02*
X437324D01*
Y269258D01*
X437169Y269564D01*
X436962Y269756D01*
X436549Y269833D01*
X436136Y269756D01*
X435877Y269526D01*
X435722Y269258D01*
Y268299D01*
G01Y269258D02*
X434224Y269833D01*
G01X436807Y271438D02*
X437117Y271668D01*
X437272Y271936D01*
X437324Y272243D01*
X437221Y272626D01*
X436962Y272894D01*
X436652Y272971D01*
X436342Y272933D01*
X436084Y272779D01*
X435567Y272013D01*
X435206Y271668D01*
X434689Y271438D01*
X434224Y271361D01*
Y272971D01*
G01X436807Y274538D02*
X437117Y274768D01*
X437272Y275036D01*
X437324Y275343D01*
X437221Y275726D01*
X436962Y275994D01*
X436652Y276071D01*
X436342Y276033D01*
X436084Y275879D01*
X435567Y275113D01*
X435206Y274768D01*
X434689Y274538D01*
X434224Y274461D01*
Y276071D01*
G01Y278826D02*
X437324D01*
X435102Y277408D01*
Y279324D01*
G01X437373Y266978D02*
X434173D01*
G01X444081Y421229D02*
X459081D01*
G01X444081Y428029D02*
Y421229D01*
G01Y429398D02*
X459081D01*
G01X444081Y436198D02*
Y429398D01*
G01X459081Y436198D02*
X444081D01*
G01X459081Y428029D02*
X444081D01*
G01X432400Y538707D02*
Y543307D01*
G01X454683Y556582D02*
Y559682D01*
X453724D01*
X453418Y559527D01*
X453226Y559320D01*
X453149Y558907D01*
X453226Y558494D01*
X453456Y558235D01*
X453724Y558080D01*
X454683D01*
G01X453724D02*
X453149Y556582D01*
G01X451468Y556944D02*
X451199Y556685D01*
X450893Y556582D01*
X450586Y556685D01*
X450318Y556995D01*
X450126Y557460D01*
X450049Y557925D01*
Y558494D01*
X450126Y558959D01*
X450318Y559372D01*
X450548Y559579D01*
X450816Y559682D01*
X451123Y559579D01*
X451353Y559372D01*
X451506Y559062D01*
X451583Y558649D01*
X451506Y558287D01*
X451314Y557925D01*
X451084Y557719D01*
X450816Y557667D01*
X450509Y557770D01*
X450279Y558029D01*
X450049Y558494D01*
G01X447716Y556582D02*
Y559682D01*
X448176Y559062D01*
G01Y556582D02*
X447256D01*
G01X445344Y559165D02*
X445114Y559475D01*
X444846Y559630D01*
X444539Y559682D01*
X444156Y559579D01*
X443888Y559320D01*
X443811Y559010D01*
X443849Y558700D01*
X444003Y558442D01*
X444769Y557925D01*
X445114Y557564D01*
X445344Y557047D01*
X445421Y556582D01*
X443811D01*
G01X454683Y564504D02*
Y567604D01*
X453724D01*
X453418Y567449D01*
X453226Y567242D01*
X453149Y566829D01*
X453226Y566416D01*
X453456Y566157D01*
X453724Y566002D01*
X454683D01*
G01X453724D02*
X453149Y564504D01*
G01X450893D02*
X450816Y565176D01*
X450701Y565744D01*
X450548Y566261D01*
X450356Y566829D01*
X450049Y567604D01*
X451583D01*
G01X447716Y564504D02*
X447448Y564556D01*
X447141Y564711D01*
X446949Y564969D01*
X446873Y565331D01*
X446949Y565692D01*
X447179Y566002D01*
X447524Y566157D01*
X447908D01*
X448138Y566261D01*
X448329Y566519D01*
X448406Y566881D01*
X448291Y567242D01*
X448023Y567501D01*
X447716Y567604D01*
X447409Y567501D01*
X447141Y567242D01*
X447026Y566881D01*
X447103Y566519D01*
X447294Y566261D01*
X447524Y566157D01*
X447908D01*
X448253Y566002D01*
X448483Y565692D01*
X448559Y565331D01*
X448483Y564969D01*
X448291Y564711D01*
X447984Y564556D01*
X447716Y564504D01*
G01X444616Y567604D02*
X444923Y567501D01*
X445153Y567242D01*
X445306Y566932D01*
X445421Y566519D01*
X445459Y566054D01*
X445421Y565589D01*
X445306Y565176D01*
X445153Y564866D01*
X444923Y564607D01*
X444616Y564504D01*
X444309Y564607D01*
X444079Y564866D01*
X443926Y565176D01*
X443811Y565589D01*
X443773Y566054D01*
X443811Y566519D01*
X443926Y566932D01*
X444079Y567242D01*
X444309Y567501D01*
X444616Y567604D01*
G01X454683Y560457D02*
Y563557D01*
X453724D01*
X453418Y563402D01*
X453226Y563195D01*
X453149Y562782D01*
X453226Y562369D01*
X453456Y562110D01*
X453724Y561955D01*
X454683D01*
G01X453724D02*
X453149Y560457D01*
G01X450893D02*
X450816Y561129D01*
X450701Y561697D01*
X450548Y562214D01*
X450356Y562782D01*
X450049Y563557D01*
X451583D01*
G01X447716Y560457D02*
X447448Y560509D01*
X447141Y560664D01*
X446949Y560922D01*
X446873Y561284D01*
X446949Y561645D01*
X447179Y561955D01*
X447524Y562110D01*
X447908D01*
X448138Y562214D01*
X448329Y562472D01*
X448406Y562834D01*
X448291Y563195D01*
X448023Y563454D01*
X447716Y563557D01*
X447409Y563454D01*
X447141Y563195D01*
X447026Y562834D01*
X447103Y562472D01*
X447294Y562214D01*
X447524Y562110D01*
X447908D01*
X448253Y561955D01*
X448483Y561645D01*
X448559Y561284D01*
X448483Y560922D01*
X448291Y560664D01*
X447984Y560509D01*
X447716Y560457D01*
G01X444616D02*
Y563557D01*
X445076Y562937D01*
G01Y560457D02*
X444156D01*
G01X440408Y581536D02*
Y579314D01*
X440255Y578849D01*
X439948Y578539D01*
X439565Y578436D01*
X439182Y578539D01*
X438875Y578849D01*
X438722Y579314D01*
Y581536D01*
G01X436542Y578436D02*
X436465Y579108D01*
X436350Y579676D01*
X436197Y580193D01*
X436005Y580761D01*
X435698Y581536D01*
X437232D01*
G01X434208Y579056D02*
X433978Y578694D01*
X433672Y578488D01*
X433327Y578436D01*
X433020Y578488D01*
X432713Y578746D01*
X432522Y579056D01*
X432483Y579366D01*
X432560Y579728D01*
X432828Y579986D01*
X433097Y580089D01*
X433442D01*
G01X433097D02*
X432867Y580244D01*
X432675Y580503D01*
X432598Y580813D01*
X432675Y581123D01*
X432867Y581381D01*
X433212Y581536D01*
X433557Y581484D01*
X433902Y581278D01*
G01X454033Y580933D02*
Y584033D01*
X453074D01*
X452768Y583878D01*
X452576Y583671D01*
X452499Y583258D01*
X452576Y582845D01*
X452806Y582586D01*
X453074Y582431D01*
X454033D01*
G01X453074D02*
X452499Y580933D01*
G01X450243D02*
X450166Y581605D01*
X450051Y582173D01*
X449898Y582690D01*
X449706Y583258D01*
X449399Y584033D01*
X450933D01*
G01X447066Y580933D02*
X446798Y580985D01*
X446491Y581140D01*
X446299Y581398D01*
X446223Y581760D01*
X446299Y582121D01*
X446529Y582431D01*
X446874Y582586D01*
X447258D01*
X447488Y582690D01*
X447679Y582948D01*
X447756Y583310D01*
X447641Y583671D01*
X447373Y583930D01*
X447066Y584033D01*
X446759Y583930D01*
X446491Y583671D01*
X446376Y583310D01*
X446453Y582948D01*
X446644Y582690D01*
X446874Y582586D01*
X447258D01*
X447603Y582431D01*
X447833Y582121D01*
X447909Y581760D01*
X447833Y581398D01*
X447641Y581140D01*
X447334Y580985D01*
X447066Y580933D01*
G01X443506D02*
Y584033D01*
X444924Y581811D01*
X443008D01*
G01X454683Y576457D02*
Y579557D01*
X453724D01*
X453418Y579402D01*
X453226Y579195D01*
X453149Y578782D01*
X453226Y578369D01*
X453456Y578110D01*
X453724Y577955D01*
X454683D01*
G01X453724D02*
X453149Y576457D01*
G01X450893D02*
X450816Y577129D01*
X450701Y577697D01*
X450548Y578214D01*
X450356Y578782D01*
X450049Y579557D01*
X451583D01*
G01X447716Y576457D02*
X447448Y576509D01*
X447141Y576664D01*
X446949Y576922D01*
X446873Y577284D01*
X446949Y577645D01*
X447179Y577955D01*
X447524Y578110D01*
X447908D01*
X448138Y578214D01*
X448329Y578472D01*
X448406Y578834D01*
X448291Y579195D01*
X448023Y579454D01*
X447716Y579557D01*
X447409Y579454D01*
X447141Y579195D01*
X447026Y578834D01*
X447103Y578472D01*
X447294Y578214D01*
X447524Y578110D01*
X447908D01*
X448253Y577955D01*
X448483Y577645D01*
X448559Y577284D01*
X448483Y576922D01*
X448291Y576664D01*
X447984Y576509D01*
X447716Y576457D01*
G01X445459Y576922D02*
X445229Y576664D01*
X444961Y576509D01*
X444616Y576457D01*
X444271Y576560D01*
X444003Y576767D01*
X443811Y577129D01*
X443773Y577542D01*
X443849Y577955D01*
X444041Y578214D01*
X444309Y578420D01*
X444578Y578472D01*
X444846Y578420D01*
X445191Y578214D01*
X445076Y579557D01*
X444041D01*
G01X454683Y572457D02*
Y575557D01*
X453724D01*
X453418Y575402D01*
X453226Y575195D01*
X453149Y574782D01*
X453226Y574369D01*
X453456Y574110D01*
X453724Y573955D01*
X454683D01*
G01X453724D02*
X453149Y572457D01*
G01X450893D02*
X450816Y573129D01*
X450701Y573697D01*
X450548Y574214D01*
X450356Y574782D01*
X450049Y575557D01*
X451583D01*
G01X447716Y572457D02*
X447448Y572509D01*
X447141Y572664D01*
X446949Y572922D01*
X446873Y573284D01*
X446949Y573645D01*
X447179Y573955D01*
X447524Y574110D01*
X447908D01*
X448138Y574214D01*
X448329Y574472D01*
X448406Y574834D01*
X448291Y575195D01*
X448023Y575454D01*
X447716Y575557D01*
X447409Y575454D01*
X447141Y575195D01*
X447026Y574834D01*
X447103Y574472D01*
X447294Y574214D01*
X447524Y574110D01*
X447908D01*
X448253Y573955D01*
X448483Y573645D01*
X448559Y573284D01*
X448483Y572922D01*
X448291Y572664D01*
X447984Y572509D01*
X447716Y572457D01*
G01X445344Y573749D02*
X445076Y574110D01*
X444846Y574317D01*
X444539Y574420D01*
X444271Y574317D01*
X444079Y574110D01*
X443926Y573800D01*
X443888Y573439D01*
X443926Y573129D01*
X444079Y572819D01*
X444309Y572560D01*
X444578Y572457D01*
X444884Y572560D01*
X445153Y572870D01*
X445306Y573335D01*
X445344Y573852D01*
X445268Y574524D01*
X445153Y574885D01*
X444961Y575247D01*
X444693Y575505D01*
X444424Y575557D01*
X444156Y575454D01*
X443964Y575195D01*
G01X454683Y568457D02*
Y571557D01*
X453724D01*
X453418Y571402D01*
X453226Y571195D01*
X453149Y570782D01*
X453226Y570369D01*
X453456Y570110D01*
X453724Y569955D01*
X454683D01*
G01X453724D02*
X453149Y568457D01*
G01X450893D02*
X450816Y569129D01*
X450701Y569697D01*
X450548Y570214D01*
X450356Y570782D01*
X450049Y571557D01*
X451583D01*
G01X447716Y568457D02*
X447448Y568509D01*
X447141Y568664D01*
X446949Y568922D01*
X446873Y569284D01*
X446949Y569645D01*
X447179Y569955D01*
X447524Y570110D01*
X447908D01*
X448138Y570214D01*
X448329Y570472D01*
X448406Y570834D01*
X448291Y571195D01*
X448023Y571454D01*
X447716Y571557D01*
X447409Y571454D01*
X447141Y571195D01*
X447026Y570834D01*
X447103Y570472D01*
X447294Y570214D01*
X447524Y570110D01*
X447908D01*
X448253Y569955D01*
X448483Y569645D01*
X448559Y569284D01*
X448483Y568922D01*
X448291Y568664D01*
X447984Y568509D01*
X447716Y568457D01*
G01X444693D02*
X444616Y569129D01*
X444501Y569697D01*
X444348Y570214D01*
X444156Y570782D01*
X443849Y571557D01*
X445383D01*
G01X440111Y595860D02*
Y593638D01*
X439958Y593173D01*
X439651Y592863D01*
X439268Y592760D01*
X438885Y592863D01*
X438578Y593173D01*
X438425Y593638D01*
Y595860D01*
G01X436896Y594052D02*
X436628Y594413D01*
X436398Y594620D01*
X436091Y594723D01*
X435823Y594620D01*
X435631Y594413D01*
X435478Y594103D01*
X435440Y593742D01*
X435478Y593432D01*
X435631Y593122D01*
X435861Y592863D01*
X436130Y592760D01*
X436436Y592863D01*
X436705Y593173D01*
X436858Y593638D01*
X436896Y594155D01*
X436820Y594827D01*
X436705Y595188D01*
X436513Y595550D01*
X436245Y595808D01*
X435976Y595860D01*
X435708Y595757D01*
X435516Y595498D01*
G01X433796Y595343D02*
X433566Y595653D01*
X433298Y595808D01*
X432991Y595860D01*
X432608Y595757D01*
X432340Y595498D01*
X432263Y595188D01*
X432301Y594878D01*
X432455Y594620D01*
X433221Y594103D01*
X433566Y593742D01*
X433796Y593225D01*
X433873Y592760D01*
X432263D01*
G01X453447Y587950D02*
X453677Y588105D01*
X453945Y588208D01*
X454252D01*
X454597Y588053D01*
X454865Y587795D01*
X455057Y587485D01*
X455210Y586968D01*
X455248Y586503D01*
X455172Y586038D01*
X455057Y585728D01*
X454827Y585418D01*
X454558Y585211D01*
X454290Y585108D01*
X454022D01*
X453753Y585211D01*
X453523Y585366D01*
X453332Y585573D01*
G01X452033D02*
X451803Y585315D01*
X451535Y585160D01*
X451190Y585108D01*
X450845Y585211D01*
X450577Y585418D01*
X450385Y585780D01*
X450347Y586193D01*
X450423Y586606D01*
X450615Y586865D01*
X450883Y587071D01*
X451152Y587123D01*
X451420Y587071D01*
X451765Y586865D01*
X451650Y588208D01*
X450615D01*
G01X448818Y586400D02*
X448550Y586761D01*
X448320Y586968D01*
X448013Y587071D01*
X447745Y586968D01*
X447553Y586761D01*
X447400Y586451D01*
X447362Y586090D01*
X447400Y585780D01*
X447553Y585470D01*
X447783Y585211D01*
X448052Y585108D01*
X448358Y585211D01*
X448627Y585521D01*
X448780Y585986D01*
X448818Y586503D01*
X448742Y587175D01*
X448627Y587536D01*
X448435Y587898D01*
X448167Y588156D01*
X447898Y588208D01*
X447630Y588105D01*
X447438Y587846D01*
G01X444990Y585108D02*
X444722Y585160D01*
X444415Y585315D01*
X444223Y585573D01*
X444147Y585935D01*
X444223Y586296D01*
X444453Y586606D01*
X444798Y586761D01*
X445182D01*
X445412Y586865D01*
X445603Y587123D01*
X445680Y587485D01*
X445565Y587846D01*
X445297Y588105D01*
X444990Y588208D01*
X444683Y588105D01*
X444415Y587846D01*
X444300Y587485D01*
X444377Y587123D01*
X444568Y586865D01*
X444798Y586761D01*
X445182D01*
X445527Y586606D01*
X445757Y586296D01*
X445833Y585935D01*
X445757Y585573D01*
X445565Y585315D01*
X445258Y585160D01*
X444990Y585108D01*
G01X455188Y596351D02*
Y599451D01*
X454229D01*
X453923Y599296D01*
X453731Y599089D01*
X453654Y598676D01*
X453731Y598263D01*
X453961Y598004D01*
X454229Y597849D01*
X455188D01*
G01X454229D02*
X453654Y596351D01*
G01X451398D02*
X451321Y597023D01*
X451206Y597591D01*
X451053Y598108D01*
X450861Y598676D01*
X450554Y599451D01*
X452088D01*
G01X448221D02*
X448528Y599348D01*
X448758Y599089D01*
X448911Y598779D01*
X449026Y598366D01*
X449064Y597901D01*
X449026Y597436D01*
X448911Y597023D01*
X448758Y596713D01*
X448528Y596454D01*
X448221Y596351D01*
X447914Y596454D01*
X447684Y596713D01*
X447531Y597023D01*
X447416Y597436D01*
X447378Y597901D01*
X447416Y598366D01*
X447531Y598779D01*
X447684Y599089D01*
X447914Y599348D01*
X448221Y599451D01*
G01X445198Y596351D02*
X445121Y597023D01*
X445006Y597591D01*
X444853Y598108D01*
X444661Y598676D01*
X444354Y599451D01*
X445888D01*
G01X455188Y592351D02*
Y595451D01*
X454229D01*
X453923Y595296D01*
X453731Y595089D01*
X453654Y594676D01*
X453731Y594263D01*
X453961Y594004D01*
X454229Y593849D01*
X455188D01*
G01X454229D02*
X453654Y592351D01*
G01X451398D02*
X451321Y593023D01*
X451206Y593591D01*
X451053Y594108D01*
X450861Y594676D01*
X450554Y595451D01*
X452088D01*
G01X448221D02*
X448528Y595348D01*
X448758Y595089D01*
X448911Y594779D01*
X449026Y594366D01*
X449064Y593901D01*
X449026Y593436D01*
X448911Y593023D01*
X448758Y592713D01*
X448528Y592454D01*
X448221Y592351D01*
X447914Y592454D01*
X447684Y592713D01*
X447531Y593023D01*
X447416Y593436D01*
X447378Y593901D01*
X447416Y594366D01*
X447531Y594779D01*
X447684Y595089D01*
X447914Y595348D01*
X448221Y595451D01*
G01X445773Y592713D02*
X445504Y592454D01*
X445198Y592351D01*
X444891Y592454D01*
X444623Y592764D01*
X444431Y593229D01*
X444354Y593694D01*
Y594263D01*
X444431Y594728D01*
X444623Y595141D01*
X444853Y595348D01*
X445121Y595451D01*
X445428Y595348D01*
X445658Y595141D01*
X445811Y594831D01*
X445888Y594418D01*
X445811Y594056D01*
X445619Y593694D01*
X445389Y593488D01*
X445121Y593436D01*
X444814Y593539D01*
X444584Y593798D01*
X444354Y594263D01*
G01X454852Y588711D02*
Y591811D01*
X453893D01*
X453587Y591656D01*
X453395Y591449D01*
X453318Y591036D01*
X453395Y590623D01*
X453625Y590364D01*
X453893Y590209D01*
X454852D01*
G01X453893D02*
X453318Y588711D01*
G01X451713Y590003D02*
X451445Y590364D01*
X451215Y590571D01*
X450908Y590674D01*
X450640Y590571D01*
X450448Y590364D01*
X450295Y590054D01*
X450257Y589693D01*
X450295Y589383D01*
X450448Y589073D01*
X450678Y588814D01*
X450947Y588711D01*
X451253Y588814D01*
X451522Y589124D01*
X451675Y589589D01*
X451713Y590106D01*
X451637Y590778D01*
X451522Y591139D01*
X451330Y591501D01*
X451062Y591759D01*
X450793Y591811D01*
X450525Y591708D01*
X450333Y591449D01*
G01X447885Y588711D02*
X447617Y588763D01*
X447310Y588918D01*
X447118Y589176D01*
X447042Y589538D01*
X447118Y589899D01*
X447348Y590209D01*
X447693Y590364D01*
X448077D01*
X448307Y590468D01*
X448498Y590726D01*
X448575Y591088D01*
X448460Y591449D01*
X448192Y591708D01*
X447885Y591811D01*
X447578Y591708D01*
X447310Y591449D01*
X447195Y591088D01*
X447272Y590726D01*
X447463Y590468D01*
X447693Y590364D01*
X448077D01*
X448422Y590209D01*
X448652Y589899D01*
X448728Y589538D01*
X448652Y589176D01*
X448460Y588918D01*
X448153Y588763D01*
X447885Y588711D01*
G01X444862D02*
X444785Y589383D01*
X444670Y589951D01*
X444517Y590468D01*
X444325Y591036D01*
X444018Y591811D01*
X445552D01*
G01X455188Y612665D02*
Y615765D01*
X454229D01*
X453923Y615610D01*
X453731Y615403D01*
X453654Y614990D01*
X453731Y614577D01*
X453961Y614318D01*
X454229Y614163D01*
X455188D01*
G01X454229D02*
X453654Y612665D01*
G01X452049Y613957D02*
X451781Y614318D01*
X451551Y614525D01*
X451244Y614628D01*
X450976Y614525D01*
X450784Y614318D01*
X450631Y614008D01*
X450593Y613647D01*
X450631Y613337D01*
X450784Y613027D01*
X451014Y612768D01*
X451283Y612665D01*
X451589Y612768D01*
X451858Y613078D01*
X452011Y613543D01*
X452049Y614060D01*
X451973Y614732D01*
X451858Y615093D01*
X451666Y615455D01*
X451398Y615713D01*
X451129Y615765D01*
X450861Y615662D01*
X450669Y615403D01*
G01X448873Y613027D02*
X448604Y612768D01*
X448298Y612665D01*
X447991Y612768D01*
X447723Y613078D01*
X447531Y613543D01*
X447454Y614008D01*
Y614577D01*
X447531Y615042D01*
X447723Y615455D01*
X447953Y615662D01*
X448221Y615765D01*
X448528Y615662D01*
X448758Y615455D01*
X448911Y615145D01*
X448988Y614732D01*
X448911Y614370D01*
X448719Y614008D01*
X448489Y613802D01*
X448221Y613750D01*
X447914Y613853D01*
X447684Y614112D01*
X447454Y614577D01*
G01X445773Y613027D02*
X445504Y612768D01*
X445198Y612665D01*
X444891Y612768D01*
X444623Y613078D01*
X444431Y613543D01*
X444354Y614008D01*
Y614577D01*
X444431Y615042D01*
X444623Y615455D01*
X444853Y615662D01*
X445121Y615765D01*
X445428Y615662D01*
X445658Y615455D01*
X445811Y615145D01*
X445888Y614732D01*
X445811Y614370D01*
X445619Y614008D01*
X445389Y613802D01*
X445121Y613750D01*
X444814Y613853D01*
X444584Y614112D01*
X444354Y614577D01*
G01X455188Y608665D02*
Y611765D01*
X454229D01*
X453923Y611610D01*
X453731Y611403D01*
X453654Y610990D01*
X453731Y610577D01*
X453961Y610318D01*
X454229Y610163D01*
X455188D01*
G01X454229D02*
X453654Y608665D01*
G01X451398D02*
X451321Y609337D01*
X451206Y609905D01*
X451053Y610422D01*
X450861Y610990D01*
X450554Y611765D01*
X452088D01*
G01X448221D02*
X448528Y611662D01*
X448758Y611403D01*
X448911Y611093D01*
X449026Y610680D01*
X449064Y610215D01*
X449026Y609750D01*
X448911Y609337D01*
X448758Y609027D01*
X448528Y608768D01*
X448221Y608665D01*
X447914Y608768D01*
X447684Y609027D01*
X447531Y609337D01*
X447416Y609750D01*
X447378Y610215D01*
X447416Y610680D01*
X447531Y611093D01*
X447684Y611403D01*
X447914Y611662D01*
X448221Y611765D01*
G01X445121D02*
X445428Y611662D01*
X445658Y611403D01*
X445811Y611093D01*
X445926Y610680D01*
X445964Y610215D01*
X445926Y609750D01*
X445811Y609337D01*
X445658Y609027D01*
X445428Y608768D01*
X445121Y608665D01*
X444814Y608768D01*
X444584Y609027D01*
X444431Y609337D01*
X444316Y609750D01*
X444278Y610215D01*
X444316Y610680D01*
X444431Y611093D01*
X444584Y611403D01*
X444814Y611662D01*
X445121Y611765D01*
G01X455188Y604351D02*
Y607451D01*
X454229D01*
X453923Y607296D01*
X453731Y607089D01*
X453654Y606676D01*
X453731Y606263D01*
X453961Y606004D01*
X454229Y605849D01*
X455188D01*
G01X454229D02*
X453654Y604351D01*
G01X451398D02*
X451321Y605023D01*
X451206Y605591D01*
X451053Y606108D01*
X450861Y606676D01*
X450554Y607451D01*
X452088D01*
G01X448221D02*
X448528Y607348D01*
X448758Y607089D01*
X448911Y606779D01*
X449026Y606366D01*
X449064Y605901D01*
X449026Y605436D01*
X448911Y605023D01*
X448758Y604713D01*
X448528Y604454D01*
X448221Y604351D01*
X447914Y604454D01*
X447684Y604713D01*
X447531Y605023D01*
X447416Y605436D01*
X447378Y605901D01*
X447416Y606366D01*
X447531Y606779D01*
X447684Y607089D01*
X447914Y607348D01*
X448221Y607451D01*
G01X445964Y604971D02*
X445734Y604609D01*
X445428Y604403D01*
X445083Y604351D01*
X444776Y604403D01*
X444469Y604661D01*
X444278Y604971D01*
X444239Y605281D01*
X444316Y605643D01*
X444584Y605901D01*
X444853Y606004D01*
X445198D01*
G01X444853D02*
X444623Y606159D01*
X444431Y606418D01*
X444354Y606728D01*
X444431Y607038D01*
X444623Y607296D01*
X444968Y607451D01*
X445313Y607399D01*
X445658Y607193D01*
G01X455188Y600351D02*
Y603451D01*
X454229D01*
X453923Y603296D01*
X453731Y603089D01*
X453654Y602676D01*
X453731Y602263D01*
X453961Y602004D01*
X454229Y601849D01*
X455188D01*
G01X454229D02*
X453654Y600351D01*
G01X451398D02*
X451321Y601023D01*
X451206Y601591D01*
X451053Y602108D01*
X450861Y602676D01*
X450554Y603451D01*
X452088D01*
G01X448221D02*
X448528Y603348D01*
X448758Y603089D01*
X448911Y602779D01*
X449026Y602366D01*
X449064Y601901D01*
X449026Y601436D01*
X448911Y601023D01*
X448758Y600713D01*
X448528Y600454D01*
X448221Y600351D01*
X447914Y600454D01*
X447684Y600713D01*
X447531Y601023D01*
X447416Y601436D01*
X447378Y601901D01*
X447416Y602366D01*
X447531Y602779D01*
X447684Y603089D01*
X447914Y603348D01*
X448221Y603451D01*
G01X445964Y600816D02*
X445734Y600558D01*
X445466Y600403D01*
X445121Y600351D01*
X444776Y600454D01*
X444508Y600661D01*
X444316Y601023D01*
X444278Y601436D01*
X444354Y601849D01*
X444546Y602108D01*
X444814Y602314D01*
X445083Y602366D01*
X445351Y602314D01*
X445696Y602108D01*
X445581Y603451D01*
X444546D01*
G01X435918Y630381D02*
X436298Y630631D01*
X436741Y630798D01*
X437248D01*
X437818Y630548D01*
X438261Y630131D01*
X438578Y629631D01*
X438831Y628798D01*
X438894Y628048D01*
X438768Y627298D01*
X438578Y626798D01*
X438198Y626298D01*
X437754Y625965D01*
X437311Y625798D01*
X436868D01*
X436424Y625965D01*
X436044Y626215D01*
X435728Y626548D01*
G01X455188Y620665D02*
Y623765D01*
X454229D01*
X453923Y623610D01*
X453731Y623403D01*
X453654Y622990D01*
X453731Y622577D01*
X453961Y622318D01*
X454229Y622163D01*
X455188D01*
G01X454229D02*
X453654Y620665D01*
G01X452049Y621957D02*
X451781Y622318D01*
X451551Y622525D01*
X451244Y622628D01*
X450976Y622525D01*
X450784Y622318D01*
X450631Y622008D01*
X450593Y621647D01*
X450631Y621337D01*
X450784Y621027D01*
X451014Y620768D01*
X451283Y620665D01*
X451589Y620768D01*
X451858Y621078D01*
X452011Y621543D01*
X452049Y622060D01*
X451973Y622732D01*
X451858Y623093D01*
X451666Y623455D01*
X451398Y623713D01*
X451129Y623765D01*
X450861Y623662D01*
X450669Y623403D01*
G01X448873Y621027D02*
X448604Y620768D01*
X448298Y620665D01*
X447991Y620768D01*
X447723Y621078D01*
X447531Y621543D01*
X447454Y622008D01*
Y622577D01*
X447531Y623042D01*
X447723Y623455D01*
X447953Y623662D01*
X448221Y623765D01*
X448528Y623662D01*
X448758Y623455D01*
X448911Y623145D01*
X448988Y622732D01*
X448911Y622370D01*
X448719Y622008D01*
X448489Y621802D01*
X448221Y621750D01*
X447914Y621853D01*
X447684Y622112D01*
X447454Y622577D01*
G01X445198Y620665D02*
X445121Y621337D01*
X445006Y621905D01*
X444853Y622422D01*
X444661Y622990D01*
X444354Y623765D01*
X445888D01*
G01X455188Y616665D02*
Y619765D01*
X454229D01*
X453923Y619610D01*
X453731Y619403D01*
X453654Y618990D01*
X453731Y618577D01*
X453961Y618318D01*
X454229Y618163D01*
X455188D01*
G01X454229D02*
X453654Y616665D01*
G01X452049Y617957D02*
X451781Y618318D01*
X451551Y618525D01*
X451244Y618628D01*
X450976Y618525D01*
X450784Y618318D01*
X450631Y618008D01*
X450593Y617647D01*
X450631Y617337D01*
X450784Y617027D01*
X451014Y616768D01*
X451283Y616665D01*
X451589Y616768D01*
X451858Y617078D01*
X452011Y617543D01*
X452049Y618060D01*
X451973Y618732D01*
X451858Y619093D01*
X451666Y619455D01*
X451398Y619713D01*
X451129Y619765D01*
X450861Y619662D01*
X450669Y619403D01*
G01X448873Y617027D02*
X448604Y616768D01*
X448298Y616665D01*
X447991Y616768D01*
X447723Y617078D01*
X447531Y617543D01*
X447454Y618008D01*
Y618577D01*
X447531Y619042D01*
X447723Y619455D01*
X447953Y619662D01*
X448221Y619765D01*
X448528Y619662D01*
X448758Y619455D01*
X448911Y619145D01*
X448988Y618732D01*
X448911Y618370D01*
X448719Y618008D01*
X448489Y617802D01*
X448221Y617750D01*
X447914Y617853D01*
X447684Y618112D01*
X447454Y618577D01*
G01X445121Y616665D02*
X444853Y616717D01*
X444546Y616872D01*
X444354Y617130D01*
X444278Y617492D01*
X444354Y617853D01*
X444584Y618163D01*
X444929Y618318D01*
X445313D01*
X445543Y618422D01*
X445734Y618680D01*
X445811Y619042D01*
X445696Y619403D01*
X445428Y619662D01*
X445121Y619765D01*
X444814Y619662D01*
X444546Y619403D01*
X444431Y619042D01*
X444508Y618680D01*
X444699Y618422D01*
X444929Y618318D01*
X445313D01*
X445658Y618163D01*
X445888Y617853D01*
X445964Y617492D01*
X445888Y617130D01*
X445696Y616872D01*
X445389Y616717D01*
X445121Y616665D01*
G01X442185Y637238D02*
X445285D01*
Y638197D01*
X445130Y638503D01*
X444923Y638695D01*
X444510Y638772D01*
X444097Y638695D01*
X443838Y638465D01*
X443683Y638197D01*
Y637238D01*
G01Y638197D02*
X442185Y638772D01*
G01Y641028D02*
X442857Y641105D01*
X443425Y641220D01*
X443942Y641373D01*
X444510Y641565D01*
X445285Y641872D01*
Y640338D01*
G01X442185Y644128D02*
X442857Y644205D01*
X443425Y644320D01*
X443942Y644473D01*
X444510Y644665D01*
X445285Y644972D01*
Y643438D01*
G01X442805Y646462D02*
X442443Y646692D01*
X442237Y646998D01*
X442185Y647343D01*
X442237Y647650D01*
X442495Y647957D01*
X442805Y648148D01*
X443115Y648187D01*
X443477Y648110D01*
X443735Y647842D01*
X443838Y647573D01*
Y647228D01*
G01Y647573D02*
X443993Y647803D01*
X444252Y647995D01*
X444562Y648072D01*
X444872Y647995D01*
X445130Y647803D01*
X445285Y647458D01*
X445233Y647113D01*
X445027Y646768D01*
G01X438361Y637050D02*
X441461D01*
Y638009D01*
X441306Y638315D01*
X441099Y638507D01*
X440686Y638584D01*
X440273Y638507D01*
X440014Y638277D01*
X439859Y638009D01*
Y637050D01*
G01Y638009D02*
X438361Y638584D01*
G01Y640840D02*
X439033Y640917D01*
X439601Y641032D01*
X440118Y641185D01*
X440686Y641377D01*
X441461Y641684D01*
Y640150D01*
G01X438361Y643940D02*
X439033Y644017D01*
X439601Y644132D01*
X440118Y644285D01*
X440686Y644477D01*
X441461Y644784D01*
Y643250D01*
G01X438361Y647577D02*
X441461D01*
X439239Y646159D01*
Y648075D01*
G01X450783Y652279D02*
X447583D01*
G01D02*
Y646079D01*
G01D02*
X450783D01*
G01X437940Y685556D02*
Y688756D01*
G01Y677556D02*
Y680756D01*
G01Y681556D02*
Y684756D01*
G01Y689556D02*
Y692756D01*
G01Y705556D02*
Y708756D01*
G01Y701556D02*
Y704756D01*
G01Y697556D02*
Y700756D01*
G01Y693556D02*
Y696756D01*
G01Y709556D02*
Y712756D01*
G01Y713556D02*
Y716756D01*
G01X432755Y720728D02*
Y717528D01*
G01X438955Y720728D02*
X432755D01*
G01X438955Y717528D02*
Y720728D01*
G01X432755Y717528D02*
X438955D01*
G01X443940Y729156D02*
X446940D01*
G01X443840Y726056D02*
X447040D01*
G01X443840Y732256D02*
Y726056D01*
G01X447040Y732256D02*
X443840D01*
G01X447040Y726056D02*
Y732256D01*
G01X434340Y737556D02*
X437540D01*
G01X434340Y743756D02*
Y737556D01*
G01X437540D02*
Y743756D01*
G01X434840Y726056D02*
X438040D01*
G01X434840Y732256D02*
Y726056D01*
G01X438040Y732256D02*
X434840D01*
G01X438040Y726056D02*
Y732256D01*
G01X434940Y729156D02*
X437940D01*
G01X443340Y737556D02*
X446540D01*
G01X443340Y743756D02*
Y737556D01*
G01X446540D02*
Y743756D01*
G01X442040Y737556D02*
Y743756D01*
G01X438840Y737556D02*
X442040D01*
G01X438840Y743756D02*
Y737556D01*
G01X442540Y732256D02*
X439340D01*
G01Y726056D02*
X442540D01*
G01X439340Y732256D02*
Y726056D01*
G01X442540D02*
Y732256D01*
G01X433040Y737556D02*
Y743756D01*
G01X448967Y746731D02*
X449122Y746501D01*
X449225Y746233D01*
Y745926D01*
X449070Y745581D01*
X448812Y745313D01*
X448502Y745121D01*
X447985Y744968D01*
X447520Y744930D01*
X447055Y745006D01*
X446745Y745121D01*
X446435Y745351D01*
X446228Y745620D01*
X446125Y745888D01*
Y746156D01*
X446228Y746425D01*
X446383Y746655D01*
X446590Y746846D01*
G01X446125Y748911D02*
X446797Y748988D01*
X447365Y749103D01*
X447882Y749256D01*
X448450Y749448D01*
X449225Y749755D01*
Y748221D01*
G01X448708Y751360D02*
X449018Y751590D01*
X449173Y751858D01*
X449225Y752165D01*
X449122Y752548D01*
X448863Y752816D01*
X448553Y752893D01*
X448243Y752855D01*
X447985Y752701D01*
X447468Y751935D01*
X447107Y751590D01*
X446590Y751360D01*
X446125Y751283D01*
Y752893D01*
G01Y755648D02*
X449225D01*
X447003Y754230D01*
Y756146D01*
G01X437540Y743756D02*
X434340D01*
G01X434440Y740656D02*
X437440D01*
G01X439724Y746731D02*
X439879Y746501D01*
X439982Y746233D01*
Y745926D01*
X439827Y745581D01*
X439569Y745313D01*
X439259Y745121D01*
X438742Y744968D01*
X438277Y744930D01*
X437812Y745006D01*
X437502Y745121D01*
X437192Y745351D01*
X436985Y745620D01*
X436882Y745888D01*
Y746156D01*
X436985Y746425D01*
X437140Y746655D01*
X437347Y746846D01*
G01X436882Y748911D02*
X437554Y748988D01*
X438122Y749103D01*
X438639Y749256D01*
X439207Y749448D01*
X439982Y749755D01*
Y748221D01*
G01X437502Y751245D02*
X437140Y751475D01*
X436934Y751781D01*
X436882Y752126D01*
X436934Y752433D01*
X437192Y752740D01*
X437502Y752931D01*
X437812Y752970D01*
X438174Y752893D01*
X438432Y752625D01*
X438535Y752356D01*
Y752011D01*
G01Y752356D02*
X438690Y752586D01*
X438949Y752778D01*
X439259Y752855D01*
X439569Y752778D01*
X439827Y752586D01*
X439982Y752241D01*
X439930Y751896D01*
X439724Y751551D01*
G01X439982Y755188D02*
X439879Y754881D01*
X439620Y754651D01*
X439310Y754498D01*
X438897Y754383D01*
X438432Y754345D01*
X437967Y754383D01*
X437554Y754498D01*
X437244Y754651D01*
X436985Y754881D01*
X436882Y755188D01*
X436985Y755495D01*
X437244Y755725D01*
X437554Y755878D01*
X437967Y755993D01*
X438432Y756031D01*
X438897Y755993D01*
X439310Y755878D01*
X439620Y755725D01*
X439879Y755495D01*
X439982Y755188D01*
G01X446540Y743756D02*
X443340D01*
G01X443440Y740656D02*
X446440D01*
G01X442040Y743756D02*
X438840D01*
G01X441434Y745121D02*
X444534D01*
Y746080D01*
X444379Y746386D01*
X444172Y746578D01*
X443759Y746655D01*
X443346Y746578D01*
X443087Y746348D01*
X442932Y746080D01*
Y745121D01*
G01Y746080D02*
X441434Y746655D01*
G01X441796Y748336D02*
X441537Y748605D01*
X441434Y748911D01*
X441537Y749218D01*
X441847Y749486D01*
X442312Y749678D01*
X442777Y749755D01*
X443346D01*
X443811Y749678D01*
X444224Y749486D01*
X444431Y749256D01*
X444534Y748988D01*
X444431Y748681D01*
X444224Y748451D01*
X443914Y748298D01*
X443501Y748221D01*
X443139Y748298D01*
X442777Y748490D01*
X442571Y748720D01*
X442519Y748988D01*
X442622Y749295D01*
X442881Y749525D01*
X443346Y749755D01*
G01X442726Y751360D02*
X443087Y751628D01*
X443294Y751858D01*
X443397Y752165D01*
X443294Y752433D01*
X443087Y752625D01*
X442777Y752778D01*
X442416Y752816D01*
X442106Y752778D01*
X441796Y752625D01*
X441537Y752395D01*
X441434Y752126D01*
X441537Y751820D01*
X441847Y751551D01*
X442312Y751398D01*
X442829Y751360D01*
X443501Y751436D01*
X443862Y751551D01*
X444224Y751743D01*
X444482Y752011D01*
X444534Y752280D01*
X444431Y752548D01*
X444172Y752740D01*
G01X441434Y755648D02*
X444534D01*
X442312Y754230D01*
Y756146D01*
G01X440212Y758713D02*
X440367Y758483D01*
X440470Y758215D01*
Y757908D01*
X440315Y757563D01*
X440057Y757295D01*
X439747Y757103D01*
X439230Y756950D01*
X438765Y756912D01*
X438300Y756988D01*
X437990Y757103D01*
X437680Y757333D01*
X437473Y757602D01*
X437370Y757870D01*
Y758138D01*
X437473Y758407D01*
X437628Y758637D01*
X437835Y758828D01*
G01X437370Y760893D02*
X438042Y760970D01*
X438610Y761085D01*
X439127Y761238D01*
X439695Y761430D01*
X440470Y761737D01*
Y760203D01*
G01X437990Y763227D02*
X437628Y763457D01*
X437422Y763763D01*
X437370Y764108D01*
X437422Y764415D01*
X437680Y764722D01*
X437990Y764913D01*
X438300Y764952D01*
X438662Y764875D01*
X438920Y764607D01*
X439023Y764338D01*
Y763993D01*
G01Y764338D02*
X439178Y764568D01*
X439437Y764760D01*
X439747Y764837D01*
X440057Y764760D01*
X440315Y764568D01*
X440470Y764223D01*
X440418Y763878D01*
X440212Y763533D01*
G01X437990Y766327D02*
X437628Y766557D01*
X437422Y766863D01*
X437370Y767208D01*
X437422Y767515D01*
X437680Y767822D01*
X437990Y768013D01*
X438300Y768052D01*
X438662Y767975D01*
X438920Y767707D01*
X439023Y767438D01*
Y767093D01*
G01Y767438D02*
X439178Y767668D01*
X439437Y767860D01*
X439747Y767937D01*
X440057Y767860D01*
X440315Y767668D01*
X440470Y767323D01*
X440418Y766978D01*
X440212Y766633D01*
G01X449179Y758713D02*
X449334Y758483D01*
X449437Y758215D01*
Y757908D01*
X449282Y757563D01*
X449024Y757295D01*
X448714Y757103D01*
X448197Y756950D01*
X447732Y756912D01*
X447267Y756988D01*
X446957Y757103D01*
X446647Y757333D01*
X446440Y757602D01*
X446337Y757870D01*
Y758138D01*
X446440Y758407D01*
X446595Y758637D01*
X446802Y758828D01*
G01X446337Y760893D02*
X447009Y760970D01*
X447577Y761085D01*
X448094Y761238D01*
X448662Y761430D01*
X449437Y761737D01*
Y760203D01*
G01X448920Y763342D02*
X449230Y763572D01*
X449385Y763840D01*
X449437Y764147D01*
X449334Y764530D01*
X449075Y764798D01*
X448765Y764875D01*
X448455Y764837D01*
X448197Y764683D01*
X447680Y763917D01*
X447319Y763572D01*
X446802Y763342D01*
X446337Y763265D01*
Y764875D01*
G01Y767093D02*
X447009Y767170D01*
X447577Y767285D01*
X448094Y767438D01*
X448662Y767630D01*
X449437Y767937D01*
Y766403D01*
G01X441785Y757103D02*
X444885D01*
Y758062D01*
X444730Y758368D01*
X444523Y758560D01*
X444110Y758637D01*
X443697Y758560D01*
X443438Y758330D01*
X443283Y758062D01*
Y757103D01*
G01Y758062D02*
X441785Y758637D01*
G01X442147Y760318D02*
X441888Y760587D01*
X441785Y760893D01*
X441888Y761200D01*
X442198Y761468D01*
X442663Y761660D01*
X443128Y761737D01*
X443697D01*
X444162Y761660D01*
X444575Y761468D01*
X444782Y761238D01*
X444885Y760970D01*
X444782Y760663D01*
X444575Y760433D01*
X444265Y760280D01*
X443852Y760203D01*
X443490Y760280D01*
X443128Y760472D01*
X442922Y760702D01*
X442870Y760970D01*
X442973Y761277D01*
X443232Y761507D01*
X443697Y761737D01*
G01X443077Y763342D02*
X443438Y763610D01*
X443645Y763840D01*
X443748Y764147D01*
X443645Y764415D01*
X443438Y764607D01*
X443128Y764760D01*
X442767Y764798D01*
X442457Y764760D01*
X442147Y764607D01*
X441888Y764377D01*
X441785Y764108D01*
X441888Y763802D01*
X442198Y763533D01*
X442663Y763380D01*
X443180Y763342D01*
X443852Y763418D01*
X444213Y763533D01*
X444575Y763725D01*
X444833Y763993D01*
X444885Y764262D01*
X444782Y764530D01*
X444523Y764722D01*
G01X441785Y767093D02*
X442457Y767170D01*
X443025Y767285D01*
X443542Y767438D01*
X444110Y767630D01*
X444885Y767937D01*
Y766403D01*
G01X470552Y123643D02*
X470782Y123798D01*
X471050Y123901D01*
X471357D01*
X471702Y123746D01*
X471970Y123488D01*
X472162Y123178D01*
X472315Y122661D01*
X472353Y122196D01*
X472277Y121731D01*
X472162Y121421D01*
X471932Y121111D01*
X471663Y120904D01*
X471395Y120801D01*
X471127D01*
X470858Y120904D01*
X470628Y121059D01*
X470437Y121266D01*
G01X467835Y120801D02*
Y123901D01*
X469253Y121679D01*
X467337D01*
G01X465195Y120801D02*
X464927Y120853D01*
X464620Y121008D01*
X464428Y121266D01*
X464352Y121628D01*
X464428Y121989D01*
X464658Y122299D01*
X465003Y122454D01*
X465387D01*
X465617Y122558D01*
X465808Y122816D01*
X465885Y123178D01*
X465770Y123539D01*
X465502Y123798D01*
X465195Y123901D01*
X464888Y123798D01*
X464620Y123539D01*
X464505Y123178D01*
X464582Y122816D01*
X464773Y122558D01*
X465003Y122454D01*
X465387D01*
X465732Y122299D01*
X465962Y121989D01*
X466038Y121628D01*
X465962Y121266D01*
X465770Y121008D01*
X465463Y120853D01*
X465195Y120801D01*
G01X462172D02*
X462095Y121473D01*
X461980Y122041D01*
X461827Y122558D01*
X461635Y123126D01*
X461328Y123901D01*
X462862D01*
G01X470688Y127923D02*
X470918Y128078D01*
X471186Y128181D01*
X471493D01*
X471838Y128026D01*
X472106Y127768D01*
X472298Y127458D01*
X472451Y126941D01*
X472489Y126476D01*
X472413Y126011D01*
X472298Y125701D01*
X472068Y125391D01*
X471799Y125184D01*
X471531Y125081D01*
X471263D01*
X470994Y125184D01*
X470764Y125339D01*
X470573Y125546D01*
G01X467971Y125081D02*
Y128181D01*
X469389Y125959D01*
X467473D01*
G01X465331Y125081D02*
X465063Y125133D01*
X464756Y125288D01*
X464564Y125546D01*
X464488Y125908D01*
X464564Y126269D01*
X464794Y126579D01*
X465139Y126734D01*
X465523D01*
X465753Y126838D01*
X465944Y127096D01*
X466021Y127458D01*
X465906Y127819D01*
X465638Y128078D01*
X465331Y128181D01*
X465024Y128078D01*
X464756Y127819D01*
X464641Y127458D01*
X464718Y127096D01*
X464909Y126838D01*
X465139Y126734D01*
X465523D01*
X465868Y126579D01*
X466098Y126269D01*
X466174Y125908D01*
X466098Y125546D01*
X465906Y125288D01*
X465599Y125133D01*
X465331Y125081D01*
G01X462231D02*
X461963Y125133D01*
X461656Y125288D01*
X461464Y125546D01*
X461388Y125908D01*
X461464Y126269D01*
X461694Y126579D01*
X462039Y126734D01*
X462423D01*
X462653Y126838D01*
X462844Y127096D01*
X462921Y127458D01*
X462806Y127819D01*
X462538Y128078D01*
X462231Y128181D01*
X461924Y128078D01*
X461656Y127819D01*
X461541Y127458D01*
X461618Y127096D01*
X461809Y126838D01*
X462039Y126734D01*
X462423D01*
X462768Y126579D01*
X462998Y126269D01*
X463074Y125908D01*
X462998Y125546D01*
X462806Y125288D01*
X462499Y125133D01*
X462231Y125081D01*
G01X465798Y138262D02*
Y141362D01*
X464839D01*
X464533Y141207D01*
X464341Y141000D01*
X464264Y140587D01*
X464341Y140174D01*
X464571Y139915D01*
X464839Y139760D01*
X465798D01*
G01X464839D02*
X464264Y138262D01*
G01X461931D02*
Y141362D01*
X462391Y140742D01*
G01Y138262D02*
X461471D01*
G01X459559Y140845D02*
X459329Y141155D01*
X459061Y141310D01*
X458754Y141362D01*
X458371Y141259D01*
X458103Y141000D01*
X458026Y140690D01*
X458064Y140380D01*
X458218Y140122D01*
X458984Y139605D01*
X459329Y139244D01*
X459559Y138727D01*
X459636Y138262D01*
X458026D01*
G01X455731Y141362D02*
X456038Y141259D01*
X456268Y141000D01*
X456421Y140690D01*
X456536Y140277D01*
X456574Y139812D01*
X456536Y139347D01*
X456421Y138934D01*
X456268Y138624D01*
X456038Y138365D01*
X455731Y138262D01*
X455424Y138365D01*
X455194Y138624D01*
X455041Y138934D01*
X454926Y139347D01*
X454888Y139812D01*
X454926Y140277D01*
X455041Y140690D01*
X455194Y141000D01*
X455424Y141259D01*
X455731Y141362D01*
G01X453359Y140845D02*
X453129Y141155D01*
X452861Y141310D01*
X452554Y141362D01*
X452171Y141259D01*
X451903Y141000D01*
X451826Y140690D01*
X451864Y140380D01*
X452018Y140122D01*
X452784Y139605D01*
X453129Y139244D01*
X453359Y138727D01*
X453436Y138262D01*
X451826D01*
G01X465798Y134262D02*
Y137362D01*
X464839D01*
X464533Y137207D01*
X464341Y137000D01*
X464264Y136587D01*
X464341Y136174D01*
X464571Y135915D01*
X464839Y135760D01*
X465798D01*
G01X464839D02*
X464264Y134262D01*
G01X461931D02*
Y137362D01*
X462391Y136742D01*
G01Y134262D02*
X461471D01*
G01X459559Y136845D02*
X459329Y137155D01*
X459061Y137310D01*
X458754Y137362D01*
X458371Y137259D01*
X458103Y137000D01*
X458026Y136690D01*
X458064Y136380D01*
X458218Y136122D01*
X458984Y135605D01*
X459329Y135244D01*
X459559Y134727D01*
X459636Y134262D01*
X458026D01*
G01X455731Y137362D02*
X456038Y137259D01*
X456268Y137000D01*
X456421Y136690D01*
X456536Y136277D01*
X456574Y135812D01*
X456536Y135347D01*
X456421Y134934D01*
X456268Y134624D01*
X456038Y134365D01*
X455731Y134262D01*
X455424Y134365D01*
X455194Y134624D01*
X455041Y134934D01*
X454926Y135347D01*
X454888Y135812D01*
X454926Y136277D01*
X455041Y136690D01*
X455194Y137000D01*
X455424Y137259D01*
X455731Y137362D01*
G01X452631Y134262D02*
Y137362D01*
X453091Y136742D01*
G01Y134262D02*
X452171D01*
G01X465798Y142262D02*
Y145362D01*
X464839D01*
X464533Y145207D01*
X464341Y145000D01*
X464264Y144587D01*
X464341Y144174D01*
X464571Y143915D01*
X464839Y143760D01*
X465798D01*
G01X464839D02*
X464264Y142262D01*
G01X461931D02*
Y145362D01*
X462391Y144742D01*
G01Y142262D02*
X461471D01*
G01X459559Y144845D02*
X459329Y145155D01*
X459061Y145310D01*
X458754Y145362D01*
X458371Y145259D01*
X458103Y145000D01*
X458026Y144690D01*
X458064Y144380D01*
X458218Y144122D01*
X458984Y143605D01*
X459329Y143244D01*
X459559Y142727D01*
X459636Y142262D01*
X458026D01*
G01X455731Y145362D02*
X456038Y145259D01*
X456268Y145000D01*
X456421Y144690D01*
X456536Y144277D01*
X456574Y143812D01*
X456536Y143347D01*
X456421Y142934D01*
X456268Y142624D01*
X456038Y142365D01*
X455731Y142262D01*
X455424Y142365D01*
X455194Y142624D01*
X455041Y142934D01*
X454926Y143347D01*
X454888Y143812D01*
X454926Y144277D01*
X455041Y144690D01*
X455194Y145000D01*
X455424Y145259D01*
X455731Y145362D01*
G01X453474Y142882D02*
X453244Y142520D01*
X452938Y142314D01*
X452593Y142262D01*
X452286Y142314D01*
X451979Y142572D01*
X451788Y142882D01*
X451749Y143192D01*
X451826Y143554D01*
X452094Y143812D01*
X452363Y143915D01*
X452708D01*
G01X452363D02*
X452133Y144070D01*
X451941Y144329D01*
X451864Y144639D01*
X451941Y144949D01*
X452133Y145207D01*
X452478Y145362D01*
X452823Y145310D01*
X453168Y145104D01*
G01X465798Y146262D02*
Y149362D01*
X464839D01*
X464533Y149207D01*
X464341Y149000D01*
X464264Y148587D01*
X464341Y148174D01*
X464571Y147915D01*
X464839Y147760D01*
X465798D01*
G01X464839D02*
X464264Y146262D01*
G01X461931D02*
Y149362D01*
X462391Y148742D01*
G01Y146262D02*
X461471D01*
G01X459559Y148845D02*
X459329Y149155D01*
X459061Y149310D01*
X458754Y149362D01*
X458371Y149259D01*
X458103Y149000D01*
X458026Y148690D01*
X458064Y148380D01*
X458218Y148122D01*
X458984Y147605D01*
X459329Y147244D01*
X459559Y146727D01*
X459636Y146262D01*
X458026D01*
G01X455731Y149362D02*
X456038Y149259D01*
X456268Y149000D01*
X456421Y148690D01*
X456536Y148277D01*
X456574Y147812D01*
X456536Y147347D01*
X456421Y146934D01*
X456268Y146624D01*
X456038Y146365D01*
X455731Y146262D01*
X455424Y146365D01*
X455194Y146624D01*
X455041Y146934D01*
X454926Y147347D01*
X454888Y147812D01*
X454926Y148277D01*
X455041Y148690D01*
X455194Y149000D01*
X455424Y149259D01*
X455731Y149362D01*
G01X452171Y146262D02*
Y149362D01*
X453589Y147140D01*
X451673D01*
G01X469259Y170583D02*
Y173683D01*
X468300D01*
X467994Y173528D01*
X467802Y173321D01*
X467725Y172908D01*
X467802Y172495D01*
X468032Y172236D01*
X468300Y172081D01*
X469259D01*
G01X468300D02*
X467725Y170583D01*
G01X465392D02*
Y173683D01*
X465852Y173063D01*
G01Y170583D02*
X464932D01*
G01X462292D02*
X462024Y170635D01*
X461717Y170790D01*
X461525Y171048D01*
X461449Y171410D01*
X461525Y171771D01*
X461755Y172081D01*
X462100Y172236D01*
X462484D01*
X462714Y172340D01*
X462905Y172598D01*
X462982Y172960D01*
X462867Y173321D01*
X462599Y173580D01*
X462292Y173683D01*
X461985Y173580D01*
X461717Y173321D01*
X461602Y172960D01*
X461679Y172598D01*
X461870Y172340D01*
X462100Y172236D01*
X462484D01*
X462829Y172081D01*
X463059Y171771D01*
X463135Y171410D01*
X463059Y171048D01*
X462867Y170790D01*
X462560Y170635D01*
X462292Y170583D01*
G01X460035Y171203D02*
X459805Y170841D01*
X459499Y170635D01*
X459154Y170583D01*
X458847Y170635D01*
X458540Y170893D01*
X458349Y171203D01*
X458310Y171513D01*
X458387Y171875D01*
X458655Y172133D01*
X458924Y172236D01*
X459269D01*
G01X458924D02*
X458694Y172391D01*
X458502Y172650D01*
X458425Y172960D01*
X458502Y173270D01*
X458694Y173528D01*
X459039Y173683D01*
X459384Y173631D01*
X459729Y173425D01*
G01X469259Y161619D02*
Y164719D01*
X468300D01*
X467994Y164564D01*
X467802Y164357D01*
X467725Y163944D01*
X467802Y163531D01*
X468032Y163272D01*
X468300Y163117D01*
X469259D01*
G01X468300D02*
X467725Y161619D01*
G01X465392D02*
Y164719D01*
X465852Y164099D01*
G01Y161619D02*
X464932D01*
G01X462292D02*
X462024Y161671D01*
X461717Y161826D01*
X461525Y162084D01*
X461449Y162446D01*
X461525Y162807D01*
X461755Y163117D01*
X462100Y163272D01*
X462484D01*
X462714Y163376D01*
X462905Y163634D01*
X462982Y163996D01*
X462867Y164357D01*
X462599Y164616D01*
X462292Y164719D01*
X461985Y164616D01*
X461717Y164357D01*
X461602Y163996D01*
X461679Y163634D01*
X461870Y163376D01*
X462100Y163272D01*
X462484D01*
X462829Y163117D01*
X463059Y162807D01*
X463135Y162446D01*
X463059Y162084D01*
X462867Y161826D01*
X462560Y161671D01*
X462292Y161619D01*
G01X460035Y162084D02*
X459805Y161826D01*
X459537Y161671D01*
X459192Y161619D01*
X458847Y161722D01*
X458579Y161929D01*
X458387Y162291D01*
X458349Y162704D01*
X458425Y163117D01*
X458617Y163376D01*
X458885Y163582D01*
X459154Y163634D01*
X459422Y163582D01*
X459767Y163376D01*
X459652Y164719D01*
X458617D01*
G01X469259Y166195D02*
Y169295D01*
X468300D01*
X467994Y169140D01*
X467802Y168933D01*
X467725Y168520D01*
X467802Y168107D01*
X468032Y167848D01*
X468300Y167693D01*
X469259D01*
G01X468300D02*
X467725Y166195D01*
G01X465392D02*
Y169295D01*
X465852Y168675D01*
G01Y166195D02*
X464932D01*
G01X462292D02*
X462024Y166247D01*
X461717Y166402D01*
X461525Y166660D01*
X461449Y167022D01*
X461525Y167383D01*
X461755Y167693D01*
X462100Y167848D01*
X462484D01*
X462714Y167952D01*
X462905Y168210D01*
X462982Y168572D01*
X462867Y168933D01*
X462599Y169192D01*
X462292Y169295D01*
X461985Y169192D01*
X461717Y168933D01*
X461602Y168572D01*
X461679Y168210D01*
X461870Y167952D01*
X462100Y167848D01*
X462484D01*
X462829Y167693D01*
X463059Y167383D01*
X463135Y167022D01*
X463059Y166660D01*
X462867Y166402D01*
X462560Y166247D01*
X462292Y166195D01*
G01X458732D02*
Y169295D01*
X460150Y167073D01*
X458234D01*
G01X469259Y174782D02*
Y177882D01*
X468300D01*
X467994Y177727D01*
X467802Y177520D01*
X467725Y177107D01*
X467802Y176694D01*
X468032Y176435D01*
X468300Y176280D01*
X469259D01*
G01X468300D02*
X467725Y174782D01*
G01X465392D02*
Y177882D01*
X465852Y177262D01*
G01Y174782D02*
X464932D01*
G01X462292D02*
X462024Y174834D01*
X461717Y174989D01*
X461525Y175247D01*
X461449Y175609D01*
X461525Y175970D01*
X461755Y176280D01*
X462100Y176435D01*
X462484D01*
X462714Y176539D01*
X462905Y176797D01*
X462982Y177159D01*
X462867Y177520D01*
X462599Y177779D01*
X462292Y177882D01*
X461985Y177779D01*
X461717Y177520D01*
X461602Y177159D01*
X461679Y176797D01*
X461870Y176539D01*
X462100Y176435D01*
X462484D01*
X462829Y176280D01*
X463059Y175970D01*
X463135Y175609D01*
X463059Y175247D01*
X462867Y174989D01*
X462560Y174834D01*
X462292Y174782D01*
G01X459920Y177365D02*
X459690Y177675D01*
X459422Y177830D01*
X459115Y177882D01*
X458732Y177779D01*
X458464Y177520D01*
X458387Y177210D01*
X458425Y176900D01*
X458579Y176642D01*
X459345Y176125D01*
X459690Y175764D01*
X459920Y175247D01*
X459997Y174782D01*
X458387D01*
G01X460600Y201400D02*
Y207600D01*
X457400D01*
Y201400D01*
X460600D01*
G01X457500Y209883D02*
X460600D01*
Y210842D01*
X460445Y211148D01*
X460238Y211340D01*
X459825Y211417D01*
X459412Y211340D01*
X459153Y211110D01*
X458998Y210842D01*
Y209883D01*
G01Y210842D02*
X457500Y211417D01*
G01Y213750D02*
X460600D01*
X459980Y213290D01*
G01X457500D02*
Y214210D01*
G01X460083Y216122D02*
X460393Y216352D01*
X460548Y216620D01*
X460600Y216927D01*
X460497Y217310D01*
X460238Y217578D01*
X459928Y217655D01*
X459618Y217617D01*
X459360Y217463D01*
X458843Y216697D01*
X458482Y216352D01*
X457965Y216122D01*
X457500Y216045D01*
Y217655D01*
G01Y219950D02*
X457552Y220218D01*
X457707Y220525D01*
X457965Y220717D01*
X458327Y220793D01*
X458688Y220717D01*
X458998Y220487D01*
X459153Y220142D01*
Y219758D01*
X459257Y219528D01*
X459515Y219337D01*
X459877Y219260D01*
X460238Y219375D01*
X460497Y219643D01*
X460600Y219950D01*
X460497Y220257D01*
X460238Y220525D01*
X459877Y220640D01*
X459515Y220563D01*
X459257Y220372D01*
X459153Y220142D01*
Y219758D01*
X458998Y219413D01*
X458688Y219183D01*
X458327Y219107D01*
X457965Y219183D01*
X457707Y219375D01*
X457552Y219682D01*
X457500Y219950D01*
G01X457862Y222398D02*
X457603Y222667D01*
X457500Y222973D01*
X457603Y223280D01*
X457913Y223548D01*
X458378Y223740D01*
X458843Y223817D01*
X459412D01*
X459877Y223740D01*
X460290Y223548D01*
X460497Y223318D01*
X460600Y223050D01*
X460497Y222743D01*
X460290Y222513D01*
X459980Y222360D01*
X459567Y222283D01*
X459205Y222360D01*
X458843Y222552D01*
X458637Y222782D01*
X458585Y223050D01*
X458688Y223357D01*
X458947Y223587D01*
X459412Y223817D01*
G01X456974Y415277D02*
G02X471286Y377165I-43588J-38112D01*
G01X473756Y423142D02*
Y426242D01*
X472836D01*
X472529Y426087D01*
X472299Y425725D01*
X472222Y425312D01*
X472299Y424899D01*
X472491Y424589D01*
X472836Y424434D01*
X473756D01*
G01X469046Y425984D02*
X469276Y426139D01*
X469544Y426242D01*
X469851D01*
X470196Y426087D01*
X470464Y425829D01*
X470656Y425519D01*
X470809Y425002D01*
X470847Y424537D01*
X470771Y424072D01*
X470656Y423762D01*
X470426Y423452D01*
X470157Y423245D01*
X469889Y423142D01*
X469621D01*
X469352Y423245D01*
X469122Y423400D01*
X468931Y423607D01*
G01X466789Y423142D02*
Y426242D01*
X467249Y425622D01*
G01Y423142D02*
X466329D01*
G01X463689D02*
Y426242D01*
X464149Y425622D01*
G01Y423142D02*
X463229D01*
G01X460589D02*
X460321Y423194D01*
X460014Y423349D01*
X459822Y423607D01*
X459746Y423969D01*
X459822Y424330D01*
X460052Y424640D01*
X460397Y424795D01*
X460781D01*
X461011Y424899D01*
X461202Y425157D01*
X461279Y425519D01*
X461164Y425880D01*
X460896Y426139D01*
X460589Y426242D01*
X460282Y426139D01*
X460014Y425880D01*
X459899Y425519D01*
X459976Y425157D01*
X460167Y424899D01*
X460397Y424795D01*
X460781D01*
X461126Y424640D01*
X461356Y424330D01*
X461432Y423969D01*
X461356Y423607D01*
X461164Y423349D01*
X460857Y423194D01*
X460589Y423142D01*
G01X459081Y421229D02*
Y428029D01*
G01X451581Y427929D02*
Y421329D01*
G01X473756Y430927D02*
Y434027D01*
X472836D01*
X472529Y433872D01*
X472299Y433510D01*
X472222Y433097D01*
X472299Y432684D01*
X472491Y432374D01*
X472836Y432219D01*
X473756D01*
G01X469046Y433769D02*
X469276Y433924D01*
X469544Y434027D01*
X469851D01*
X470196Y433872D01*
X470464Y433614D01*
X470656Y433304D01*
X470809Y432787D01*
X470847Y432322D01*
X470771Y431857D01*
X470656Y431547D01*
X470426Y431237D01*
X470157Y431030D01*
X469889Y430927D01*
X469621D01*
X469352Y431030D01*
X469122Y431185D01*
X468931Y431392D01*
G01X466789Y430927D02*
Y434027D01*
X467249Y433407D01*
G01Y430927D02*
X466329D01*
G01X464417Y433510D02*
X464187Y433820D01*
X463919Y433975D01*
X463612Y434027D01*
X463229Y433924D01*
X462961Y433665D01*
X462884Y433355D01*
X462922Y433045D01*
X463076Y432787D01*
X463842Y432270D01*
X464187Y431909D01*
X464417Y431392D01*
X464494Y430927D01*
X462884D01*
G01X460589D02*
Y434027D01*
X461049Y433407D01*
G01Y430927D02*
X460129D01*
G01X459081Y429398D02*
Y436198D01*
G01X451581Y436098D02*
Y429498D01*
G01X452557Y484780D02*
Y490980D01*
G01X449357D02*
Y484780D01*
G01D02*
X452557D01*
G01X460663Y476723D02*
Y494123D01*
G01X453263Y476723D02*
X460663D01*
G01X453263Y494123D02*
Y476723D01*
G01X460663Y485423D02*
X453263D01*
G01X461593Y476723D02*
X468993D01*
G01X461593Y494123D02*
Y476723D01*
G01X468993Y485423D02*
X461593D01*
G01X452244Y497972D02*
X455344D01*
Y498892D01*
X455189Y499199D01*
X454827Y499429D01*
X454414Y499506D01*
X454001Y499429D01*
X453691Y499237D01*
X453536Y498892D01*
Y497972D01*
G01X455086Y502682D02*
X455241Y502452D01*
X455344Y502184D01*
Y501877D01*
X455189Y501532D01*
X454931Y501264D01*
X454621Y501072D01*
X454104Y500919D01*
X453639Y500881D01*
X453174Y500957D01*
X452864Y501072D01*
X452554Y501302D01*
X452347Y501571D01*
X452244Y501839D01*
Y502107D01*
X452347Y502376D01*
X452502Y502606D01*
X452709Y502797D01*
G01X452606Y504287D02*
X452347Y504556D01*
X452244Y504862D01*
X452347Y505169D01*
X452657Y505437D01*
X453122Y505629D01*
X453587Y505706D01*
X454156D01*
X454621Y505629D01*
X455034Y505437D01*
X455241Y505207D01*
X455344Y504939D01*
X455241Y504632D01*
X455034Y504402D01*
X454724Y504249D01*
X454311Y504172D01*
X453949Y504249D01*
X453587Y504441D01*
X453381Y504671D01*
X453329Y504939D01*
X453432Y505246D01*
X453691Y505476D01*
X454156Y505706D01*
G01X455344Y508039D02*
X455241Y507732D01*
X454982Y507502D01*
X454672Y507349D01*
X454259Y507234D01*
X453794Y507196D01*
X453329Y507234D01*
X452916Y507349D01*
X452606Y507502D01*
X452347Y507732D01*
X452244Y508039D01*
X452347Y508346D01*
X452606Y508576D01*
X452916Y508729D01*
X453329Y508844D01*
X453794Y508882D01*
X454259Y508844D01*
X454672Y508729D01*
X454982Y508576D01*
X455241Y508346D01*
X455344Y508039D01*
G01X449457Y487880D02*
X452457D01*
G01X452557Y490980D02*
X449357D01*
G01X456383Y497972D02*
X459483D01*
Y498892D01*
X459328Y499199D01*
X458966Y499429D01*
X458553Y499506D01*
X458140Y499429D01*
X457830Y499237D01*
X457675Y498892D01*
Y497972D01*
G01X459225Y502682D02*
X459380Y502452D01*
X459483Y502184D01*
Y501877D01*
X459328Y501532D01*
X459070Y501264D01*
X458760Y501072D01*
X458243Y500919D01*
X457778Y500881D01*
X457313Y500957D01*
X457003Y501072D01*
X456693Y501302D01*
X456486Y501571D01*
X456383Y501839D01*
Y502107D01*
X456486Y502376D01*
X456641Y502606D01*
X456848Y502797D01*
G01X456745Y504287D02*
X456486Y504556D01*
X456383Y504862D01*
X456486Y505169D01*
X456796Y505437D01*
X457261Y505629D01*
X457726Y505706D01*
X458295D01*
X458760Y505629D01*
X459173Y505437D01*
X459380Y505207D01*
X459483Y504939D01*
X459380Y504632D01*
X459173Y504402D01*
X458863Y504249D01*
X458450Y504172D01*
X458088Y504249D01*
X457726Y504441D01*
X457520Y504671D01*
X457468Y504939D01*
X457571Y505246D01*
X457830Y505476D01*
X458295Y505706D01*
G01X458966Y507311D02*
X459276Y507541D01*
X459431Y507809D01*
X459483Y508116D01*
X459380Y508499D01*
X459121Y508767D01*
X458811Y508844D01*
X458501Y508806D01*
X458243Y508652D01*
X457726Y507886D01*
X457365Y507541D01*
X456848Y507311D01*
X456383Y507234D01*
Y508844D01*
G01X460663Y494123D02*
X453263D01*
G01X460428Y497940D02*
X463528D01*
Y498860D01*
X463373Y499167D01*
X463011Y499397D01*
X462598Y499474D01*
X462185Y499397D01*
X461875Y499205D01*
X461720Y498860D01*
Y497940D01*
G01X463270Y502650D02*
X463425Y502420D01*
X463528Y502152D01*
Y501845D01*
X463373Y501500D01*
X463115Y501232D01*
X462805Y501040D01*
X462288Y500887D01*
X461823Y500849D01*
X461358Y500925D01*
X461048Y501040D01*
X460738Y501270D01*
X460531Y501539D01*
X460428Y501807D01*
Y502075D01*
X460531Y502344D01*
X460686Y502574D01*
X460893Y502765D01*
G01X460790Y504255D02*
X460531Y504524D01*
X460428Y504830D01*
X460531Y505137D01*
X460841Y505405D01*
X461306Y505597D01*
X461771Y505674D01*
X462340D01*
X462805Y505597D01*
X463218Y505405D01*
X463425Y505175D01*
X463528Y504907D01*
X463425Y504600D01*
X463218Y504370D01*
X462908Y504217D01*
X462495Y504140D01*
X462133Y504217D01*
X461771Y504409D01*
X461565Y504639D01*
X461513Y504907D01*
X461616Y505214D01*
X461875Y505444D01*
X462340Y505674D01*
G01X461048Y507164D02*
X460686Y507394D01*
X460480Y507700D01*
X460428Y508045D01*
X460480Y508352D01*
X460738Y508659D01*
X461048Y508850D01*
X461358Y508889D01*
X461720Y508812D01*
X461978Y508544D01*
X462081Y508275D01*
Y507930D01*
G01Y508275D02*
X462236Y508505D01*
X462495Y508697D01*
X462805Y508774D01*
X463115Y508697D01*
X463373Y508505D01*
X463528Y508160D01*
X463476Y507815D01*
X463270Y507470D01*
G01X468993Y494123D02*
X461593D01*
G01X467794Y557774D02*
X468024Y557929D01*
X468292Y558032D01*
X468599D01*
X468944Y557877D01*
X469212Y557619D01*
X469404Y557309D01*
X469557Y556792D01*
X469595Y556327D01*
X469519Y555862D01*
X469404Y555552D01*
X469174Y555242D01*
X468905Y555035D01*
X468637Y554932D01*
X468369D01*
X468100Y555035D01*
X467870Y555190D01*
X467679Y555397D01*
G01X465537Y554932D02*
Y558032D01*
X465997Y557412D01*
G01Y554932D02*
X465077D01*
G01X462437D02*
X462169Y554984D01*
X461862Y555139D01*
X461670Y555397D01*
X461594Y555759D01*
X461670Y556120D01*
X461900Y556430D01*
X462245Y556585D01*
X462629D01*
X462859Y556689D01*
X463050Y556947D01*
X463127Y557309D01*
X463012Y557670D01*
X462744Y557929D01*
X462437Y558032D01*
X462130Y557929D01*
X461862Y557670D01*
X461747Y557309D01*
X461824Y556947D01*
X462015Y556689D01*
X462245Y556585D01*
X462629D01*
X462974Y556430D01*
X463204Y556120D01*
X463280Y555759D01*
X463204Y555397D01*
X463012Y555139D01*
X462705Y554984D01*
X462437Y554932D01*
G01X459414D02*
X459337Y555604D01*
X459222Y556172D01*
X459069Y556689D01*
X458877Y557257D01*
X458570Y558032D01*
X460104D01*
G01X467794Y562074D02*
X468024Y562229D01*
X468292Y562332D01*
X468599D01*
X468944Y562177D01*
X469212Y561919D01*
X469404Y561609D01*
X469557Y561092D01*
X469595Y560627D01*
X469519Y560162D01*
X469404Y559852D01*
X469174Y559542D01*
X468905Y559335D01*
X468637Y559232D01*
X468369D01*
X468100Y559335D01*
X467870Y559490D01*
X467679Y559697D01*
G01X465537Y559232D02*
Y562332D01*
X465997Y561712D01*
G01Y559232D02*
X465077D01*
G01X462437D02*
X462169Y559284D01*
X461862Y559439D01*
X461670Y559697D01*
X461594Y560059D01*
X461670Y560420D01*
X461900Y560730D01*
X462245Y560885D01*
X462629D01*
X462859Y560989D01*
X463050Y561247D01*
X463127Y561609D01*
X463012Y561970D01*
X462744Y562229D01*
X462437Y562332D01*
X462130Y562229D01*
X461862Y561970D01*
X461747Y561609D01*
X461824Y561247D01*
X462015Y560989D01*
X462245Y560885D01*
X462629D01*
X462974Y560730D01*
X463204Y560420D01*
X463280Y560059D01*
X463204Y559697D01*
X463012Y559439D01*
X462705Y559284D01*
X462437Y559232D01*
G01X459337D02*
X459069Y559284D01*
X458762Y559439D01*
X458570Y559697D01*
X458494Y560059D01*
X458570Y560420D01*
X458800Y560730D01*
X459145Y560885D01*
X459529D01*
X459759Y560989D01*
X459950Y561247D01*
X460027Y561609D01*
X459912Y561970D01*
X459644Y562229D01*
X459337Y562332D01*
X459030Y562229D01*
X458762Y561970D01*
X458647Y561609D01*
X458724Y561247D01*
X458915Y560989D01*
X459145Y560885D01*
X459529D01*
X459874Y560730D01*
X460104Y560420D01*
X460180Y560059D01*
X460104Y559697D01*
X459912Y559439D01*
X459605Y559284D01*
X459337Y559232D01*
G01X471493Y568425D02*
X471723Y568580D01*
X471991Y568683D01*
X472298D01*
X472643Y568528D01*
X472911Y568270D01*
X473103Y567960D01*
X473256Y567443D01*
X473294Y566978D01*
X473218Y566513D01*
X473103Y566203D01*
X472873Y565893D01*
X472604Y565686D01*
X472336Y565583D01*
X472068D01*
X471799Y565686D01*
X471569Y565841D01*
X471378Y566048D01*
G01X469236Y565583D02*
Y568683D01*
X469696Y568063D01*
G01Y565583D02*
X468776D01*
G01X466136D02*
X465868Y565635D01*
X465561Y565790D01*
X465369Y566048D01*
X465293Y566410D01*
X465369Y566771D01*
X465599Y567081D01*
X465944Y567236D01*
X466328D01*
X466558Y567340D01*
X466749Y567598D01*
X466826Y567960D01*
X466711Y568321D01*
X466443Y568580D01*
X466136Y568683D01*
X465829Y568580D01*
X465561Y568321D01*
X465446Y567960D01*
X465523Y567598D01*
X465714Y567340D01*
X465944Y567236D01*
X466328D01*
X466673Y567081D01*
X466903Y566771D01*
X466979Y566410D01*
X466903Y566048D01*
X466711Y565790D01*
X466404Y565635D01*
X466136Y565583D01*
G01X463879Y566048D02*
X463649Y565790D01*
X463381Y565635D01*
X463036Y565583D01*
X462691Y565686D01*
X462423Y565893D01*
X462231Y566255D01*
X462193Y566668D01*
X462269Y567081D01*
X462461Y567340D01*
X462729Y567546D01*
X462998Y567598D01*
X463266Y567546D01*
X463611Y567340D01*
X463496Y568683D01*
X462461D01*
G01X471493Y572944D02*
X471723Y573099D01*
X471991Y573202D01*
X472298D01*
X472643Y573047D01*
X472911Y572789D01*
X473103Y572479D01*
X473256Y571962D01*
X473294Y571497D01*
X473218Y571032D01*
X473103Y570722D01*
X472873Y570412D01*
X472604Y570205D01*
X472336Y570102D01*
X472068D01*
X471799Y570205D01*
X471569Y570360D01*
X471378Y570567D01*
G01X469236Y570102D02*
Y573202D01*
X469696Y572582D01*
G01Y570102D02*
X468776D01*
G01X466136D02*
X465868Y570154D01*
X465561Y570309D01*
X465369Y570567D01*
X465293Y570929D01*
X465369Y571290D01*
X465599Y571600D01*
X465944Y571755D01*
X466328D01*
X466558Y571859D01*
X466749Y572117D01*
X466826Y572479D01*
X466711Y572840D01*
X466443Y573099D01*
X466136Y573202D01*
X465829Y573099D01*
X465561Y572840D01*
X465446Y572479D01*
X465523Y572117D01*
X465714Y571859D01*
X465944Y571755D01*
X466328D01*
X466673Y571600D01*
X466903Y571290D01*
X466979Y570929D01*
X466903Y570567D01*
X466711Y570309D01*
X466404Y570154D01*
X466136Y570102D01*
G01X463764Y571394D02*
X463496Y571755D01*
X463266Y571962D01*
X462959Y572065D01*
X462691Y571962D01*
X462499Y571755D01*
X462346Y571445D01*
X462308Y571084D01*
X462346Y570774D01*
X462499Y570464D01*
X462729Y570205D01*
X462998Y570102D01*
X463304Y570205D01*
X463573Y570515D01*
X463726Y570980D01*
X463764Y571497D01*
X463688Y572169D01*
X463573Y572530D01*
X463381Y572892D01*
X463113Y573150D01*
X462844Y573202D01*
X462576Y573099D01*
X462384Y572840D01*
G01X457537Y631758D02*
X457767Y631913D01*
X458035Y632016D01*
X458342D01*
X458687Y631861D01*
X458955Y631603D01*
X459147Y631293D01*
X459300Y630776D01*
X459338Y630311D01*
X459262Y629846D01*
X459147Y629536D01*
X458917Y629226D01*
X458648Y629019D01*
X458380Y628916D01*
X458112D01*
X457843Y629019D01*
X457613Y629174D01*
X457422Y629381D01*
G01X456123D02*
X455893Y629123D01*
X455625Y628968D01*
X455280Y628916D01*
X454935Y629019D01*
X454667Y629226D01*
X454475Y629588D01*
X454437Y630001D01*
X454513Y630414D01*
X454705Y630673D01*
X454973Y630879D01*
X455242Y630931D01*
X455510Y630879D01*
X455855Y630673D01*
X455740Y632016D01*
X454705D01*
G01X452832Y629278D02*
X452563Y629019D01*
X452257Y628916D01*
X451950Y629019D01*
X451682Y629329D01*
X451490Y629794D01*
X451413Y630259D01*
Y630828D01*
X451490Y631293D01*
X451682Y631706D01*
X451912Y631913D01*
X452180Y632016D01*
X452487Y631913D01*
X452717Y631706D01*
X452870Y631396D01*
X452947Y630983D01*
X452870Y630621D01*
X452678Y630259D01*
X452448Y630053D01*
X452180Y630001D01*
X451873Y630104D01*
X451643Y630363D01*
X451413Y630828D01*
G01X449080Y632016D02*
X449387Y631913D01*
X449617Y631654D01*
X449770Y631344D01*
X449885Y630931D01*
X449923Y630466D01*
X449885Y630001D01*
X449770Y629588D01*
X449617Y629278D01*
X449387Y629019D01*
X449080Y628916D01*
X448773Y629019D01*
X448543Y629278D01*
X448390Y629588D01*
X448275Y630001D01*
X448237Y630466D01*
X448275Y630931D01*
X448390Y631344D01*
X448543Y631654D01*
X448773Y631913D01*
X449080Y632016D01*
G01X452796Y637286D02*
Y640286D01*
G01X455896Y637186D02*
Y640386D01*
G01X449696Y637186D02*
X455896D01*
G01X449696Y640386D02*
Y637186D01*
G01X455896Y640386D02*
X449696D01*
G01X464000Y638447D02*
X467100D01*
Y639406D01*
X466945Y639712D01*
X466738Y639904D01*
X466325Y639981D01*
X465912Y639904D01*
X465653Y639674D01*
X465498Y639406D01*
Y638447D01*
G01Y639406D02*
X464000Y639981D01*
G01Y642314D02*
X467100D01*
X466480Y641854D01*
G01X464000D02*
Y642774D01*
G01X466583Y644686D02*
X466893Y644916D01*
X467048Y645184D01*
X467100Y645491D01*
X466997Y645874D01*
X466738Y646142D01*
X466428Y646219D01*
X466118Y646181D01*
X465860Y646027D01*
X465343Y645261D01*
X464982Y644916D01*
X464465Y644686D01*
X464000Y644609D01*
Y646219D01*
G01Y648974D02*
X467100D01*
X464878Y647556D01*
Y649472D01*
G01X464465Y650771D02*
X464207Y651001D01*
X464052Y651269D01*
X464000Y651614D01*
X464103Y651959D01*
X464310Y652227D01*
X464672Y652419D01*
X465085Y652457D01*
X465498Y652381D01*
X465757Y652189D01*
X465963Y651921D01*
X466015Y651652D01*
X465963Y651384D01*
X465757Y651039D01*
X467100Y651154D01*
Y652189D01*
G01X459147Y633116D02*
Y636216D01*
X458188D01*
X457882Y636061D01*
X457690Y635854D01*
X457613Y635441D01*
X457690Y635028D01*
X457920Y634769D01*
X458188Y634614D01*
X459147D01*
G01X458188D02*
X457613Y633116D01*
G01X455357D02*
X455280Y633788D01*
X455165Y634356D01*
X455012Y634873D01*
X454820Y635441D01*
X454513Y636216D01*
X456047D01*
G01X452832Y633478D02*
X452563Y633219D01*
X452257Y633116D01*
X451950Y633219D01*
X451682Y633529D01*
X451490Y633994D01*
X451413Y634459D01*
Y635028D01*
X451490Y635493D01*
X451682Y635906D01*
X451912Y636113D01*
X452180Y636216D01*
X452487Y636113D01*
X452717Y635906D01*
X452870Y635596D01*
X452947Y635183D01*
X452870Y634821D01*
X452678Y634459D01*
X452448Y634253D01*
X452180Y634201D01*
X451873Y634304D01*
X451643Y634563D01*
X451413Y635028D01*
G01X449923Y633581D02*
X449693Y633323D01*
X449425Y633168D01*
X449080Y633116D01*
X448735Y633219D01*
X448467Y633426D01*
X448275Y633788D01*
X448237Y634201D01*
X448313Y634614D01*
X448505Y634873D01*
X448773Y635079D01*
X449042Y635131D01*
X449310Y635079D01*
X449655Y634873D01*
X449540Y636216D01*
X448505D01*
G01X449701Y644285D02*
Y641085D01*
G01X455901D02*
Y644285D01*
G01X449701Y641085D02*
X455901D01*
G01X460538Y656723D02*
X457338D01*
G01X460538Y650523D02*
Y656723D01*
G01X457338Y650523D02*
X460538D01*
G01X457338Y656723D02*
Y650523D01*
G01X454758Y655803D02*
Y659003D01*
G01X448558Y655803D02*
X454758D01*
G01X448558Y659003D02*
Y655803D01*
G01X454758Y659003D02*
X448558D01*
G01X455901Y644285D02*
X449701D01*
G01X451635Y652255D02*
Y646055D01*
G01X454835Y652255D02*
X451635D01*
G01X454835Y646055D02*
Y652255D01*
G01X451635Y646055D02*
X454835D01*
G01X450783Y646079D02*
Y652279D01*
G01X477255Y670423D02*
Y673523D01*
X476296D01*
X475990Y673368D01*
X475798Y673161D01*
X475721Y672748D01*
X475798Y672335D01*
X476028Y672076D01*
X476296Y671921D01*
X477255D01*
G01X476296D02*
X475721Y670423D01*
G01X473388D02*
Y673523D01*
X473848Y672903D01*
G01Y670423D02*
X472928D01*
G01X471016Y673006D02*
X470786Y673316D01*
X470518Y673471D01*
X470211Y673523D01*
X469828Y673420D01*
X469560Y673161D01*
X469483Y672851D01*
X469521Y672541D01*
X469675Y672283D01*
X470441Y671766D01*
X470786Y671405D01*
X471016Y670888D01*
X471093Y670423D01*
X469483D01*
G01X466728D02*
Y673523D01*
X468146Y671301D01*
X466230D01*
G01X463628Y670423D02*
Y673523D01*
X465046Y671301D01*
X463130D01*
G01X477455Y666123D02*
Y669223D01*
X476496D01*
X476190Y669068D01*
X475998Y668861D01*
X475921Y668448D01*
X475998Y668035D01*
X476228Y667776D01*
X476496Y667621D01*
X477455D01*
G01X476496D02*
X475921Y666123D01*
G01X473588D02*
Y669223D01*
X474048Y668603D01*
G01Y666123D02*
X473128D01*
G01X471216Y668706D02*
X470986Y669016D01*
X470718Y669171D01*
X470411Y669223D01*
X470028Y669120D01*
X469760Y668861D01*
X469683Y668551D01*
X469721Y668241D01*
X469875Y667983D01*
X470641Y667466D01*
X470986Y667105D01*
X471216Y666588D01*
X471293Y666123D01*
X469683D01*
G01X467388D02*
Y669223D01*
X467848Y668603D01*
G01Y666123D02*
X466928D01*
G01X464288D02*
Y669223D01*
X464748Y668603D01*
G01Y666123D02*
X463828D01*
G01X458440Y684356D02*
X460740Y682056D01*
G01X456140D02*
X458440Y684356D01*
G01X450540Y682056D02*
X456140D01*
G01X450540Y713256D02*
Y682056D01*
G01X453440Y684156D02*
G02I-1000J0D01*
G01X460740Y682056D02*
X466340D01*
G01X486600Y720370D02*
X450200D01*
G01X466340Y713256D02*
X450540D01*
G01X460840Y737556D02*
X464040D01*
G01X460840Y743756D02*
Y737556D01*
G01X452340D02*
X455540D01*
G01X452340Y743756D02*
Y737556D01*
G01X455540D02*
Y743756D01*
G01X452940Y729156D02*
X455940D01*
G01X452840Y726056D02*
X456040D01*
G01X452840Y732256D02*
Y726056D01*
G01X456040Y732256D02*
X452840D01*
G01X456040Y726056D02*
Y732256D01*
G01X460040D02*
X456840D01*
G01X460040Y726056D02*
Y732256D01*
G01X456840Y726056D02*
X460040D01*
G01X456840Y732256D02*
Y726056D01*
G01X464039Y732256D02*
X460841D01*
G01Y726056D02*
X464039D01*
G01X460841Y732256D02*
Y726056D01*
G01X460040Y737556D02*
Y743756D01*
G01X456840Y737556D02*
X460040D01*
G01X456840Y743756D02*
Y737556D01*
G01X451540Y732256D02*
X448340D01*
G01X451540Y726056D02*
Y732256D01*
G01X448340Y726056D02*
X451540D01*
G01X448340Y732256D02*
Y726056D01*
G01X451040Y737556D02*
Y743756D01*
G01X447840Y737556D02*
X451040D01*
G01X447840Y743756D02*
Y737556D01*
G01X460940Y740656D02*
X463940D01*
G01X464040Y743756D02*
X460840D01*
G01X452440Y740656D02*
X455440D01*
G01X455540Y743756D02*
X452340D01*
G01X457704Y746731D02*
X457859Y746501D01*
X457962Y746233D01*
Y745926D01*
X457807Y745581D01*
X457549Y745313D01*
X457239Y745121D01*
X456722Y744968D01*
X456257Y744930D01*
X455792Y745006D01*
X455482Y745121D01*
X455172Y745351D01*
X454965Y745620D01*
X454862Y745888D01*
Y746156D01*
X454965Y746425D01*
X455120Y746655D01*
X455327Y746846D01*
G01X454862Y748911D02*
X455534Y748988D01*
X456102Y749103D01*
X456619Y749256D01*
X457187Y749448D01*
X457962Y749755D01*
Y748221D01*
G01X454862Y752088D02*
X457962D01*
X457342Y751628D01*
G01X454862D02*
Y752548D01*
G01Y755188D02*
X454914Y755456D01*
X455069Y755763D01*
X455327Y755955D01*
X455689Y756031D01*
X456050Y755955D01*
X456360Y755725D01*
X456515Y755380D01*
Y754996D01*
X456619Y754766D01*
X456877Y754575D01*
X457239Y754498D01*
X457600Y754613D01*
X457859Y754881D01*
X457962Y755188D01*
X457859Y755495D01*
X457600Y755763D01*
X457239Y755878D01*
X456877Y755801D01*
X456619Y755610D01*
X456515Y755380D01*
Y754996D01*
X456360Y754651D01*
X456050Y754421D01*
X455689Y754345D01*
X455327Y754421D01*
X455069Y754613D01*
X454914Y754920D01*
X454862Y755188D01*
G01X459309Y745121D02*
X462409D01*
Y746080D01*
X462254Y746386D01*
X462047Y746578D01*
X461634Y746655D01*
X461221Y746578D01*
X460962Y746348D01*
X460807Y746080D01*
Y745121D01*
G01Y746080D02*
X459309Y746655D01*
G01Y748988D02*
X459361Y749256D01*
X459516Y749563D01*
X459774Y749755D01*
X460136Y749831D01*
X460497Y749755D01*
X460807Y749525D01*
X460962Y749180D01*
Y748796D01*
X461066Y748566D01*
X461324Y748375D01*
X461686Y748298D01*
X462047Y748413D01*
X462306Y748681D01*
X462409Y748988D01*
X462306Y749295D01*
X462047Y749563D01*
X461686Y749678D01*
X461324Y749601D01*
X461066Y749410D01*
X460962Y749180D01*
Y748796D01*
X460807Y748451D01*
X460497Y748221D01*
X460136Y748145D01*
X459774Y748221D01*
X459516Y748413D01*
X459361Y748720D01*
X459309Y748988D01*
G01Y752088D02*
X459361Y752356D01*
X459516Y752663D01*
X459774Y752855D01*
X460136Y752931D01*
X460497Y752855D01*
X460807Y752625D01*
X460962Y752280D01*
Y751896D01*
X461066Y751666D01*
X461324Y751475D01*
X461686Y751398D01*
X462047Y751513D01*
X462306Y751781D01*
X462409Y752088D01*
X462306Y752395D01*
X462047Y752663D01*
X461686Y752778D01*
X461324Y752701D01*
X461066Y752510D01*
X460962Y752280D01*
Y751896D01*
X460807Y751551D01*
X460497Y751321D01*
X460136Y751245D01*
X459774Y751321D01*
X459516Y751513D01*
X459361Y751820D01*
X459309Y752088D01*
G01Y755188D02*
X462409D01*
X461789Y754728D01*
G01X459309D02*
Y755648D01*
G01X462888Y745121D02*
X465988D01*
Y746080D01*
X465833Y746386D01*
X465626Y746578D01*
X465213Y746655D01*
X464800Y746578D01*
X464541Y746348D01*
X464386Y746080D01*
Y745121D01*
G01Y746080D02*
X462888Y746655D01*
G01Y748988D02*
X462940Y749256D01*
X463095Y749563D01*
X463353Y749755D01*
X463715Y749831D01*
X464076Y749755D01*
X464386Y749525D01*
X464541Y749180D01*
Y748796D01*
X464645Y748566D01*
X464903Y748375D01*
X465265Y748298D01*
X465626Y748413D01*
X465885Y748681D01*
X465988Y748988D01*
X465885Y749295D01*
X465626Y749563D01*
X465265Y749678D01*
X464903Y749601D01*
X464645Y749410D01*
X464541Y749180D01*
Y748796D01*
X464386Y748451D01*
X464076Y748221D01*
X463715Y748145D01*
X463353Y748221D01*
X463095Y748413D01*
X462940Y748720D01*
X462888Y748988D01*
G01Y752011D02*
X463560Y752088D01*
X464128Y752203D01*
X464645Y752356D01*
X465213Y752548D01*
X465988Y752855D01*
Y751321D01*
G01X462888Y755188D02*
X462940Y755456D01*
X463095Y755763D01*
X463353Y755955D01*
X463715Y756031D01*
X464076Y755955D01*
X464386Y755725D01*
X464541Y755380D01*
Y754996D01*
X464645Y754766D01*
X464903Y754575D01*
X465265Y754498D01*
X465626Y754613D01*
X465885Y754881D01*
X465988Y755188D01*
X465885Y755495D01*
X465626Y755763D01*
X465265Y755878D01*
X464903Y755801D01*
X464645Y755610D01*
X464541Y755380D01*
Y754996D01*
X464386Y754651D01*
X464076Y754421D01*
X463715Y754345D01*
X463353Y754421D01*
X463095Y754613D01*
X462940Y754920D01*
X462888Y755188D01*
G01X460040Y743756D02*
X456840D01*
G01X450401Y745121D02*
X453501D01*
Y746080D01*
X453346Y746386D01*
X453139Y746578D01*
X452726Y746655D01*
X452313Y746578D01*
X452054Y746348D01*
X451899Y746080D01*
Y745121D01*
G01Y746080D02*
X450401Y746655D01*
G01X450763Y748336D02*
X450504Y748605D01*
X450401Y748911D01*
X450504Y749218D01*
X450814Y749486D01*
X451279Y749678D01*
X451744Y749755D01*
X452313D01*
X452778Y749678D01*
X453191Y749486D01*
X453398Y749256D01*
X453501Y748988D01*
X453398Y748681D01*
X453191Y748451D01*
X452881Y748298D01*
X452468Y748221D01*
X452106Y748298D01*
X451744Y748490D01*
X451538Y748720D01*
X451486Y748988D01*
X451589Y749295D01*
X451848Y749525D01*
X452313Y749755D01*
G01X450866Y751245D02*
X450608Y751475D01*
X450453Y751743D01*
X450401Y752088D01*
X450504Y752433D01*
X450711Y752701D01*
X451073Y752893D01*
X451486Y752931D01*
X451899Y752855D01*
X452158Y752663D01*
X452364Y752395D01*
X452416Y752126D01*
X452364Y751858D01*
X452158Y751513D01*
X453501Y751628D01*
Y752663D01*
G01X450401Y755188D02*
X450453Y755456D01*
X450608Y755763D01*
X450866Y755955D01*
X451228Y756031D01*
X451589Y755955D01*
X451899Y755725D01*
X452054Y755380D01*
Y754996D01*
X452158Y754766D01*
X452416Y754575D01*
X452778Y754498D01*
X453139Y754613D01*
X453398Y754881D01*
X453501Y755188D01*
X453398Y755495D01*
X453139Y755763D01*
X452778Y755878D01*
X452416Y755801D01*
X452158Y755610D01*
X452054Y755380D01*
Y754996D01*
X451899Y754651D01*
X451589Y754421D01*
X451228Y754345D01*
X450866Y754421D01*
X450608Y754613D01*
X450453Y754920D01*
X450401Y755188D01*
G01X451040Y743756D02*
X447840D01*
G01X467094Y758713D02*
X467249Y758483D01*
X467352Y758215D01*
Y757908D01*
X467197Y757563D01*
X466939Y757295D01*
X466629Y757103D01*
X466112Y756950D01*
X465647Y756912D01*
X465182Y756988D01*
X464872Y757103D01*
X464562Y757333D01*
X464355Y757602D01*
X464252Y757870D01*
Y758138D01*
X464355Y758407D01*
X464510Y758637D01*
X464717Y758828D01*
G01X465544Y760242D02*
X465905Y760510D01*
X466112Y760740D01*
X466215Y761047D01*
X466112Y761315D01*
X465905Y761507D01*
X465595Y761660D01*
X465234Y761698D01*
X464924Y761660D01*
X464614Y761507D01*
X464355Y761277D01*
X464252Y761008D01*
X464355Y760702D01*
X464665Y760433D01*
X465130Y760280D01*
X465647Y760242D01*
X466319Y760318D01*
X466680Y760433D01*
X467042Y760625D01*
X467300Y760893D01*
X467352Y761162D01*
X467249Y761430D01*
X466990Y761622D01*
G01X464252Y764530D02*
X467352D01*
X465130Y763112D01*
Y765028D01*
G01X464252Y767630D02*
X467352D01*
X465130Y766212D01*
Y768128D01*
G01X458146Y758713D02*
X458301Y758483D01*
X458404Y758215D01*
Y757908D01*
X458249Y757563D01*
X457991Y757295D01*
X457681Y757103D01*
X457164Y756950D01*
X456699Y756912D01*
X456234Y756988D01*
X455924Y757103D01*
X455614Y757333D01*
X455407Y757602D01*
X455304Y757870D01*
Y758138D01*
X455407Y758407D01*
X455562Y758637D01*
X455769Y758828D01*
G01X455304Y760893D02*
X455976Y760970D01*
X456544Y761085D01*
X457061Y761238D01*
X457629Y761430D01*
X458404Y761737D01*
Y760203D01*
G01X457887Y763342D02*
X458197Y763572D01*
X458352Y763840D01*
X458404Y764147D01*
X458301Y764530D01*
X458042Y764798D01*
X457732Y764875D01*
X457422Y764837D01*
X457164Y764683D01*
X456647Y763917D01*
X456286Y763572D01*
X455769Y763342D01*
X455304Y763265D01*
Y764875D01*
G01Y767170D02*
X458404D01*
X457784Y766710D01*
G01X455304D02*
Y767630D01*
G01X459765Y757103D02*
X462865D01*
Y758062D01*
X462710Y758368D01*
X462503Y758560D01*
X462090Y758637D01*
X461677Y758560D01*
X461418Y758330D01*
X461263Y758062D01*
Y757103D01*
G01Y758062D02*
X459765Y758637D01*
G01X460127Y760318D02*
X459868Y760587D01*
X459765Y760893D01*
X459868Y761200D01*
X460178Y761468D01*
X460643Y761660D01*
X461108Y761737D01*
X461677D01*
X462142Y761660D01*
X462555Y761468D01*
X462762Y761238D01*
X462865Y760970D01*
X462762Y760663D01*
X462555Y760433D01*
X462245Y760280D01*
X461832Y760203D01*
X461470Y760280D01*
X461108Y760472D01*
X460902Y760702D01*
X460850Y760970D01*
X460953Y761277D01*
X461212Y761507D01*
X461677Y761737D01*
G01X460230Y763227D02*
X459972Y763457D01*
X459817Y763725D01*
X459765Y764070D01*
X459868Y764415D01*
X460075Y764683D01*
X460437Y764875D01*
X460850Y764913D01*
X461263Y764837D01*
X461522Y764645D01*
X461728Y764377D01*
X461780Y764108D01*
X461728Y763840D01*
X461522Y763495D01*
X462865Y763610D01*
Y764645D01*
G01X460230Y766327D02*
X459972Y766557D01*
X459817Y766825D01*
X459765Y767170D01*
X459868Y767515D01*
X460075Y767783D01*
X460437Y767975D01*
X460850Y768013D01*
X461263Y767937D01*
X461522Y767745D01*
X461728Y767477D01*
X461780Y767208D01*
X461728Y766940D01*
X461522Y766595D01*
X462865Y766710D01*
Y767745D01*
G01X451028Y757103D02*
X454128D01*
Y758062D01*
X453973Y758368D01*
X453766Y758560D01*
X453353Y758637D01*
X452940Y758560D01*
X452681Y758330D01*
X452526Y758062D01*
Y757103D01*
G01Y758062D02*
X451028Y758637D01*
G01X451390Y760318D02*
X451131Y760587D01*
X451028Y760893D01*
X451131Y761200D01*
X451441Y761468D01*
X451906Y761660D01*
X452371Y761737D01*
X452940D01*
X453405Y761660D01*
X453818Y761468D01*
X454025Y761238D01*
X454128Y760970D01*
X454025Y760663D01*
X453818Y760433D01*
X453508Y760280D01*
X453095Y760203D01*
X452733Y760280D01*
X452371Y760472D01*
X452165Y760702D01*
X452113Y760970D01*
X452216Y761277D01*
X452475Y761507D01*
X452940Y761737D01*
G01X452320Y763342D02*
X452681Y763610D01*
X452888Y763840D01*
X452991Y764147D01*
X452888Y764415D01*
X452681Y764607D01*
X452371Y764760D01*
X452010Y764798D01*
X451700Y764760D01*
X451390Y764607D01*
X451131Y764377D01*
X451028Y764108D01*
X451131Y763802D01*
X451441Y763533D01*
X451906Y763380D01*
X452423Y763342D01*
X453095Y763418D01*
X453456Y763533D01*
X453818Y763725D01*
X454076Y763993D01*
X454128Y764262D01*
X454025Y764530D01*
X453766Y764722D01*
G01X451028Y767170D02*
X454128D01*
X453508Y766710D01*
G01X451028D02*
Y767630D01*
G01X473793Y-244364D02*
Y-236364D01*
X475793D01*
X476593Y-236764D01*
X477193Y-237297D01*
X477693Y-238097D01*
X478093Y-239031D01*
X478193Y-240364D01*
X478093Y-241697D01*
X477693Y-242631D01*
X477193Y-243431D01*
X476593Y-243964D01*
X475793Y-244364D01*
X473793D01*
G01X490195Y135791D02*
X475195D01*
G01D02*
Y128991D01*
G01D02*
X490195D01*
G01X476115Y137764D02*
X482315D01*
G01X476115Y140964D02*
Y137764D01*
G01X470600Y138400D02*
Y144600D01*
X467400D01*
Y138400D01*
X470600D01*
G01X476115Y141764D02*
X482315D01*
G01Y144964D02*
X476115D01*
G01D02*
Y141764D01*
G01Y145764D02*
X482315D01*
G01Y148964D02*
X476115D01*
G01D02*
Y145764D01*
G01X482315Y152964D02*
X476115D01*
G01Y149764D02*
X482315D01*
G01X476115Y152964D02*
Y149764D01*
G01X482315Y140964D02*
X476115D01*
G01X477600Y170513D02*
X483800D01*
G01X477600Y173713D02*
Y170513D01*
G01Y162514D02*
X483800D01*
G01Y165712D02*
X477600D01*
G01D02*
Y162514D01*
G01Y166513D02*
X483800D01*
G01Y169713D02*
X477600D01*
G01D02*
Y166513D01*
G01X483800Y173713D02*
X477600D01*
G01X472268Y181940D02*
Y185040D01*
X471309D01*
X471003Y184885D01*
X470811Y184678D01*
X470734Y184265D01*
X470811Y183852D01*
X471041Y183593D01*
X471309Y183438D01*
X472268D01*
G01X471309D02*
X470734Y181940D01*
G01X469053Y182302D02*
X468784Y182043D01*
X468478Y181940D01*
X468171Y182043D01*
X467903Y182353D01*
X467711Y182818D01*
X467634Y183283D01*
Y183852D01*
X467711Y184317D01*
X467903Y184730D01*
X468133Y184937D01*
X468401Y185040D01*
X468708Y184937D01*
X468938Y184730D01*
X469091Y184420D01*
X469168Y184007D01*
X469091Y183645D01*
X468899Y183283D01*
X468669Y183077D01*
X468401Y183025D01*
X468094Y183128D01*
X467864Y183387D01*
X467634Y183852D01*
G01X466144Y182405D02*
X465914Y182147D01*
X465646Y181992D01*
X465301Y181940D01*
X464956Y182043D01*
X464688Y182250D01*
X464496Y182612D01*
X464458Y183025D01*
X464534Y183438D01*
X464726Y183697D01*
X464994Y183903D01*
X465263Y183955D01*
X465531Y183903D01*
X465876Y183697D01*
X465761Y185040D01*
X464726D01*
G01X473860Y178783D02*
X480060D01*
G01X473860Y181983D02*
Y178783D01*
G01X480060Y181983D02*
X473860D01*
G01X477600Y174513D02*
X483800D01*
G01X477600Y177713D02*
Y174513D01*
G01X483800Y177713D02*
X477600D01*
G01X476000Y215883D02*
X479100D01*
Y216842D01*
X478945Y217148D01*
X478738Y217340D01*
X478325Y217417D01*
X477912Y217340D01*
X477653Y217110D01*
X477498Y216842D01*
Y215883D01*
G01Y216842D02*
X476000Y217417D01*
G01Y219750D02*
X479100D01*
X478480Y219290D01*
G01X476000D02*
Y220210D01*
G01X478583Y222122D02*
X478893Y222352D01*
X479048Y222620D01*
X479100Y222927D01*
X478997Y223310D01*
X478738Y223578D01*
X478428Y223655D01*
X478118Y223617D01*
X477860Y223463D01*
X477343Y222697D01*
X476982Y222352D01*
X476465Y222122D01*
X476000Y222045D01*
Y223655D01*
G01Y225950D02*
X476052Y226218D01*
X476207Y226525D01*
X476465Y226717D01*
X476827Y226793D01*
X477188Y226717D01*
X477498Y226487D01*
X477653Y226142D01*
Y225758D01*
X477757Y225528D01*
X478015Y225337D01*
X478377Y225260D01*
X478738Y225375D01*
X478997Y225643D01*
X479100Y225950D01*
X478997Y226257D01*
X478738Y226525D01*
X478377Y226640D01*
X478015Y226563D01*
X477757Y226372D01*
X477653Y226142D01*
Y225758D01*
X477498Y225413D01*
X477188Y225183D01*
X476827Y225107D01*
X476465Y225183D01*
X476207Y225375D01*
X476052Y225682D01*
X476000Y225950D01*
G01Y229050D02*
X476052Y229318D01*
X476207Y229625D01*
X476465Y229817D01*
X476827Y229893D01*
X477188Y229817D01*
X477498Y229587D01*
X477653Y229242D01*
Y228858D01*
X477757Y228628D01*
X478015Y228437D01*
X478377Y228360D01*
X478738Y228475D01*
X478997Y228743D01*
X479100Y229050D01*
X478997Y229357D01*
X478738Y229625D01*
X478377Y229740D01*
X478015Y229663D01*
X477757Y229472D01*
X477653Y229242D01*
Y228858D01*
X477498Y228513D01*
X477188Y228283D01*
X476827Y228207D01*
X476465Y228283D01*
X476207Y228475D01*
X476052Y228782D01*
X476000Y229050D01*
G01X476400Y211600D02*
Y205400D01*
X479600D01*
Y211600D01*
X476400D01*
G01X468993Y476723D02*
Y494123D01*
G01X477960Y558148D02*
Y555148D01*
G01X474860Y558248D02*
Y555048D01*
G01X481060Y558248D02*
X474860D01*
G01Y555048D02*
X481060D01*
G01X477960Y562148D02*
Y559148D01*
G01X474860Y562248D02*
Y559048D01*
G01X481060Y562248D02*
X474860D01*
G01Y559048D02*
X481060D01*
G01X477960Y568194D02*
Y565194D01*
G01X474860Y568293D02*
Y565095D01*
G01D02*
X481060D01*
G01X480808Y582313D02*
X481038Y582468D01*
X481306Y582571D01*
X481613D01*
X481958Y582416D01*
X482226Y582158D01*
X482418Y581848D01*
X482571Y581331D01*
X482609Y580866D01*
X482533Y580401D01*
X482418Y580091D01*
X482188Y579781D01*
X481919Y579574D01*
X481651Y579471D01*
X481383D01*
X481114Y579574D01*
X480884Y579729D01*
X480693Y579936D01*
G01X478551Y579471D02*
X478283Y579523D01*
X477976Y579678D01*
X477784Y579936D01*
X477708Y580298D01*
X477784Y580659D01*
X478014Y580969D01*
X478359Y581124D01*
X478743D01*
X478973Y581228D01*
X479164Y581486D01*
X479241Y581848D01*
X479126Y582209D01*
X478858Y582468D01*
X478551Y582571D01*
X478244Y582468D01*
X477976Y582209D01*
X477861Y581848D01*
X477938Y581486D01*
X478129Y581228D01*
X478359Y581124D01*
X478743D01*
X479088Y580969D01*
X479318Y580659D01*
X479394Y580298D01*
X479318Y579936D01*
X479126Y579678D01*
X478819Y579523D01*
X478551Y579471D01*
G01X476103Y579833D02*
X475834Y579574D01*
X475528Y579471D01*
X475221Y579574D01*
X474953Y579884D01*
X474761Y580349D01*
X474684Y580814D01*
Y581383D01*
X474761Y581848D01*
X474953Y582261D01*
X475183Y582468D01*
X475451Y582571D01*
X475758Y582468D01*
X475988Y582261D01*
X476141Y581951D01*
X476218Y581538D01*
X476141Y581176D01*
X475949Y580814D01*
X475719Y580608D01*
X475451Y580556D01*
X475144Y580659D01*
X474914Y580918D01*
X474684Y581383D01*
G01X473079Y580763D02*
X472811Y581124D01*
X472581Y581331D01*
X472274Y581434D01*
X472006Y581331D01*
X471814Y581124D01*
X471661Y580814D01*
X471623Y580453D01*
X471661Y580143D01*
X471814Y579833D01*
X472044Y579574D01*
X472313Y579471D01*
X472619Y579574D01*
X472888Y579884D01*
X473041Y580349D01*
X473079Y580866D01*
X473003Y581538D01*
X472888Y581899D01*
X472696Y582261D01*
X472428Y582519D01*
X472159Y582571D01*
X471891Y582468D01*
X471699Y582209D01*
G01X480808Y578233D02*
X481038Y578388D01*
X481306Y578491D01*
X481613D01*
X481958Y578336D01*
X482226Y578078D01*
X482418Y577768D01*
X482571Y577251D01*
X482609Y576786D01*
X482533Y576321D01*
X482418Y576011D01*
X482188Y575701D01*
X481919Y575494D01*
X481651Y575391D01*
X481383D01*
X481114Y575494D01*
X480884Y575649D01*
X480693Y575856D01*
G01X478551Y575391D02*
X478283Y575443D01*
X477976Y575598D01*
X477784Y575856D01*
X477708Y576218D01*
X477784Y576579D01*
X478014Y576889D01*
X478359Y577044D01*
X478743D01*
X478973Y577148D01*
X479164Y577406D01*
X479241Y577768D01*
X479126Y578129D01*
X478858Y578388D01*
X478551Y578491D01*
X478244Y578388D01*
X477976Y578129D01*
X477861Y577768D01*
X477938Y577406D01*
X478129Y577148D01*
X478359Y577044D01*
X478743D01*
X479088Y576889D01*
X479318Y576579D01*
X479394Y576218D01*
X479318Y575856D01*
X479126Y575598D01*
X478819Y575443D01*
X478551Y575391D01*
G01X476103Y575753D02*
X475834Y575494D01*
X475528Y575391D01*
X475221Y575494D01*
X474953Y575804D01*
X474761Y576269D01*
X474684Y576734D01*
Y577303D01*
X474761Y577768D01*
X474953Y578181D01*
X475183Y578388D01*
X475451Y578491D01*
X475758Y578388D01*
X475988Y578181D01*
X476141Y577871D01*
X476218Y577458D01*
X476141Y577096D01*
X475949Y576734D01*
X475719Y576528D01*
X475451Y576476D01*
X475144Y576579D01*
X474914Y576838D01*
X474684Y577303D01*
G01X471891Y575391D02*
Y578491D01*
X473309Y576269D01*
X471393D01*
G01X481060Y568293D02*
X474860D01*
G01X477960Y572194D02*
Y569194D01*
G01X474860Y572293D02*
Y569095D01*
G01X481060Y572293D02*
X474860D01*
G01Y569095D02*
X481060D01*
G01X480808Y586173D02*
X481038Y586328D01*
X481306Y586431D01*
X481613D01*
X481958Y586276D01*
X482226Y586018D01*
X482418Y585708D01*
X482571Y585191D01*
X482609Y584726D01*
X482533Y584261D01*
X482418Y583951D01*
X482188Y583641D01*
X481919Y583434D01*
X481651Y583331D01*
X481383D01*
X481114Y583434D01*
X480884Y583589D01*
X480693Y583796D01*
G01X478551Y583331D02*
X478283Y583383D01*
X477976Y583538D01*
X477784Y583796D01*
X477708Y584158D01*
X477784Y584519D01*
X478014Y584829D01*
X478359Y584984D01*
X478743D01*
X478973Y585088D01*
X479164Y585346D01*
X479241Y585708D01*
X479126Y586069D01*
X478858Y586328D01*
X478551Y586431D01*
X478244Y586328D01*
X477976Y586069D01*
X477861Y585708D01*
X477938Y585346D01*
X478129Y585088D01*
X478359Y584984D01*
X478743D01*
X479088Y584829D01*
X479318Y584519D01*
X479394Y584158D01*
X479318Y583796D01*
X479126Y583538D01*
X478819Y583383D01*
X478551Y583331D01*
G01X475451D02*
X475183Y583383D01*
X474876Y583538D01*
X474684Y583796D01*
X474608Y584158D01*
X474684Y584519D01*
X474914Y584829D01*
X475259Y584984D01*
X475643D01*
X475873Y585088D01*
X476064Y585346D01*
X476141Y585708D01*
X476026Y586069D01*
X475758Y586328D01*
X475451Y586431D01*
X475144Y586328D01*
X474876Y586069D01*
X474761Y585708D01*
X474838Y585346D01*
X475029Y585088D01*
X475259Y584984D01*
X475643D01*
X475988Y584829D01*
X476218Y584519D01*
X476294Y584158D01*
X476218Y583796D01*
X476026Y583538D01*
X475719Y583383D01*
X475451Y583331D01*
G01X472351Y586431D02*
X472658Y586328D01*
X472888Y586069D01*
X473041Y585759D01*
X473156Y585346D01*
X473194Y584881D01*
X473156Y584416D01*
X473041Y584003D01*
X472888Y583693D01*
X472658Y583434D01*
X472351Y583331D01*
X472044Y583434D01*
X471814Y583693D01*
X471661Y584003D01*
X471546Y584416D01*
X471508Y584881D01*
X471546Y585346D01*
X471661Y585759D01*
X471814Y586069D01*
X472044Y586328D01*
X472351Y586431D01*
G01X481824Y598580D02*
X482054Y598735D01*
X482322Y598838D01*
X482629D01*
X482974Y598683D01*
X483242Y598425D01*
X483434Y598115D01*
X483587Y597598D01*
X483625Y597133D01*
X483549Y596668D01*
X483434Y596358D01*
X483204Y596048D01*
X482935Y595841D01*
X482667Y595738D01*
X482399D01*
X482130Y595841D01*
X481900Y595996D01*
X481709Y596203D01*
G01X479567Y595738D02*
X479299Y595790D01*
X478992Y595945D01*
X478800Y596203D01*
X478724Y596565D01*
X478800Y596926D01*
X479030Y597236D01*
X479375Y597391D01*
X479759D01*
X479989Y597495D01*
X480180Y597753D01*
X480257Y598115D01*
X480142Y598476D01*
X479874Y598735D01*
X479567Y598838D01*
X479260Y598735D01*
X478992Y598476D01*
X478877Y598115D01*
X478954Y597753D01*
X479145Y597495D01*
X479375Y597391D01*
X479759D01*
X480104Y597236D01*
X480334Y596926D01*
X480410Y596565D01*
X480334Y596203D01*
X480142Y595945D01*
X479835Y595790D01*
X479567Y595738D01*
G01X477195Y597030D02*
X476927Y597391D01*
X476697Y597598D01*
X476390Y597701D01*
X476122Y597598D01*
X475930Y597391D01*
X475777Y597081D01*
X475739Y596720D01*
X475777Y596410D01*
X475930Y596100D01*
X476160Y595841D01*
X476429Y595738D01*
X476735Y595841D01*
X477004Y596151D01*
X477157Y596616D01*
X477195Y597133D01*
X477119Y597805D01*
X477004Y598166D01*
X476812Y598528D01*
X476544Y598786D01*
X476275Y598838D01*
X476007Y598735D01*
X475815Y598476D01*
G01X474095Y598321D02*
X473865Y598631D01*
X473597Y598786D01*
X473290Y598838D01*
X472907Y598735D01*
X472639Y598476D01*
X472562Y598166D01*
X472600Y597856D01*
X472754Y597598D01*
X473520Y597081D01*
X473865Y596720D01*
X474095Y596203D01*
X474172Y595738D01*
X472562D01*
G01X480808Y590183D02*
X481038Y590338D01*
X481306Y590441D01*
X481613D01*
X481958Y590286D01*
X482226Y590028D01*
X482418Y589718D01*
X482571Y589201D01*
X482609Y588736D01*
X482533Y588271D01*
X482418Y587961D01*
X482188Y587651D01*
X481919Y587444D01*
X481651Y587341D01*
X481383D01*
X481114Y587444D01*
X480884Y587599D01*
X480693Y587806D01*
G01X478551Y587341D02*
X478283Y587393D01*
X477976Y587548D01*
X477784Y587806D01*
X477708Y588168D01*
X477784Y588529D01*
X478014Y588839D01*
X478359Y588994D01*
X478743D01*
X478973Y589098D01*
X479164Y589356D01*
X479241Y589718D01*
X479126Y590079D01*
X478858Y590338D01*
X478551Y590441D01*
X478244Y590338D01*
X477976Y590079D01*
X477861Y589718D01*
X477938Y589356D01*
X478129Y589098D01*
X478359Y588994D01*
X478743D01*
X479088Y588839D01*
X479318Y588529D01*
X479394Y588168D01*
X479318Y587806D01*
X479126Y587548D01*
X478819Y587393D01*
X478551Y587341D01*
G01X475451D02*
X475183Y587393D01*
X474876Y587548D01*
X474684Y587806D01*
X474608Y588168D01*
X474684Y588529D01*
X474914Y588839D01*
X475259Y588994D01*
X475643D01*
X475873Y589098D01*
X476064Y589356D01*
X476141Y589718D01*
X476026Y590079D01*
X475758Y590338D01*
X475451Y590441D01*
X475144Y590338D01*
X474876Y590079D01*
X474761Y589718D01*
X474838Y589356D01*
X475029Y589098D01*
X475259Y588994D01*
X475643D01*
X475988Y588839D01*
X476218Y588529D01*
X476294Y588168D01*
X476218Y587806D01*
X476026Y587548D01*
X475719Y587393D01*
X475451Y587341D01*
G01X473079Y589924D02*
X472849Y590234D01*
X472581Y590389D01*
X472274Y590441D01*
X471891Y590338D01*
X471623Y590079D01*
X471546Y589769D01*
X471584Y589459D01*
X471738Y589201D01*
X472504Y588684D01*
X472849Y588323D01*
X473079Y587806D01*
X473156Y587341D01*
X471546D01*
G01X472298Y648123D02*
X475498D01*
G01X472298Y654323D02*
Y648123D01*
G01X475498Y654323D02*
X472298D01*
G01X475498Y648123D02*
Y654323D01*
G01X477891Y655113D02*
Y658313D01*
G01X471691Y655113D02*
X477891D01*
G01X471691Y658313D02*
Y655113D01*
G01X477891Y658313D02*
X471691D01*
G01X471838Y665223D02*
Y662023D01*
G01X478038Y665223D02*
X471838D01*
G01X478038Y662023D02*
Y665223D01*
G01X471838Y662023D02*
X478038D01*
G01X468440Y676230D02*
X467490D01*
G01X477870D02*
X472600D01*
G01X466340Y682056D02*
Y713256D01*
G01X478913Y716580D02*
X478660Y716830D01*
X478470Y717246D01*
X478343Y717830D01*
X478470Y718330D01*
X478723Y718663D01*
X479167Y718913D01*
X480877D01*
Y713913D01*
X478787D01*
X478343Y714246D01*
X478090Y714746D01*
X477963Y715330D01*
X478090Y715913D01*
X478470Y716413D01*
X478913Y716580D01*
X480877D01*
G01X464841Y737556D02*
X468039D01*
G01X464841Y743756D02*
Y737556D01*
G01X468039D02*
Y743756D01*
G01X468840Y737556D02*
X472040D01*
G01X468840Y743756D02*
Y737556D01*
G01X472040D02*
Y743756D01*
G01X464040Y737556D02*
Y743756D01*
G01X472040Y732256D02*
X468840D01*
G01Y726056D02*
X472040D01*
G01X468840Y732256D02*
Y726056D01*
G01X472040D02*
Y732256D01*
G01X464039Y726056D02*
Y732256D01*
G01X468040D02*
X464840D01*
G01X468040Y726056D02*
Y732256D01*
G01X464840Y726056D02*
X468040D01*
G01X464840Y732256D02*
Y726056D01*
G01X464940Y740656D02*
X467940D01*
G01X468039Y743756D02*
X464841D01*
G01X468940Y740656D02*
X471940D01*
G01X472040Y743756D02*
X468840D01*
G01X470100Y745121D02*
X473200D01*
Y746080D01*
X473045Y746386D01*
X472838Y746578D01*
X472425Y746655D01*
X472012Y746578D01*
X471753Y746348D01*
X471598Y746080D01*
Y745121D01*
G01Y746080D02*
X470100Y746655D01*
G01Y748988D02*
X470152Y749256D01*
X470307Y749563D01*
X470565Y749755D01*
X470927Y749831D01*
X471288Y749755D01*
X471598Y749525D01*
X471753Y749180D01*
Y748796D01*
X471857Y748566D01*
X472115Y748375D01*
X472477Y748298D01*
X472838Y748413D01*
X473097Y748681D01*
X473200Y748988D01*
X473097Y749295D01*
X472838Y749563D01*
X472477Y749678D01*
X472115Y749601D01*
X471857Y749410D01*
X471753Y749180D01*
Y748796D01*
X471598Y748451D01*
X471288Y748221D01*
X470927Y748145D01*
X470565Y748221D01*
X470307Y748413D01*
X470152Y748720D01*
X470100Y748988D01*
G01Y752011D02*
X470772Y752088D01*
X471340Y752203D01*
X471857Y752356D01*
X472425Y752548D01*
X473200Y752855D01*
Y751321D01*
G01X472683Y754460D02*
X472993Y754690D01*
X473148Y754958D01*
X473200Y755265D01*
X473097Y755648D01*
X472838Y755916D01*
X472528Y755993D01*
X472218Y755955D01*
X471960Y755801D01*
X471443Y755035D01*
X471082Y754690D01*
X470565Y754460D01*
X470100Y754383D01*
Y755993D01*
G01X466556Y745121D02*
X469656D01*
Y746080D01*
X469501Y746386D01*
X469294Y746578D01*
X468881Y746655D01*
X468468Y746578D01*
X468209Y746348D01*
X468054Y746080D01*
Y745121D01*
G01Y746080D02*
X466556Y746655D01*
G01Y748988D02*
X466608Y749256D01*
X466763Y749563D01*
X467021Y749755D01*
X467383Y749831D01*
X467744Y749755D01*
X468054Y749525D01*
X468209Y749180D01*
Y748796D01*
X468313Y748566D01*
X468571Y748375D01*
X468933Y748298D01*
X469294Y748413D01*
X469553Y748681D01*
X469656Y748988D01*
X469553Y749295D01*
X469294Y749563D01*
X468933Y749678D01*
X468571Y749601D01*
X468313Y749410D01*
X468209Y749180D01*
Y748796D01*
X468054Y748451D01*
X467744Y748221D01*
X467383Y748145D01*
X467021Y748221D01*
X466763Y748413D01*
X466608Y748720D01*
X466556Y748988D01*
G01Y752011D02*
X467228Y752088D01*
X467796Y752203D01*
X468313Y752356D01*
X468881Y752548D01*
X469656Y752855D01*
Y751321D01*
G01X467021Y754345D02*
X466763Y754575D01*
X466608Y754843D01*
X466556Y755188D01*
X466659Y755533D01*
X466866Y755801D01*
X467228Y755993D01*
X467641Y756031D01*
X468054Y755955D01*
X468313Y755763D01*
X468519Y755495D01*
X468571Y755226D01*
X468519Y754958D01*
X468313Y754613D01*
X469656Y754728D01*
Y755763D01*
G01X470673Y758713D02*
X470828Y758483D01*
X470931Y758215D01*
Y757908D01*
X470776Y757563D01*
X470518Y757295D01*
X470208Y757103D01*
X469691Y756950D01*
X469226Y756912D01*
X468761Y756988D01*
X468451Y757103D01*
X468141Y757333D01*
X467934Y757602D01*
X467831Y757870D01*
Y758138D01*
X467934Y758407D01*
X468089Y758637D01*
X468296Y758828D01*
G01X469123Y760242D02*
X469484Y760510D01*
X469691Y760740D01*
X469794Y761047D01*
X469691Y761315D01*
X469484Y761507D01*
X469174Y761660D01*
X468813Y761698D01*
X468503Y761660D01*
X468193Y761507D01*
X467934Y761277D01*
X467831Y761008D01*
X467934Y760702D01*
X468244Y760433D01*
X468709Y760280D01*
X469226Y760242D01*
X469898Y760318D01*
X470259Y760433D01*
X470621Y760625D01*
X470879Y760893D01*
X470931Y761162D01*
X470828Y761430D01*
X470569Y761622D01*
G01X467831Y764530D02*
X470931D01*
X468709Y763112D01*
Y765028D01*
G01X467831Y767170D02*
X470931D01*
X470311Y766710D01*
G01X467831D02*
Y767630D01*
G01X474341Y758713D02*
X474496Y758483D01*
X474599Y758215D01*
Y757908D01*
X474444Y757563D01*
X474186Y757295D01*
X473876Y757103D01*
X473359Y756950D01*
X472894Y756912D01*
X472429Y756988D01*
X472119Y757103D01*
X471809Y757333D01*
X471602Y757602D01*
X471499Y757870D01*
Y758138D01*
X471602Y758407D01*
X471757Y758637D01*
X471964Y758828D01*
G01X472791Y760242D02*
X473152Y760510D01*
X473359Y760740D01*
X473462Y761047D01*
X473359Y761315D01*
X473152Y761507D01*
X472842Y761660D01*
X472481Y761698D01*
X472171Y761660D01*
X471861Y761507D01*
X471602Y761277D01*
X471499Y761008D01*
X471602Y760702D01*
X471912Y760433D01*
X472377Y760280D01*
X472894Y760242D01*
X473566Y760318D01*
X473927Y760433D01*
X474289Y760625D01*
X474547Y760893D01*
X474599Y761162D01*
X474496Y761430D01*
X474237Y761622D01*
G01X472119Y763227D02*
X471757Y763457D01*
X471551Y763763D01*
X471499Y764108D01*
X471551Y764415D01*
X471809Y764722D01*
X472119Y764913D01*
X472429Y764952D01*
X472791Y764875D01*
X473049Y764607D01*
X473152Y764338D01*
Y763993D01*
G01Y764338D02*
X473307Y764568D01*
X473566Y764760D01*
X473876Y764837D01*
X474186Y764760D01*
X474444Y764568D01*
X474599Y764223D01*
X474547Y763878D01*
X474341Y763533D01*
G01X471499Y767170D02*
X471551Y767438D01*
X471706Y767745D01*
X471964Y767937D01*
X472326Y768013D01*
X472687Y767937D01*
X472997Y767707D01*
X473152Y767362D01*
Y766978D01*
X473256Y766748D01*
X473514Y766557D01*
X473876Y766480D01*
X474237Y766595D01*
X474496Y766863D01*
X474599Y767170D01*
X474496Y767477D01*
X474237Y767745D01*
X473876Y767860D01*
X473514Y767783D01*
X473256Y767592D01*
X473152Y767362D01*
Y766978D01*
X472997Y766633D01*
X472687Y766403D01*
X472326Y766327D01*
X471964Y766403D01*
X471706Y766595D01*
X471551Y766902D01*
X471499Y767170D01*
G01X507967Y119563D02*
Y122663D01*
X507008D01*
X506702Y122508D01*
X506510Y122301D01*
X506433Y121888D01*
X506510Y121475D01*
X506740Y121216D01*
X507008Y121061D01*
X507967D01*
G01X507008D02*
X506433Y119563D01*
G01X504100D02*
Y122663D01*
X504560Y122043D01*
G01Y119563D02*
X503640D01*
G01X501728Y122146D02*
X501498Y122456D01*
X501230Y122611D01*
X500923Y122663D01*
X500540Y122560D01*
X500272Y122301D01*
X500195Y121991D01*
X500233Y121681D01*
X500387Y121423D01*
X501153Y120906D01*
X501498Y120545D01*
X501728Y120028D01*
X501805Y119563D01*
X500195D01*
G01X497900Y122663D02*
X498207Y122560D01*
X498437Y122301D01*
X498590Y121991D01*
X498705Y121578D01*
X498743Y121113D01*
X498705Y120648D01*
X498590Y120235D01*
X498437Y119925D01*
X498207Y119666D01*
X497900Y119563D01*
X497593Y119666D01*
X497363Y119925D01*
X497210Y120235D01*
X497095Y120648D01*
X497057Y121113D01*
X497095Y121578D01*
X497210Y121991D01*
X497363Y122301D01*
X497593Y122560D01*
X497900Y122663D01*
G01X494877Y119563D02*
X494800Y120235D01*
X494685Y120803D01*
X494532Y121320D01*
X494340Y121888D01*
X494033Y122663D01*
X495567D01*
G01X508043Y115496D02*
Y118596D01*
X507084D01*
X506778Y118441D01*
X506586Y118234D01*
X506509Y117821D01*
X506586Y117408D01*
X506816Y117149D01*
X507084Y116994D01*
X508043D01*
G01X507084D02*
X506509Y115496D01*
G01X504176D02*
Y118596D01*
X504636Y117976D01*
G01Y115496D02*
X503716D01*
G01X501804Y118079D02*
X501574Y118389D01*
X501306Y118544D01*
X500999Y118596D01*
X500616Y118493D01*
X500348Y118234D01*
X500271Y117924D01*
X500309Y117614D01*
X500463Y117356D01*
X501229Y116839D01*
X501574Y116478D01*
X501804Y115961D01*
X501881Y115496D01*
X500271D01*
G01X497976D02*
Y118596D01*
X498436Y117976D01*
G01Y115496D02*
X497516D01*
G01X494876Y118596D02*
X495183Y118493D01*
X495413Y118234D01*
X495566Y117924D01*
X495681Y117511D01*
X495719Y117046D01*
X495681Y116581D01*
X495566Y116168D01*
X495413Y115858D01*
X495183Y115599D01*
X494876Y115496D01*
X494569Y115599D01*
X494339Y115858D01*
X494186Y116168D01*
X494071Y116581D01*
X494033Y117046D01*
X494071Y117511D01*
X494186Y117924D01*
X494339Y118234D01*
X494569Y118493D01*
X494876Y118596D01*
G01X480601Y124802D02*
X486801D01*
G01D02*
Y128002D01*
G01D02*
X480601D01*
G01D02*
Y124802D01*
G01X483701Y127902D02*
Y124902D01*
G01X490195Y128991D02*
Y135791D01*
G01X482695Y135691D02*
Y129091D01*
G01X482315Y137764D02*
Y140964D01*
G01X502912Y131491D02*
Y134591D01*
X501953D01*
X501647Y134436D01*
X501455Y134229D01*
X501378Y133816D01*
X501455Y133403D01*
X501685Y133144D01*
X501953Y132989D01*
X502912D01*
G01X501953D02*
X501378Y131491D01*
G01X499773Y132783D02*
X499505Y133144D01*
X499275Y133351D01*
X498968Y133454D01*
X498700Y133351D01*
X498508Y133144D01*
X498355Y132834D01*
X498317Y132473D01*
X498355Y132163D01*
X498508Y131853D01*
X498738Y131594D01*
X499007Y131491D01*
X499313Y131594D01*
X499582Y131904D01*
X499735Y132369D01*
X499773Y132886D01*
X499697Y133558D01*
X499582Y133919D01*
X499390Y134281D01*
X499122Y134539D01*
X498853Y134591D01*
X498585Y134488D01*
X498393Y134229D01*
G01X496673Y134074D02*
X496443Y134384D01*
X496175Y134539D01*
X495868Y134591D01*
X495485Y134488D01*
X495217Y134229D01*
X495140Y133919D01*
X495178Y133609D01*
X495332Y133351D01*
X496098Y132834D01*
X496443Y132473D01*
X496673Y131956D01*
X496750Y131491D01*
X495140D01*
G01X492845D02*
X492577Y131543D01*
X492270Y131698D01*
X492078Y131956D01*
X492002Y132318D01*
X492078Y132679D01*
X492308Y132989D01*
X492653Y133144D01*
X493037D01*
X493267Y133248D01*
X493458Y133506D01*
X493535Y133868D01*
X493420Y134229D01*
X493152Y134488D01*
X492845Y134591D01*
X492538Y134488D01*
X492270Y134229D01*
X492155Y133868D01*
X492232Y133506D01*
X492423Y133248D01*
X492653Y133144D01*
X493037D01*
X493382Y132989D01*
X493612Y132679D01*
X493688Y132318D01*
X493612Y131956D01*
X493420Y131698D01*
X493113Y131543D01*
X492845Y131491D01*
G01X491174Y127066D02*
X497374D01*
G01Y130266D02*
X491174D01*
G01D02*
Y127066D01*
G01X482315Y141764D02*
Y144964D01*
G01Y145764D02*
Y148964D01*
G01Y149764D02*
Y152964D01*
G01X501717Y151500D02*
Y154600D01*
X500758D01*
X500452Y154445D01*
X500260Y154238D01*
X500183Y153825D01*
X500260Y153412D01*
X500490Y153153D01*
X500758Y152998D01*
X501717D01*
G01X500758D02*
X500183Y151500D01*
G01X498578Y152792D02*
X498310Y153153D01*
X498080Y153360D01*
X497773Y153463D01*
X497505Y153360D01*
X497313Y153153D01*
X497160Y152843D01*
X497122Y152482D01*
X497160Y152172D01*
X497313Y151862D01*
X497543Y151603D01*
X497812Y151500D01*
X498118Y151603D01*
X498387Y151913D01*
X498540Y152378D01*
X498578Y152895D01*
X498502Y153567D01*
X498387Y153928D01*
X498195Y154290D01*
X497927Y154548D01*
X497658Y154600D01*
X497390Y154497D01*
X497198Y154238D01*
G01X495478Y154083D02*
X495248Y154393D01*
X494980Y154548D01*
X494673Y154600D01*
X494290Y154497D01*
X494022Y154238D01*
X493945Y153928D01*
X493983Y153618D01*
X494137Y153360D01*
X494903Y152843D01*
X495248Y152482D01*
X495478Y151965D01*
X495555Y151500D01*
X493945D01*
G01X491650Y154600D02*
X491957Y154497D01*
X492187Y154238D01*
X492340Y153928D01*
X492455Y153515D01*
X492493Y153050D01*
X492455Y152585D01*
X492340Y152172D01*
X492187Y151862D01*
X491957Y151603D01*
X491650Y151500D01*
X491343Y151603D01*
X491113Y151862D01*
X490960Y152172D01*
X490845Y152585D01*
X490807Y153050D01*
X490845Y153515D01*
X490960Y153928D01*
X491113Y154238D01*
X491343Y154497D01*
X491650Y154600D01*
G01X483800Y170513D02*
Y173713D01*
G01Y162514D02*
Y165712D01*
G01Y166513D02*
Y169713D01*
G01X499319Y159361D02*
X493119D01*
G01Y156161D02*
X499319D01*
G01X493119Y159361D02*
Y156161D01*
G01Y160661D02*
X499319D01*
G01X493119Y163861D02*
Y160661D01*
G01X499319Y163861D02*
X493119D01*
G01X506117Y174700D02*
Y177800D01*
X505158D01*
X504852Y177645D01*
X504660Y177438D01*
X504583Y177025D01*
X504660Y176612D01*
X504890Y176353D01*
X505158Y176198D01*
X506117D01*
G01X505158D02*
X504583Y174700D01*
G01X502250D02*
Y177800D01*
X502710Y177180D01*
G01Y174700D02*
X501790D01*
G01X499150D02*
Y177800D01*
X499610Y177180D01*
G01Y174700D02*
X498690D01*
G01X496893Y175320D02*
X496663Y174958D01*
X496357Y174752D01*
X496012Y174700D01*
X495705Y174752D01*
X495398Y175010D01*
X495207Y175320D01*
X495168Y175630D01*
X495245Y175992D01*
X495513Y176250D01*
X495782Y176353D01*
X496127D01*
G01X495782D02*
X495552Y176508D01*
X495360Y176767D01*
X495283Y177077D01*
X495360Y177387D01*
X495552Y177645D01*
X495897Y177800D01*
X496242Y177748D01*
X496587Y177542D01*
G01X492950Y174700D02*
X492682Y174752D01*
X492375Y174907D01*
X492183Y175165D01*
X492107Y175527D01*
X492183Y175888D01*
X492413Y176198D01*
X492758Y176353D01*
X493142D01*
X493372Y176457D01*
X493563Y176715D01*
X493640Y177077D01*
X493525Y177438D01*
X493257Y177697D01*
X492950Y177800D01*
X492643Y177697D01*
X492375Y177438D01*
X492260Y177077D01*
X492337Y176715D01*
X492528Y176457D01*
X492758Y176353D01*
X493142D01*
X493487Y176198D01*
X493717Y175888D01*
X493793Y175527D01*
X493717Y175165D01*
X493525Y174907D01*
X493218Y174752D01*
X492950Y174700D01*
G01X480060Y178783D02*
Y181983D01*
G01X483800Y174513D02*
Y177713D01*
G01X508417Y196200D02*
Y199300D01*
X507458D01*
X507152Y199145D01*
X506960Y198938D01*
X506883Y198525D01*
X506960Y198112D01*
X507190Y197853D01*
X507458Y197698D01*
X508417D01*
G01X507458D02*
X506883Y196200D01*
G01X504550D02*
Y199300D01*
X505010Y198680D01*
G01Y196200D02*
X504090D01*
G01X502178Y198783D02*
X501948Y199093D01*
X501680Y199248D01*
X501373Y199300D01*
X500990Y199197D01*
X500722Y198938D01*
X500645Y198628D01*
X500683Y198318D01*
X500837Y198060D01*
X501603Y197543D01*
X501948Y197182D01*
X502178Y196665D01*
X502255Y196200D01*
X500645D01*
G01X499078Y197492D02*
X498810Y197853D01*
X498580Y198060D01*
X498273Y198163D01*
X498005Y198060D01*
X497813Y197853D01*
X497660Y197543D01*
X497622Y197182D01*
X497660Y196872D01*
X497813Y196562D01*
X498043Y196303D01*
X498312Y196200D01*
X498618Y196303D01*
X498887Y196613D01*
X499040Y197078D01*
X499078Y197595D01*
X499002Y198267D01*
X498887Y198628D01*
X498695Y198990D01*
X498427Y199248D01*
X498158Y199300D01*
X497890Y199197D01*
X497698Y198938D01*
G01X496093Y196820D02*
X495863Y196458D01*
X495557Y196252D01*
X495212Y196200D01*
X494905Y196252D01*
X494598Y196510D01*
X494407Y196820D01*
X494368Y197130D01*
X494445Y197492D01*
X494713Y197750D01*
X494982Y197853D01*
X495327D01*
G01X494982D02*
X494752Y198008D01*
X494560Y198267D01*
X494483Y198577D01*
X494560Y198887D01*
X494752Y199145D01*
X495097Y199300D01*
X495442Y199248D01*
X495787Y199042D01*
G01X492774Y456680D02*
X495874D01*
Y457639D01*
X495719Y457945D01*
X495512Y458137D01*
X495099Y458214D01*
X494686Y458137D01*
X494427Y457907D01*
X494272Y457639D01*
Y456680D01*
G01Y457639D02*
X492774Y458214D01*
G01X494066Y459819D02*
X494427Y460087D01*
X494634Y460317D01*
X494737Y460624D01*
X494634Y460892D01*
X494427Y461084D01*
X494117Y461237D01*
X493756Y461275D01*
X493446Y461237D01*
X493136Y461084D01*
X492877Y460854D01*
X492774Y460585D01*
X492877Y460279D01*
X493187Y460010D01*
X493652Y459857D01*
X494169Y459819D01*
X494841Y459895D01*
X495202Y460010D01*
X495564Y460202D01*
X495822Y460470D01*
X495874Y460739D01*
X495771Y461007D01*
X495512Y461199D01*
G01X491765Y484125D02*
X496365D01*
G01X491765Y494325D02*
Y484125D01*
G01X492803Y495293D02*
X495903D01*
Y496252D01*
X495748Y496558D01*
X495541Y496750D01*
X495128Y496827D01*
X494715Y496750D01*
X494456Y496520D01*
X494301Y496252D01*
Y495293D01*
G01Y496252D02*
X492803Y496827D01*
G01X493423Y498317D02*
X493061Y498547D01*
X492855Y498853D01*
X492803Y499198D01*
X492855Y499505D01*
X493113Y499812D01*
X493423Y500003D01*
X493733Y500042D01*
X494095Y499965D01*
X494353Y499697D01*
X494456Y499428D01*
Y499083D01*
G01Y499428D02*
X494611Y499658D01*
X494870Y499850D01*
X495180Y499927D01*
X495490Y499850D01*
X495748Y499658D01*
X495903Y499313D01*
X495851Y498968D01*
X495645Y498623D01*
G01X496365Y494325D02*
X491765D01*
G01X494926Y532028D02*
X495081Y531798D01*
X495184Y531530D01*
Y531223D01*
X495029Y530878D01*
X494771Y530610D01*
X494461Y530418D01*
X493944Y530265D01*
X493479Y530227D01*
X493014Y530303D01*
X492704Y530418D01*
X492394Y530648D01*
X492187Y530917D01*
X492084Y531185D01*
Y531453D01*
X492187Y531722D01*
X492342Y531952D01*
X492549Y532143D01*
G01X492084Y534285D02*
X492136Y534553D01*
X492291Y534860D01*
X492549Y535052D01*
X492911Y535128D01*
X493272Y535052D01*
X493582Y534822D01*
X493737Y534477D01*
Y534093D01*
X493841Y533863D01*
X494099Y533672D01*
X494461Y533595D01*
X494822Y533710D01*
X495081Y533978D01*
X495184Y534285D01*
X495081Y534592D01*
X494822Y534860D01*
X494461Y534975D01*
X494099Y534898D01*
X493841Y534707D01*
X493737Y534477D01*
Y534093D01*
X493582Y533748D01*
X493272Y533518D01*
X492911Y533442D01*
X492549Y533518D01*
X492291Y533710D01*
X492136Y534017D01*
X492084Y534285D01*
G01X492446Y536733D02*
X492187Y537002D01*
X492084Y537308D01*
X492187Y537615D01*
X492497Y537883D01*
X492962Y538075D01*
X493427Y538152D01*
X493996D01*
X494461Y538075D01*
X494874Y537883D01*
X495081Y537653D01*
X495184Y537385D01*
X495081Y537078D01*
X494874Y536848D01*
X494564Y536695D01*
X494151Y536618D01*
X493789Y536695D01*
X493427Y536887D01*
X493221Y537117D01*
X493169Y537385D01*
X493272Y537692D01*
X493531Y537922D01*
X493996Y538152D01*
G01X492084Y540408D02*
X492756Y540485D01*
X493324Y540600D01*
X493841Y540753D01*
X494409Y540945D01*
X495184Y541252D01*
Y539718D01*
G01X494238Y545425D02*
X497238D01*
G01X494138Y542325D02*
X497338D01*
G01X494138Y548525D02*
Y542325D01*
G01X497338Y548525D02*
X494138D01*
G01X495922Y552626D02*
X496152Y552781D01*
X496420Y552884D01*
X496727D01*
X497072Y552729D01*
X497340Y552471D01*
X497532Y552161D01*
X497685Y551644D01*
X497723Y551179D01*
X497647Y550714D01*
X497532Y550404D01*
X497302Y550094D01*
X497033Y549887D01*
X496765Y549784D01*
X496497D01*
X496228Y549887D01*
X495998Y550042D01*
X495807Y550249D01*
G01X493665Y549784D02*
X493397Y549836D01*
X493090Y549991D01*
X492898Y550249D01*
X492822Y550611D01*
X492898Y550972D01*
X493128Y551282D01*
X493473Y551437D01*
X493857D01*
X494087Y551541D01*
X494278Y551799D01*
X494355Y552161D01*
X494240Y552522D01*
X493972Y552781D01*
X493665Y552884D01*
X493358Y552781D01*
X493090Y552522D01*
X492975Y552161D01*
X493052Y551799D01*
X493243Y551541D01*
X493473Y551437D01*
X493857D01*
X494202Y551282D01*
X494432Y550972D01*
X494508Y550611D01*
X494432Y550249D01*
X494240Y549991D01*
X493933Y549836D01*
X493665Y549784D01*
G01X490642D02*
X490565Y550456D01*
X490450Y551024D01*
X490297Y551541D01*
X490105Y552109D01*
X489798Y552884D01*
X491332D01*
G01X487465Y549784D02*
X487197Y549836D01*
X486890Y549991D01*
X486698Y550249D01*
X486622Y550611D01*
X486698Y550972D01*
X486928Y551282D01*
X487273Y551437D01*
X487657D01*
X487887Y551541D01*
X488078Y551799D01*
X488155Y552161D01*
X488040Y552522D01*
X487772Y552781D01*
X487465Y552884D01*
X487158Y552781D01*
X486890Y552522D01*
X486775Y552161D01*
X486852Y551799D01*
X487043Y551541D01*
X487273Y551437D01*
X487657D01*
X488002Y551282D01*
X488232Y550972D01*
X488308Y550611D01*
X488232Y550249D01*
X488040Y549991D01*
X487733Y549836D01*
X487465Y549784D01*
G01X492438Y564625D02*
Y561425D01*
G01X498638Y564625D02*
X492438D01*
G01Y561425D02*
X498638D01*
G01X481060Y555048D02*
Y558248D01*
G01Y559048D02*
Y562248D01*
G01X494738Y554225D02*
X497938D01*
G01X494738Y560425D02*
Y554225D01*
G01X494838Y557325D02*
X497838D01*
G01X497938Y560425D02*
X494738D01*
G01X481060Y565095D02*
Y568293D01*
G01X492538Y569425D02*
Y566225D01*
G01X498738Y569425D02*
X492538D01*
G01Y566225D02*
X498738D01*
G01X492538Y573325D02*
Y570125D01*
G01X498738Y573325D02*
X492538D01*
G01Y570125D02*
X498738D01*
G01X481060Y569095D02*
Y572293D01*
G01X492538Y581125D02*
Y577925D01*
G01D02*
X498738D01*
G01X492538Y577225D02*
Y574025D01*
G01D02*
X498738D01*
G01Y577225D02*
X492538D01*
G01X498738Y581125D02*
X492538D01*
G01X496997Y585454D02*
X497227Y585609D01*
X497495Y585712D01*
X497802D01*
X498147Y585557D01*
X498415Y585299D01*
X498607Y584989D01*
X498760Y584472D01*
X498798Y584007D01*
X498722Y583542D01*
X498607Y583232D01*
X498377Y582922D01*
X498108Y582715D01*
X497840Y582612D01*
X497572D01*
X497303Y582715D01*
X497073Y582870D01*
X496882Y583077D01*
G01X495468Y585195D02*
X495238Y585505D01*
X494970Y585660D01*
X494663Y585712D01*
X494280Y585609D01*
X494012Y585350D01*
X493935Y585040D01*
X493973Y584730D01*
X494127Y584472D01*
X494893Y583955D01*
X495238Y583594D01*
X495468Y583077D01*
X495545Y582612D01*
X493935D01*
G01X491640Y585712D02*
X491947Y585609D01*
X492177Y585350D01*
X492330Y585040D01*
X492445Y584627D01*
X492483Y584162D01*
X492445Y583697D01*
X492330Y583284D01*
X492177Y582974D01*
X491947Y582715D01*
X491640Y582612D01*
X491333Y582715D01*
X491103Y582974D01*
X490950Y583284D01*
X490835Y583697D01*
X490797Y584162D01*
X490835Y584627D01*
X490950Y585040D01*
X491103Y585350D01*
X491333Y585609D01*
X491640Y585712D01*
G01X488540D02*
X488847Y585609D01*
X489077Y585350D01*
X489230Y585040D01*
X489345Y584627D01*
X489383Y584162D01*
X489345Y583697D01*
X489230Y583284D01*
X489077Y582974D01*
X488847Y582715D01*
X488540Y582612D01*
X488233Y582715D01*
X488003Y582974D01*
X487850Y583284D01*
X487735Y583697D01*
X487697Y584162D01*
X487735Y584627D01*
X487850Y585040D01*
X488003Y585350D01*
X488233Y585609D01*
X488540Y585712D01*
G01X490180Y591936D02*
X500380D01*
Y596536D01*
X490180D01*
Y591936D01*
G01X503877Y620525D02*
Y618303D01*
X503724Y617838D01*
X503417Y617528D01*
X503034Y617425D01*
X502651Y617528D01*
X502344Y617838D01*
X502191Y618303D01*
Y620525D01*
G01X499934Y617425D02*
Y620525D01*
X500394Y619905D01*
G01Y617425D02*
X499474D01*
G01X496374D02*
Y620525D01*
X497792Y618303D01*
X495876D01*
G01X494577Y618045D02*
X494347Y617683D01*
X494041Y617477D01*
X493696Y617425D01*
X493389Y617477D01*
X493082Y617735D01*
X492891Y618045D01*
X492852Y618355D01*
X492929Y618717D01*
X493197Y618975D01*
X493466Y619078D01*
X493811D01*
G01X493466D02*
X493236Y619233D01*
X493044Y619492D01*
X492967Y619802D01*
X493044Y620112D01*
X493236Y620370D01*
X493581Y620525D01*
X493926Y620473D01*
X494271Y620267D01*
G01X483268Y639936D02*
X486368D01*
Y640895D01*
X486213Y641201D01*
X486006Y641393D01*
X485593Y641470D01*
X485180Y641393D01*
X484921Y641163D01*
X484766Y640895D01*
Y639936D01*
G01Y640895D02*
X483268Y641470D01*
G01Y643803D02*
X486368D01*
X485748Y643343D01*
G01X483268D02*
Y644263D01*
G01X485851Y646175D02*
X486161Y646405D01*
X486316Y646673D01*
X486368Y646980D01*
X486265Y647363D01*
X486006Y647631D01*
X485696Y647708D01*
X485386Y647670D01*
X485128Y647516D01*
X484611Y646750D01*
X484250Y646405D01*
X483733Y646175D01*
X483268Y646098D01*
Y647708D01*
G01X485851Y649275D02*
X486161Y649505D01*
X486316Y649773D01*
X486368Y650080D01*
X486265Y650463D01*
X486006Y650731D01*
X485696Y650808D01*
X485386Y650770D01*
X485128Y650616D01*
X484611Y649850D01*
X484250Y649505D01*
X483733Y649275D01*
X483268Y649198D01*
Y650808D01*
G01X483733Y652260D02*
X483475Y652490D01*
X483320Y652758D01*
X483268Y653103D01*
X483371Y653448D01*
X483578Y653716D01*
X483940Y653908D01*
X484353Y653946D01*
X484766Y653870D01*
X485025Y653678D01*
X485231Y653410D01*
X485283Y653141D01*
X485231Y652873D01*
X485025Y652528D01*
X486368Y652643D01*
Y653678D01*
G01X493522Y638808D02*
X492989D01*
Y638058D01*
X493149Y637808D01*
X493335Y637641D01*
X493602Y637558D01*
X493869Y637641D01*
X494055Y637808D01*
X494215Y638058D01*
X494322Y638350D01*
X494375Y638683D01*
Y638975D01*
X494322Y639225D01*
X494215Y639516D01*
X494055Y639766D01*
X493895Y639933D01*
X493682Y640058D01*
X493495D01*
X493282Y639975D01*
X493122Y639808D01*
G01X503281Y655413D02*
Y658513D01*
X502322D01*
X502016Y658358D01*
X501824Y658151D01*
X501747Y657738D01*
X501824Y657325D01*
X502054Y657066D01*
X502322Y656911D01*
X503281D01*
G01X502322D02*
X501747Y655413D01*
G01X499414D02*
Y658513D01*
X499874Y657893D01*
G01Y655413D02*
X498954D01*
G01X496314Y658513D02*
X496621Y658410D01*
X496851Y658151D01*
X497004Y657841D01*
X497119Y657428D01*
X497157Y656963D01*
X497119Y656498D01*
X497004Y656085D01*
X496851Y655775D01*
X496621Y655516D01*
X496314Y655413D01*
X496007Y655516D01*
X495777Y655775D01*
X495624Y656085D01*
X495509Y656498D01*
X495471Y656963D01*
X495509Y657428D01*
X495624Y657841D01*
X495777Y658151D01*
X496007Y658410D01*
X496314Y658513D01*
G01X493214D02*
X493521Y658410D01*
X493751Y658151D01*
X493904Y657841D01*
X494019Y657428D01*
X494057Y656963D01*
X494019Y656498D01*
X493904Y656085D01*
X493751Y655775D01*
X493521Y655516D01*
X493214Y655413D01*
X492907Y655516D01*
X492677Y655775D01*
X492524Y656085D01*
X492409Y656498D01*
X492371Y656963D01*
X492409Y657428D01*
X492524Y657841D01*
X492677Y658151D01*
X492907Y658410D01*
X493214Y658513D01*
G01X490114D02*
X490421Y658410D01*
X490651Y658151D01*
X490804Y657841D01*
X490919Y657428D01*
X490957Y656963D01*
X490919Y656498D01*
X490804Y656085D01*
X490651Y655775D01*
X490421Y655516D01*
X490114Y655413D01*
X489807Y655516D01*
X489577Y655775D01*
X489424Y656085D01*
X489309Y656498D01*
X489271Y656963D01*
X489309Y657428D01*
X489424Y657841D01*
X489577Y658151D01*
X489807Y658410D01*
X490114Y658513D01*
G01X492250Y690594D02*
Y688846D01*
G01Y686740D02*
Y684155D01*
G01Y680995D02*
Y680577D01*
G01Y678386D02*
Y676866D01*
G01X489790Y676230D02*
X481360D01*
G01X483940Y680256D02*
Y677056D01*
G01X490140Y680256D02*
X483940D01*
G01X490140Y677056D02*
Y680256D01*
G01X483940Y677056D02*
X490140D01*
G01X487040Y680156D02*
Y677156D01*
G01X483940Y684256D02*
Y681056D01*
G01X490140Y684256D02*
X483940D01*
G01X490140Y681056D02*
Y684256D01*
G01X483940Y681056D02*
X490140D01*
G01Y685056D02*
Y688256D01*
G01X483940Y685056D02*
X490140D01*
G01X483940Y688256D02*
Y685056D01*
G01X490140Y688256D02*
X483940D01*
G01X490140Y689056D02*
Y692256D01*
G01X483940Y689056D02*
X490140D01*
G01X483940Y692256D02*
Y689056D01*
G01X492250Y706511D02*
Y705195D01*
G01Y702490D02*
Y701079D01*
G01Y698709D02*
Y697129D01*
G01Y694424D02*
Y692701D01*
G01X490140Y693056D02*
Y696256D01*
G01X483940Y693056D02*
X490140D01*
G01X483940Y696256D02*
Y693056D01*
G01X490140Y696256D02*
X483940D01*
G01X490140Y697056D02*
Y700256D01*
G01X483940Y697056D02*
X490140D01*
G01X483940Y700256D02*
Y697056D01*
G01X490140Y700256D02*
X483940D01*
G01X490140Y692256D02*
X483940D01*
G01X492250Y714411D02*
Y713166D01*
G01Y720370D02*
Y717331D01*
G01Y710365D02*
Y708690D01*
G01Y720370D02*
X490400D01*
G01X503493Y-244364D02*
Y-236364D01*
X502293Y-237964D01*
G01Y-244364D02*
X504693D01*
G01X509593Y-241031D02*
X510293Y-240097D01*
X510893Y-239564D01*
X511693Y-239297D01*
X512393Y-239564D01*
X512893Y-240097D01*
X513293Y-240897D01*
X513393Y-241831D01*
X513293Y-242631D01*
X512893Y-243431D01*
X512293Y-244097D01*
X511593Y-244364D01*
X510793Y-244097D01*
X510093Y-243298D01*
X509693Y-242097D01*
X509593Y-240764D01*
X509793Y-239031D01*
X510093Y-238097D01*
X510593Y-237164D01*
X511293Y-236497D01*
X511993Y-236364D01*
X512693Y-236631D01*
X513193Y-237297D01*
G01X508934Y27399D02*
Y30499D01*
X509394Y29879D01*
G01Y27399D02*
X508474D01*
G01X505834Y30499D02*
X506141Y30396D01*
X506371Y30137D01*
X506524Y29827D01*
X506639Y29414D01*
X506677Y28949D01*
X506639Y28484D01*
X506524Y28071D01*
X506371Y27761D01*
X506141Y27502D01*
X505834Y27399D01*
X505527Y27502D01*
X505297Y27761D01*
X505144Y28071D01*
X505029Y28484D01*
X504991Y28949D01*
X505029Y29414D01*
X505144Y29827D01*
X505297Y30137D01*
X505527Y30396D01*
X505834Y30499D01*
G01X509311Y38154D02*
X509042Y37895D01*
X508736Y37792D01*
X508429Y37895D01*
X508161Y38205D01*
X507969Y38670D01*
X507892Y39135D01*
Y39704D01*
X507969Y40169D01*
X508161Y40582D01*
X508391Y40789D01*
X508659Y40892D01*
X508966Y40789D01*
X509196Y40582D01*
X509349Y40272D01*
X509426Y39859D01*
X509349Y39497D01*
X509157Y39135D01*
X508927Y38929D01*
X508659Y38877D01*
X508352Y38980D01*
X508122Y39239D01*
X507892Y39704D01*
G01X554741Y132248D02*
X554866D01*
Y99524D01*
X576744D01*
Y59655D01*
X495689D01*
Y95638D01*
X554802D01*
Y99587D01*
G01X510566Y60826D02*
Y63926D01*
X509607D01*
X509301Y63771D01*
X509109Y63564D01*
X509032Y63151D01*
X509109Y62738D01*
X509339Y62479D01*
X509607Y62324D01*
X510566D01*
G01X509607D02*
X509032Y60826D01*
G01X506699D02*
Y63926D01*
X507159Y63306D01*
G01Y60826D02*
X506239D01*
G01X503599D02*
Y63926D01*
X504059Y63306D01*
G01Y60826D02*
X503139D01*
G01X500499D02*
X500231Y60878D01*
X499924Y61033D01*
X499732Y61291D01*
X499656Y61653D01*
X499732Y62014D01*
X499962Y62324D01*
X500307Y62479D01*
X500691D01*
X500921Y62583D01*
X501112Y62841D01*
X501189Y63203D01*
X501074Y63564D01*
X500806Y63823D01*
X500499Y63926D01*
X500192Y63823D01*
X499924Y63564D01*
X499809Y63203D01*
X499886Y62841D01*
X500077Y62583D01*
X500307Y62479D01*
X500691D01*
X501036Y62324D01*
X501266Y62014D01*
X501342Y61653D01*
X501266Y61291D01*
X501074Y61033D01*
X500767Y60878D01*
X500499Y60826D01*
G01X498242Y61291D02*
X498012Y61033D01*
X497744Y60878D01*
X497399Y60826D01*
X497054Y60929D01*
X496786Y61136D01*
X496594Y61498D01*
X496556Y61911D01*
X496632Y62324D01*
X496824Y62583D01*
X497092Y62789D01*
X497361Y62841D01*
X497629Y62789D01*
X497974Y62583D01*
X497859Y63926D01*
X496824D01*
G01X510566Y77993D02*
Y81093D01*
X509607D01*
X509301Y80938D01*
X509109Y80731D01*
X509032Y80318D01*
X509109Y79905D01*
X509339Y79646D01*
X509607Y79491D01*
X510566D01*
G01X509607D02*
X509032Y77993D01*
G01X506699D02*
Y81093D01*
X507159Y80473D01*
G01Y77993D02*
X506239D01*
G01X503599D02*
Y81093D01*
X504059Y80473D01*
G01Y77993D02*
X503139D01*
G01X500499D02*
X500231Y78045D01*
X499924Y78200D01*
X499732Y78458D01*
X499656Y78820D01*
X499732Y79181D01*
X499962Y79491D01*
X500307Y79646D01*
X500691D01*
X500921Y79750D01*
X501112Y80008D01*
X501189Y80370D01*
X501074Y80731D01*
X500806Y80990D01*
X500499Y81093D01*
X500192Y80990D01*
X499924Y80731D01*
X499809Y80370D01*
X499886Y80008D01*
X500077Y79750D01*
X500307Y79646D01*
X500691D01*
X501036Y79491D01*
X501266Y79181D01*
X501342Y78820D01*
X501266Y78458D01*
X501074Y78200D01*
X500767Y78045D01*
X500499Y77993D01*
G01X497399Y81093D02*
X497706Y80990D01*
X497936Y80731D01*
X498089Y80421D01*
X498204Y80008D01*
X498242Y79543D01*
X498204Y79078D01*
X498089Y78665D01*
X497936Y78355D01*
X497706Y78096D01*
X497399Y77993D01*
X497092Y78096D01*
X496862Y78355D01*
X496709Y78665D01*
X496594Y79078D01*
X496556Y79543D01*
X496594Y80008D01*
X496709Y80421D01*
X496862Y80731D01*
X497092Y80990D01*
X497399Y81093D01*
G01X510566Y65055D02*
Y68155D01*
X509607D01*
X509301Y68000D01*
X509109Y67793D01*
X509032Y67380D01*
X509109Y66967D01*
X509339Y66708D01*
X509607Y66553D01*
X510566D01*
G01X509607D02*
X509032Y65055D01*
G01X506699D02*
Y68155D01*
X507159Y67535D01*
G01Y65055D02*
X506239D01*
G01X503599D02*
Y68155D01*
X504059Y67535D01*
G01Y65055D02*
X503139D01*
G01X500499D02*
X500231Y65107D01*
X499924Y65262D01*
X499732Y65520D01*
X499656Y65882D01*
X499732Y66243D01*
X499962Y66553D01*
X500307Y66708D01*
X500691D01*
X500921Y66812D01*
X501112Y67070D01*
X501189Y67432D01*
X501074Y67793D01*
X500806Y68052D01*
X500499Y68155D01*
X500192Y68052D01*
X499924Y67793D01*
X499809Y67432D01*
X499886Y67070D01*
X500077Y66812D01*
X500307Y66708D01*
X500691D01*
X501036Y66553D01*
X501266Y66243D01*
X501342Y65882D01*
X501266Y65520D01*
X501074Y65262D01*
X500767Y65107D01*
X500499Y65055D01*
G01X498242Y65675D02*
X498012Y65313D01*
X497706Y65107D01*
X497361Y65055D01*
X497054Y65107D01*
X496747Y65365D01*
X496556Y65675D01*
X496517Y65985D01*
X496594Y66347D01*
X496862Y66605D01*
X497131Y66708D01*
X497476D01*
G01X497131D02*
X496901Y66863D01*
X496709Y67122D01*
X496632Y67432D01*
X496709Y67742D01*
X496901Y68000D01*
X497246Y68155D01*
X497591Y68103D01*
X497936Y67897D01*
G01X510566Y69986D02*
Y73086D01*
X509607D01*
X509301Y72931D01*
X509109Y72724D01*
X509032Y72311D01*
X509109Y71898D01*
X509339Y71639D01*
X509607Y71484D01*
X510566D01*
G01X509607D02*
X509032Y69986D01*
G01X506699D02*
Y73086D01*
X507159Y72466D01*
G01Y69986D02*
X506239D01*
G01X503599D02*
Y73086D01*
X504059Y72466D01*
G01Y69986D02*
X503139D01*
G01X500499D02*
X500231Y70038D01*
X499924Y70193D01*
X499732Y70451D01*
X499656Y70813D01*
X499732Y71174D01*
X499962Y71484D01*
X500307Y71639D01*
X500691D01*
X500921Y71743D01*
X501112Y72001D01*
X501189Y72363D01*
X501074Y72724D01*
X500806Y72983D01*
X500499Y73086D01*
X500192Y72983D01*
X499924Y72724D01*
X499809Y72363D01*
X499886Y72001D01*
X500077Y71743D01*
X500307Y71639D01*
X500691D01*
X501036Y71484D01*
X501266Y71174D01*
X501342Y70813D01*
X501266Y70451D01*
X501074Y70193D01*
X500767Y70038D01*
X500499Y69986D01*
G01X497399D02*
Y73086D01*
X497859Y72466D01*
G01Y69986D02*
X496939D01*
G01X510566Y73993D02*
Y77093D01*
X509607D01*
X509301Y76938D01*
X509109Y76731D01*
X509032Y76318D01*
X509109Y75905D01*
X509339Y75646D01*
X509607Y75491D01*
X510566D01*
G01X509607D02*
X509032Y73993D01*
G01X506699D02*
Y77093D01*
X507159Y76473D01*
G01Y73993D02*
X506239D01*
G01X503599D02*
Y77093D01*
X504059Y76473D01*
G01Y73993D02*
X503139D01*
G01X500499D02*
X500231Y74045D01*
X499924Y74200D01*
X499732Y74458D01*
X499656Y74820D01*
X499732Y75181D01*
X499962Y75491D01*
X500307Y75646D01*
X500691D01*
X500921Y75750D01*
X501112Y76008D01*
X501189Y76370D01*
X501074Y76731D01*
X500806Y76990D01*
X500499Y77093D01*
X500192Y76990D01*
X499924Y76731D01*
X499809Y76370D01*
X499886Y76008D01*
X500077Y75750D01*
X500307Y75646D01*
X500691D01*
X501036Y75491D01*
X501266Y75181D01*
X501342Y74820D01*
X501266Y74458D01*
X501074Y74200D01*
X500767Y74045D01*
X500499Y73993D01*
G01X497399D02*
X497131Y74045D01*
X496824Y74200D01*
X496632Y74458D01*
X496556Y74820D01*
X496632Y75181D01*
X496862Y75491D01*
X497207Y75646D01*
X497591D01*
X497821Y75750D01*
X498012Y76008D01*
X498089Y76370D01*
X497974Y76731D01*
X497706Y76990D01*
X497399Y77093D01*
X497092Y76990D01*
X496824Y76731D01*
X496709Y76370D01*
X496786Y76008D01*
X496977Y75750D01*
X497207Y75646D01*
X497591D01*
X497936Y75491D01*
X498166Y75181D01*
X498242Y74820D01*
X498166Y74458D01*
X497974Y74200D01*
X497667Y74045D01*
X497399Y73993D01*
G01X510566Y81993D02*
Y85093D01*
X509607D01*
X509301Y84938D01*
X509109Y84731D01*
X509032Y84318D01*
X509109Y83905D01*
X509339Y83646D01*
X509607Y83491D01*
X510566D01*
G01X509607D02*
X509032Y81993D01*
G01X506699D02*
Y85093D01*
X507159Y84473D01*
G01Y81993D02*
X506239D01*
G01X503599D02*
Y85093D01*
X504059Y84473D01*
G01Y81993D02*
X503139D01*
G01X501151Y82355D02*
X500882Y82096D01*
X500576Y81993D01*
X500269Y82096D01*
X500001Y82406D01*
X499809Y82871D01*
X499732Y83336D01*
Y83905D01*
X499809Y84370D01*
X500001Y84783D01*
X500231Y84990D01*
X500499Y85093D01*
X500806Y84990D01*
X501036Y84783D01*
X501189Y84473D01*
X501266Y84060D01*
X501189Y83698D01*
X500997Y83336D01*
X500767Y83130D01*
X500499Y83078D01*
X500192Y83181D01*
X499962Y83440D01*
X499732Y83905D01*
G01X497399Y81993D02*
Y85093D01*
X497859Y84473D01*
G01Y81993D02*
X496939D01*
G01X510566Y91198D02*
Y94298D01*
X509607D01*
X509301Y94143D01*
X509109Y93936D01*
X509032Y93523D01*
X509109Y93110D01*
X509339Y92851D01*
X509607Y92696D01*
X510566D01*
G01X509607D02*
X509032Y91198D01*
G01X506699D02*
Y94298D01*
X507159Y93678D01*
G01Y91198D02*
X506239D01*
G01X503599D02*
Y94298D01*
X504059Y93678D01*
G01Y91198D02*
X503139D01*
G01X500499D02*
Y94298D01*
X500959Y93678D01*
G01Y91198D02*
X500039D01*
G01X498051Y91560D02*
X497782Y91301D01*
X497476Y91198D01*
X497169Y91301D01*
X496901Y91611D01*
X496709Y92076D01*
X496632Y92541D01*
Y93110D01*
X496709Y93575D01*
X496901Y93988D01*
X497131Y94195D01*
X497399Y94298D01*
X497706Y94195D01*
X497936Y93988D01*
X498089Y93678D01*
X498166Y93265D01*
X498089Y92903D01*
X497897Y92541D01*
X497667Y92335D01*
X497399Y92283D01*
X497092Y92386D01*
X496862Y92645D01*
X496632Y93110D01*
G01X510566Y86822D02*
Y89922D01*
X509607D01*
X509301Y89767D01*
X509109Y89560D01*
X509032Y89147D01*
X509109Y88734D01*
X509339Y88475D01*
X509607Y88320D01*
X510566D01*
G01X509607D02*
X509032Y86822D01*
G01X506699D02*
Y89922D01*
X507159Y89302D01*
G01Y86822D02*
X506239D01*
G01X503599D02*
Y89922D01*
X504059Y89302D01*
G01Y86822D02*
X503139D01*
G01X501151Y87184D02*
X500882Y86925D01*
X500576Y86822D01*
X500269Y86925D01*
X500001Y87235D01*
X499809Y87700D01*
X499732Y88165D01*
Y88734D01*
X499809Y89199D01*
X500001Y89612D01*
X500231Y89819D01*
X500499Y89922D01*
X500806Y89819D01*
X501036Y89612D01*
X501189Y89302D01*
X501266Y88889D01*
X501189Y88527D01*
X500997Y88165D01*
X500767Y87959D01*
X500499Y87907D01*
X500192Y88010D01*
X499962Y88269D01*
X499732Y88734D01*
G01X498127Y89405D02*
X497897Y89715D01*
X497629Y89870D01*
X497322Y89922D01*
X496939Y89819D01*
X496671Y89560D01*
X496594Y89250D01*
X496632Y88940D01*
X496786Y88682D01*
X497552Y88165D01*
X497897Y87804D01*
X498127Y87287D01*
X498204Y86822D01*
X496594D01*
G01X511513Y104921D02*
Y108021D01*
X510554D01*
X510248Y107866D01*
X510056Y107659D01*
X509979Y107246D01*
X510056Y106833D01*
X510286Y106574D01*
X510554Y106419D01*
X511513D01*
G01X510554D02*
X509979Y104921D01*
G01X507646D02*
Y108021D01*
X508106Y107401D01*
G01Y104921D02*
X507186D01*
G01X505274Y107504D02*
X505044Y107814D01*
X504776Y107969D01*
X504469Y108021D01*
X504086Y107918D01*
X503818Y107659D01*
X503741Y107349D01*
X503779Y107039D01*
X503933Y106781D01*
X504699Y106264D01*
X505044Y105903D01*
X505274Y105386D01*
X505351Y104921D01*
X503741D01*
G01X501446Y108021D02*
X501753Y107918D01*
X501983Y107659D01*
X502136Y107349D01*
X502251Y106936D01*
X502289Y106471D01*
X502251Y106006D01*
X502136Y105593D01*
X501983Y105283D01*
X501753Y105024D01*
X501446Y104921D01*
X501139Y105024D01*
X500909Y105283D01*
X500756Y105593D01*
X500641Y106006D01*
X500603Y106471D01*
X500641Y106936D01*
X500756Y107349D01*
X500909Y107659D01*
X501139Y107918D01*
X501446Y108021D01*
G01X499189Y105386D02*
X498959Y105128D01*
X498691Y104973D01*
X498346Y104921D01*
X498001Y105024D01*
X497733Y105231D01*
X497541Y105593D01*
X497503Y106006D01*
X497579Y106419D01*
X497771Y106678D01*
X498039Y106884D01*
X498308Y106936D01*
X498576Y106884D01*
X498921Y106678D01*
X498806Y108021D01*
X497771D01*
G01X511513Y100699D02*
Y103799D01*
X510554D01*
X510248Y103644D01*
X510056Y103437D01*
X509979Y103024D01*
X510056Y102611D01*
X510286Y102352D01*
X510554Y102197D01*
X511513D01*
G01X510554D02*
X509979Y100699D01*
G01X507646D02*
Y103799D01*
X508106Y103179D01*
G01Y100699D02*
X507186D01*
G01X505274Y103282D02*
X505044Y103592D01*
X504776Y103747D01*
X504469Y103799D01*
X504086Y103696D01*
X503818Y103437D01*
X503741Y103127D01*
X503779Y102817D01*
X503933Y102559D01*
X504699Y102042D01*
X505044Y101681D01*
X505274Y101164D01*
X505351Y100699D01*
X503741D01*
G01X501446Y103799D02*
X501753Y103696D01*
X501983Y103437D01*
X502136Y103127D01*
X502251Y102714D01*
X502289Y102249D01*
X502251Y101784D01*
X502136Y101371D01*
X501983Y101061D01*
X501753Y100802D01*
X501446Y100699D01*
X501139Y100802D01*
X500909Y101061D01*
X500756Y101371D01*
X500641Y101784D01*
X500603Y102249D01*
X500641Y102714D01*
X500756Y103127D01*
X500909Y103437D01*
X501139Y103696D01*
X501446Y103799D01*
G01X498346Y100699D02*
X498078Y100751D01*
X497771Y100906D01*
X497579Y101164D01*
X497503Y101526D01*
X497579Y101887D01*
X497809Y102197D01*
X498154Y102352D01*
X498538D01*
X498768Y102456D01*
X498959Y102714D01*
X499036Y103076D01*
X498921Y103437D01*
X498653Y103696D01*
X498346Y103799D01*
X498039Y103696D01*
X497771Y103437D01*
X497656Y103076D01*
X497733Y102714D01*
X497924Y102456D01*
X498154Y102352D01*
X498538D01*
X498883Y102197D01*
X499113Y101887D01*
X499189Y101526D01*
X499113Y101164D01*
X498921Y100906D01*
X498614Y100751D01*
X498346Y100699D01*
G01X507223Y134943D02*
Y126229D01*
G01X509799Y139285D02*
X503599D01*
G01D02*
Y136087D01*
G01D02*
X509799D01*
G01D02*
Y139285D01*
G01X497374Y127066D02*
Y130266D01*
G01X509799Y152286D02*
X503599D01*
G01D02*
Y149086D01*
G01D02*
X509799D01*
G01D02*
Y152286D01*
G01X503599Y145086D02*
X509799D01*
G01D02*
Y148286D01*
G01D02*
X503599D01*
G01D02*
Y145086D01*
G01X509799Y143786D02*
X503599D01*
G01D02*
Y140586D01*
G01D02*
X509799D01*
G01D02*
Y143786D01*
G01X499200Y164200D02*
Y172400D01*
X500100Y170800D01*
X498200D01*
X499100Y172500D01*
G01X518417Y166000D02*
Y169100D01*
X517458D01*
X517152Y168945D01*
X516960Y168738D01*
X516883Y168325D01*
X516960Y167912D01*
X517190Y167653D01*
X517458Y167498D01*
X518417D01*
G01X517458D02*
X516883Y166000D01*
G01X514550D02*
Y169100D01*
X515010Y168480D01*
G01Y166000D02*
X514090D01*
G01X511450Y169100D02*
X511757Y168997D01*
X511987Y168738D01*
X512140Y168428D01*
X512255Y168015D01*
X512293Y167550D01*
X512255Y167085D01*
X512140Y166672D01*
X511987Y166362D01*
X511757Y166103D01*
X511450Y166000D01*
X511143Y166103D01*
X510913Y166362D01*
X510760Y166672D01*
X510645Y167085D01*
X510607Y167550D01*
X510645Y168015D01*
X510760Y168428D01*
X510913Y168738D01*
X511143Y168997D01*
X511450Y169100D01*
G01X508427Y166000D02*
X508350Y166672D01*
X508235Y167240D01*
X508082Y167757D01*
X507890Y168325D01*
X507583Y169100D01*
X509117D01*
G01X505902Y166362D02*
X505633Y166103D01*
X505327Y166000D01*
X505020Y166103D01*
X504752Y166413D01*
X504560Y166878D01*
X504483Y167343D01*
Y167912D01*
X504560Y168377D01*
X504752Y168790D01*
X504982Y168997D01*
X505250Y169100D01*
X505557Y168997D01*
X505787Y168790D01*
X505940Y168480D01*
X506017Y168067D01*
X505940Y167705D01*
X505748Y167343D01*
X505518Y167137D01*
X505250Y167085D01*
X504943Y167188D01*
X504713Y167447D01*
X504483Y167912D01*
G01X518217Y162100D02*
Y165200D01*
X517258D01*
X516952Y165045D01*
X516760Y164838D01*
X516683Y164425D01*
X516760Y164012D01*
X516990Y163753D01*
X517258Y163598D01*
X518217D01*
G01X517258D02*
X516683Y162100D01*
G01X514350D02*
Y165200D01*
X514810Y164580D01*
G01Y162100D02*
X513890D01*
G01X511250Y165200D02*
X511557Y165097D01*
X511787Y164838D01*
X511940Y164528D01*
X512055Y164115D01*
X512093Y163650D01*
X512055Y163185D01*
X511940Y162772D01*
X511787Y162462D01*
X511557Y162203D01*
X511250Y162100D01*
X510943Y162203D01*
X510713Y162462D01*
X510560Y162772D01*
X510445Y163185D01*
X510407Y163650D01*
X510445Y164115D01*
X510560Y164528D01*
X510713Y164838D01*
X510943Y165097D01*
X511250Y165200D01*
G01X508150Y162100D02*
X507882Y162152D01*
X507575Y162307D01*
X507383Y162565D01*
X507307Y162927D01*
X507383Y163288D01*
X507613Y163598D01*
X507958Y163753D01*
X508342D01*
X508572Y163857D01*
X508763Y164115D01*
X508840Y164477D01*
X508725Y164838D01*
X508457Y165097D01*
X508150Y165200D01*
X507843Y165097D01*
X507575Y164838D01*
X507460Y164477D01*
X507537Y164115D01*
X507728Y163857D01*
X507958Y163753D01*
X508342D01*
X508687Y163598D01*
X508917Y163288D01*
X508993Y162927D01*
X508917Y162565D01*
X508725Y162307D01*
X508418Y162152D01*
X508150Y162100D01*
G01X505050D02*
Y165200D01*
X505510Y164580D01*
G01Y162100D02*
X504590D01*
G01X499319Y156161D02*
Y159361D01*
G01Y160661D02*
Y163861D01*
G01X509517Y182800D02*
Y185900D01*
X508558D01*
X508252Y185745D01*
X508060Y185538D01*
X507983Y185125D01*
X508060Y184712D01*
X508290Y184453D01*
X508558Y184298D01*
X509517D01*
G01X508558D02*
X507983Y182800D01*
G01X505650D02*
Y185900D01*
X506110Y185280D01*
G01Y182800D02*
X505190D01*
G01X503393Y183420D02*
X503163Y183058D01*
X502857Y182852D01*
X502512Y182800D01*
X502205Y182852D01*
X501898Y183110D01*
X501707Y183420D01*
X501668Y183730D01*
X501745Y184092D01*
X502013Y184350D01*
X502282Y184453D01*
X502627D01*
G01X502282D02*
X502052Y184608D01*
X501860Y184867D01*
X501783Y185177D01*
X501860Y185487D01*
X502052Y185745D01*
X502397Y185900D01*
X502742Y185848D01*
X503087Y185642D01*
G01X500178Y185383D02*
X499948Y185693D01*
X499680Y185848D01*
X499373Y185900D01*
X498990Y185797D01*
X498722Y185538D01*
X498645Y185228D01*
X498683Y184918D01*
X498837Y184660D01*
X499603Y184143D01*
X499948Y183782D01*
X500178Y183265D01*
X500255Y182800D01*
X498645D01*
G01X497193Y183265D02*
X496963Y183007D01*
X496695Y182852D01*
X496350Y182800D01*
X496005Y182903D01*
X495737Y183110D01*
X495545Y183472D01*
X495507Y183885D01*
X495583Y184298D01*
X495775Y184557D01*
X496043Y184763D01*
X496312Y184815D01*
X496580Y184763D01*
X496925Y184557D01*
X496810Y185900D01*
X495775D01*
G01X503025Y200200D02*
X509225D01*
Y203400D01*
X503025D01*
Y200200D01*
G01X502500Y211907D02*
X500278D01*
X499813Y212060D01*
X499503Y212367D01*
X499400Y212750D01*
X499503Y213133D01*
X499813Y213440D01*
X500278Y213593D01*
X502500D01*
G01X499400Y215850D02*
X502500D01*
X501880Y215390D01*
G01X499400D02*
Y216310D01*
G01Y219410D02*
X502500D01*
X500278Y217992D01*
Y219908D01*
G01X500692Y221322D02*
X501053Y221590D01*
X501260Y221820D01*
X501363Y222127D01*
X501260Y222395D01*
X501053Y222587D01*
X500743Y222740D01*
X500382Y222778D01*
X500072Y222740D01*
X499762Y222587D01*
X499503Y222357D01*
X499400Y222088D01*
X499503Y221782D01*
X499813Y221513D01*
X500278Y221360D01*
X500795Y221322D01*
X501467Y221398D01*
X501828Y221513D01*
X502190Y221705D01*
X502448Y221973D01*
X502500Y222242D01*
X502397Y222510D01*
X502138Y222702D01*
G01X503100Y224200D02*
Y210800D01*
G01D02*
X511900D01*
G01Y218500D02*
X510300Y217500D01*
X511900Y216500D01*
G01Y224200D02*
X503100D01*
G01X500400Y237100D02*
Y230900D01*
X503600D01*
Y237100D01*
X500400D01*
G01X507600Y230900D02*
Y237100D01*
X504400D01*
Y230900D01*
X507600D01*
G01X508400Y237100D02*
Y230900D01*
X511600D01*
Y237100D01*
X508400D01*
G01X500500Y238883D02*
X503600D01*
Y239842D01*
X503445Y240148D01*
X503238Y240340D01*
X502825Y240417D01*
X502412Y240340D01*
X502153Y240110D01*
X501998Y239842D01*
Y238883D01*
G01Y239842D02*
X500500Y240417D01*
G01Y242750D02*
X503600D01*
X502980Y242290D01*
G01X500500D02*
Y243210D01*
G01X501120Y245007D02*
X500758Y245237D01*
X500552Y245543D01*
X500500Y245888D01*
X500552Y246195D01*
X500810Y246502D01*
X501120Y246693D01*
X501430Y246732D01*
X501792Y246655D01*
X502050Y246387D01*
X502153Y246118D01*
Y245773D01*
G01Y246118D02*
X502308Y246348D01*
X502567Y246540D01*
X502877Y246617D01*
X503187Y246540D01*
X503445Y246348D01*
X503600Y246003D01*
X503548Y245658D01*
X503342Y245313D01*
G01X503083Y248222D02*
X503393Y248452D01*
X503548Y248720D01*
X503600Y249027D01*
X503497Y249410D01*
X503238Y249678D01*
X502928Y249755D01*
X502618Y249717D01*
X502360Y249563D01*
X501843Y248797D01*
X501482Y248452D01*
X500965Y248222D01*
X500500Y248145D01*
Y249755D01*
G01Y252050D02*
X500552Y252318D01*
X500707Y252625D01*
X500965Y252817D01*
X501327Y252893D01*
X501688Y252817D01*
X501998Y252587D01*
X502153Y252242D01*
Y251858D01*
X502257Y251628D01*
X502515Y251437D01*
X502877Y251360D01*
X503238Y251475D01*
X503497Y251743D01*
X503600Y252050D01*
X503497Y252357D01*
X503238Y252625D01*
X502877Y252740D01*
X502515Y252663D01*
X502257Y252472D01*
X502153Y252242D01*
Y251858D01*
X501998Y251513D01*
X501688Y251283D01*
X501327Y251207D01*
X500965Y251283D01*
X500707Y251475D01*
X500552Y251782D01*
X500500Y252050D01*
G01X504500Y238883D02*
X507600D01*
Y239842D01*
X507445Y240148D01*
X507238Y240340D01*
X506825Y240417D01*
X506412Y240340D01*
X506153Y240110D01*
X505998Y239842D01*
Y238883D01*
G01Y239842D02*
X504500Y240417D01*
G01Y242750D02*
X507600D01*
X506980Y242290D01*
G01X504500D02*
Y243210D01*
G01X505120Y245007D02*
X504758Y245237D01*
X504552Y245543D01*
X504500Y245888D01*
X504552Y246195D01*
X504810Y246502D01*
X505120Y246693D01*
X505430Y246732D01*
X505792Y246655D01*
X506050Y246387D01*
X506153Y246118D01*
Y245773D01*
G01Y246118D02*
X506308Y246348D01*
X506567Y246540D01*
X506877Y246617D01*
X507187Y246540D01*
X507445Y246348D01*
X507600Y246003D01*
X507548Y245658D01*
X507342Y245313D01*
G01X507083Y248222D02*
X507393Y248452D01*
X507548Y248720D01*
X507600Y249027D01*
X507497Y249410D01*
X507238Y249678D01*
X506928Y249755D01*
X506618Y249717D01*
X506360Y249563D01*
X505843Y248797D01*
X505482Y248452D01*
X504965Y248222D01*
X504500Y248145D01*
Y249755D01*
G01Y251973D02*
X505172Y252050D01*
X505740Y252165D01*
X506257Y252318D01*
X506825Y252510D01*
X507600Y252817D01*
Y251283D01*
G01X509000Y239383D02*
X512100D01*
Y240342D01*
X511945Y240648D01*
X511738Y240840D01*
X511325Y240917D01*
X510912Y240840D01*
X510653Y240610D01*
X510498Y240342D01*
Y239383D01*
G01Y240342D02*
X509000Y240917D01*
G01Y243250D02*
X512100D01*
X511480Y242790D01*
G01X509000D02*
Y243710D01*
G01X509620Y245507D02*
X509258Y245737D01*
X509052Y246043D01*
X509000Y246388D01*
X509052Y246695D01*
X509310Y247002D01*
X509620Y247193D01*
X509930Y247232D01*
X510292Y247155D01*
X510550Y246887D01*
X510653Y246618D01*
Y246273D01*
G01Y246618D02*
X510808Y246848D01*
X511067Y247040D01*
X511377Y247117D01*
X511687Y247040D01*
X511945Y246848D01*
X512100Y246503D01*
X512048Y246158D01*
X511842Y245813D01*
G01X509620Y248607D02*
X509258Y248837D01*
X509052Y249143D01*
X509000Y249488D01*
X509052Y249795D01*
X509310Y250102D01*
X509620Y250293D01*
X509930Y250332D01*
X510292Y250255D01*
X510550Y249987D01*
X510653Y249718D01*
Y249373D01*
G01Y249718D02*
X510808Y249948D01*
X511067Y250140D01*
X511377Y250217D01*
X511687Y250140D01*
X511945Y249948D01*
X512100Y249603D01*
X512048Y249258D01*
X511842Y248913D01*
G01X512100Y252550D02*
X511997Y252243D01*
X511738Y252013D01*
X511428Y251860D01*
X511015Y251745D01*
X510550Y251707D01*
X510085Y251745D01*
X509672Y251860D01*
X509362Y252013D01*
X509103Y252243D01*
X509000Y252550D01*
X509103Y252857D01*
X509362Y253087D01*
X509672Y253240D01*
X510085Y253355D01*
X510550Y253393D01*
X511015Y253355D01*
X511428Y253240D01*
X511738Y253087D01*
X511997Y252857D01*
X512100Y252550D01*
G01X505531Y452638D02*
X505761Y452793D01*
X506029Y452896D01*
X506336D01*
X506681Y452741D01*
X506949Y452483D01*
X507141Y452173D01*
X507294Y451656D01*
X507332Y451191D01*
X507256Y450726D01*
X507141Y450416D01*
X506911Y450106D01*
X506642Y449899D01*
X506374Y449796D01*
X506106D01*
X505837Y449899D01*
X505607Y450054D01*
X505416Y450261D01*
G01X503274Y449796D02*
Y452896D01*
X503734Y452276D01*
G01Y449796D02*
X502814D01*
G01X505702Y453690D02*
X515902D01*
G01X505702Y458290D02*
Y453690D01*
G01X513338Y464823D02*
X507138D01*
G01D02*
Y461623D01*
G01D02*
X513338D01*
G01X510238Y461723D02*
Y464723D01*
G01X513338Y470323D02*
X507138D01*
G01D02*
Y467123D01*
G01D02*
X513338D01*
G01X510238Y467223D02*
Y470223D01*
G01X515902Y458290D02*
X505702D01*
G01X500163Y462041D02*
X496963D01*
G01X500163Y455841D02*
Y462041D01*
G01X496963Y455841D02*
X500163D01*
G01X496963Y462041D02*
Y455841D01*
G01X498241Y496574D02*
Y481574D01*
G01X505041D02*
Y496574D01*
G01X498341Y481574D02*
X504941D01*
G01X514173Y485792D02*
X514328Y485562D01*
X514431Y485294D01*
Y484987D01*
X514276Y484642D01*
X514018Y484374D01*
X513708Y484182D01*
X513191Y484029D01*
X512726Y483991D01*
X512261Y484067D01*
X511951Y484182D01*
X511641Y484412D01*
X511434Y484681D01*
X511331Y484949D01*
Y485217D01*
X511434Y485486D01*
X511589Y485716D01*
X511796Y485907D01*
G01X511693Y487397D02*
X511434Y487666D01*
X511331Y487972D01*
X511434Y488279D01*
X511744Y488547D01*
X512209Y488739D01*
X512674Y488816D01*
X513243D01*
X513708Y488739D01*
X514121Y488547D01*
X514328Y488317D01*
X514431Y488049D01*
X514328Y487742D01*
X514121Y487512D01*
X513811Y487359D01*
X513398Y487282D01*
X513036Y487359D01*
X512674Y487551D01*
X512468Y487781D01*
X512416Y488049D01*
X512519Y488356D01*
X512778Y488586D01*
X513243Y488816D01*
G01X506138Y482100D02*
X510738D01*
G01X506138Y492300D02*
Y482100D01*
G01X496365Y484125D02*
Y494325D01*
G01X503996Y497809D02*
X500896D01*
Y499343D01*
G01X501516Y500833D02*
X501154Y501063D01*
X500948Y501369D01*
X500896Y501714D01*
X500948Y502021D01*
X501206Y502328D01*
X501516Y502519D01*
X501826Y502558D01*
X502188Y502481D01*
X502446Y502213D01*
X502549Y501944D01*
Y501599D01*
G01Y501944D02*
X502704Y502174D01*
X502963Y502366D01*
X503273Y502443D01*
X503583Y502366D01*
X503841Y502174D01*
X503996Y501829D01*
X503944Y501484D01*
X503738Y501139D01*
G01X498341Y488574D02*
X504941D01*
G01X498341Y496574D02*
X504941D01*
G01X498341Y489574D02*
X504941D01*
G01X510738Y492300D02*
X506138D01*
G01Y487200D02*
X510738D01*
G01X509400Y516943D02*
X509555Y516713D01*
X509658Y516445D01*
Y516138D01*
X509503Y515793D01*
X509245Y515525D01*
X508935Y515333D01*
X508418Y515180D01*
X507953Y515142D01*
X507488Y515218D01*
X507178Y515333D01*
X506868Y515563D01*
X506661Y515832D01*
X506558Y516100D01*
Y516368D01*
X506661Y516637D01*
X506816Y516867D01*
X507023Y517058D01*
G01X506558Y519200D02*
X509658D01*
X509038Y518740D01*
G01X506558D02*
Y519660D01*
G01X506920Y521648D02*
X506661Y521917D01*
X506558Y522223D01*
X506661Y522530D01*
X506971Y522798D01*
X507436Y522990D01*
X507901Y523067D01*
X508470D01*
X508935Y522990D01*
X509348Y522798D01*
X509555Y522568D01*
X509658Y522300D01*
X509555Y521993D01*
X509348Y521763D01*
X509038Y521610D01*
X508625Y521533D01*
X508263Y521610D01*
X507901Y521802D01*
X507695Y522032D01*
X507643Y522300D01*
X507746Y522607D01*
X508005Y522837D01*
X508470Y523067D01*
G01X507178Y524557D02*
X506816Y524787D01*
X506610Y525093D01*
X506558Y525438D01*
X506610Y525745D01*
X506868Y526052D01*
X507178Y526243D01*
X507488Y526282D01*
X507850Y526205D01*
X508108Y525937D01*
X508211Y525668D01*
Y525323D01*
G01Y525668D02*
X508366Y525898D01*
X508625Y526090D01*
X508935Y526167D01*
X509245Y526090D01*
X509503Y525898D01*
X509658Y525553D01*
X509606Y525208D01*
X509400Y524863D01*
G01X513370Y516943D02*
X513525Y516713D01*
X513628Y516445D01*
Y516138D01*
X513473Y515793D01*
X513215Y515525D01*
X512905Y515333D01*
X512388Y515180D01*
X511923Y515142D01*
X511458Y515218D01*
X511148Y515333D01*
X510838Y515563D01*
X510631Y515832D01*
X510528Y516100D01*
Y516368D01*
X510631Y516637D01*
X510786Y516867D01*
X510993Y517058D01*
G01X510528Y519200D02*
X513628D01*
X513008Y518740D01*
G01X510528D02*
Y519660D01*
G01X510890Y521648D02*
X510631Y521917D01*
X510528Y522223D01*
X510631Y522530D01*
X510941Y522798D01*
X511406Y522990D01*
X511871Y523067D01*
X512440D01*
X512905Y522990D01*
X513318Y522798D01*
X513525Y522568D01*
X513628Y522300D01*
X513525Y521993D01*
X513318Y521763D01*
X513008Y521610D01*
X512595Y521533D01*
X512233Y521610D01*
X511871Y521802D01*
X511665Y522032D01*
X511613Y522300D01*
X511716Y522607D01*
X511975Y522837D01*
X512440Y523067D01*
G01X513111Y524672D02*
X513421Y524902D01*
X513576Y525170D01*
X513628Y525477D01*
X513525Y525860D01*
X513266Y526128D01*
X512956Y526205D01*
X512646Y526167D01*
X512388Y526013D01*
X511871Y525247D01*
X511510Y524902D01*
X510993Y524672D01*
X510528Y524595D01*
Y526205D01*
G01X502575Y517359D02*
X502730Y517129D01*
X502833Y516861D01*
Y516554D01*
X502678Y516209D01*
X502420Y515941D01*
X502110Y515749D01*
X501593Y515596D01*
X501128Y515558D01*
X500663Y515634D01*
X500353Y515749D01*
X500043Y515979D01*
X499836Y516248D01*
X499733Y516516D01*
Y516784D01*
X499836Y517053D01*
X499991Y517283D01*
X500198Y517474D01*
G01X499733Y519616D02*
X499785Y519884D01*
X499940Y520191D01*
X500198Y520383D01*
X500560Y520459D01*
X500921Y520383D01*
X501231Y520153D01*
X501386Y519808D01*
Y519424D01*
X501490Y519194D01*
X501748Y519003D01*
X502110Y518926D01*
X502471Y519041D01*
X502730Y519309D01*
X502833Y519616D01*
X502730Y519923D01*
X502471Y520191D01*
X502110Y520306D01*
X501748Y520229D01*
X501490Y520038D01*
X501386Y519808D01*
Y519424D01*
X501231Y519079D01*
X500921Y518849D01*
X500560Y518773D01*
X500198Y518849D01*
X499940Y519041D01*
X499785Y519348D01*
X499733Y519616D01*
G01X501025Y521988D02*
X501386Y522256D01*
X501593Y522486D01*
X501696Y522793D01*
X501593Y523061D01*
X501386Y523253D01*
X501076Y523406D01*
X500715Y523444D01*
X500405Y523406D01*
X500095Y523253D01*
X499836Y523023D01*
X499733Y522754D01*
X499836Y522448D01*
X500146Y522179D01*
X500611Y522026D01*
X501128Y521988D01*
X501800Y522064D01*
X502161Y522179D01*
X502523Y522371D01*
X502781Y522639D01*
X502833Y522908D01*
X502730Y523176D01*
X502471Y523368D01*
G01X500198Y524973D02*
X499940Y525203D01*
X499785Y525471D01*
X499733Y525816D01*
X499836Y526161D01*
X500043Y526429D01*
X500405Y526621D01*
X500818Y526659D01*
X501231Y526583D01*
X501490Y526391D01*
X501696Y526123D01*
X501748Y525854D01*
X501696Y525586D01*
X501490Y525241D01*
X502833Y525356D01*
Y526391D01*
G01X503538Y532505D02*
Y538705D01*
G01X500338Y532505D02*
X503538D01*
G01X500338Y538705D02*
Y532505D01*
G01X508438Y538365D02*
X505438D01*
G01X508538Y541465D02*
X505338D01*
G01X508538Y535265D02*
Y541465D01*
G01X505338Y535265D02*
X508538D01*
G01X505338Y541465D02*
Y535265D01*
G01X512438Y538365D02*
X509438D01*
G01X512538Y541465D02*
X509338D01*
G01Y535265D02*
X512538D01*
G01X509338Y541465D02*
Y535265D01*
G01X497338Y542325D02*
Y548525D01*
G01X503438Y535605D02*
X500438D01*
G01X503538Y538705D02*
X500338D01*
G01X495538Y564525D02*
Y561525D01*
G01X498638Y561425D02*
Y564625D01*
G01X497938Y554225D02*
Y560425D01*
G01X502338Y554625D02*
X512538D01*
G01X502338Y559225D02*
Y554625D01*
G01X512538Y559225D02*
X502338D01*
G01X507438D02*
Y554625D01*
G01X507938Y560125D02*
Y564725D01*
G01X502338Y559925D02*
Y564925D01*
G01X512538D02*
X502338D01*
G01X506938Y560125D02*
Y564725D01*
G01X502338Y559925D02*
X512538D01*
G01X514470Y572338D02*
X514625Y572108D01*
X514728Y571840D01*
Y571533D01*
X514573Y571188D01*
X514315Y570920D01*
X514005Y570728D01*
X513488Y570575D01*
X513023Y570537D01*
X512558Y570613D01*
X512248Y570728D01*
X511938Y570958D01*
X511731Y571227D01*
X511628Y571495D01*
Y571763D01*
X511731Y572032D01*
X511886Y572262D01*
X512093Y572453D01*
G01X511990Y573943D02*
X511731Y574212D01*
X511628Y574518D01*
X511731Y574825D01*
X512041Y575093D01*
X512506Y575285D01*
X512971Y575362D01*
X513540D01*
X514005Y575285D01*
X514418Y575093D01*
X514625Y574863D01*
X514728Y574595D01*
X514625Y574288D01*
X514418Y574058D01*
X514108Y573905D01*
X513695Y573828D01*
X513333Y573905D01*
X512971Y574097D01*
X512765Y574327D01*
X512713Y574595D01*
X512816Y574902D01*
X513075Y575132D01*
X513540Y575362D01*
G01X512248Y576852D02*
X511886Y577082D01*
X511680Y577388D01*
X511628Y577733D01*
X511680Y578040D01*
X511938Y578347D01*
X512248Y578538D01*
X512558Y578577D01*
X512920Y578500D01*
X513178Y578232D01*
X513281Y577963D01*
Y577618D01*
G01Y577963D02*
X513436Y578193D01*
X513695Y578385D01*
X514005Y578462D01*
X514315Y578385D01*
X514573Y578193D01*
X514728Y577848D01*
X514676Y577503D01*
X514470Y577158D01*
G01X514211Y580067D02*
X514521Y580297D01*
X514676Y580565D01*
X514728Y580872D01*
X514625Y581255D01*
X514366Y581523D01*
X514056Y581600D01*
X513746Y581562D01*
X513488Y581408D01*
X512971Y580642D01*
X512610Y580297D01*
X512093Y580067D01*
X511628Y579990D01*
Y581600D01*
G01X505128Y570215D02*
X502128D01*
G01X505228Y573315D02*
X502028D01*
G01X505228Y567115D02*
Y573315D01*
G01X502028Y567115D02*
X505228D01*
G01X502028Y573315D02*
Y567115D01*
G01X509028Y570215D02*
X506028D01*
G01X509128Y573315D02*
X505928D01*
G01X509128Y567115D02*
Y573315D01*
G01X505928Y567115D02*
X509128D01*
G01X505928Y573315D02*
Y567115D01*
G01X495638Y569325D02*
Y566325D01*
G01X498738Y566225D02*
Y569425D01*
G01Y570125D02*
Y573325D01*
G01X495638Y573225D02*
Y570225D01*
G01Y581025D02*
Y578025D01*
G01X498738Y577925D02*
Y581125D01*
G01X495638Y577125D02*
Y574125D01*
G01X498738Y574025D02*
Y577225D01*
G01X506738Y592625D02*
Y598825D01*
G01X503538D02*
Y592625D01*
G01X506638Y595725D02*
X503638D01*
G01X503538Y592625D02*
X506738D01*
G01X515998Y587901D02*
X516228Y588056D01*
X516496Y588159D01*
X516803D01*
X517148Y588004D01*
X517416Y587746D01*
X517608Y587436D01*
X517761Y586919D01*
X517799Y586454D01*
X517723Y585989D01*
X517608Y585679D01*
X517378Y585369D01*
X517109Y585162D01*
X516841Y585059D01*
X516573D01*
X516304Y585162D01*
X516074Y585317D01*
X515883Y585524D01*
G01X513741Y585059D02*
X513473Y585111D01*
X513166Y585266D01*
X512974Y585524D01*
X512898Y585886D01*
X512974Y586247D01*
X513204Y586557D01*
X513549Y586712D01*
X513933D01*
X514163Y586816D01*
X514354Y587074D01*
X514431Y587436D01*
X514316Y587797D01*
X514048Y588056D01*
X513741Y588159D01*
X513434Y588056D01*
X513166Y587797D01*
X513051Y587436D01*
X513128Y587074D01*
X513319Y586816D01*
X513549Y586712D01*
X513933D01*
X514278Y586557D01*
X514508Y586247D01*
X514584Y585886D01*
X514508Y585524D01*
X514316Y585266D01*
X514009Y585111D01*
X513741Y585059D01*
G01X510718D02*
X510641Y585731D01*
X510526Y586299D01*
X510373Y586816D01*
X510181Y587384D01*
X509874Y588159D01*
X511408D01*
G01X507541Y585059D02*
Y588159D01*
X508001Y587539D01*
G01Y585059D02*
X507081D01*
G01X495280Y591936D02*
Y596536D01*
G01X508817Y605379D02*
X509047Y605534D01*
X509315Y605637D01*
X509622D01*
X509967Y605482D01*
X510235Y605224D01*
X510427Y604914D01*
X510580Y604397D01*
X510618Y603932D01*
X510542Y603467D01*
X510427Y603157D01*
X510197Y602847D01*
X509928Y602640D01*
X509660Y602537D01*
X509392D01*
X509123Y602640D01*
X508893Y602795D01*
X508702Y603002D01*
G01X506560Y602537D02*
X506292Y602589D01*
X505985Y602744D01*
X505793Y603002D01*
X505717Y603364D01*
X505793Y603725D01*
X506023Y604035D01*
X506368Y604190D01*
X506752D01*
X506982Y604294D01*
X507173Y604552D01*
X507250Y604914D01*
X507135Y605275D01*
X506867Y605534D01*
X506560Y605637D01*
X506253Y605534D01*
X505985Y605275D01*
X505870Y604914D01*
X505947Y604552D01*
X506138Y604294D01*
X506368Y604190D01*
X506752D01*
X507097Y604035D01*
X507327Y603725D01*
X507403Y603364D01*
X507327Y603002D01*
X507135Y602744D01*
X506828Y602589D01*
X506560Y602537D01*
G01X503537D02*
X503460Y603209D01*
X503345Y603777D01*
X503192Y604294D01*
X503000Y604862D01*
X502693Y605637D01*
X504227D01*
G01X501088Y605120D02*
X500858Y605430D01*
X500590Y605585D01*
X500283Y605637D01*
X499900Y605534D01*
X499632Y605275D01*
X499555Y604965D01*
X499593Y604655D01*
X499747Y604397D01*
X500513Y603880D01*
X500858Y603519D01*
X501088Y603002D01*
X501165Y602537D01*
X499555D01*
G01X506738Y598825D02*
X503538D01*
G01X506117Y622011D02*
Y624511D01*
X505583D01*
X505370Y624386D01*
X505210Y624219D01*
X505077Y623969D01*
X504970Y623678D01*
X504943Y623261D01*
X504970Y622844D01*
X505077Y622553D01*
X505210Y622303D01*
X505370Y622136D01*
X505583Y622011D01*
X506117D01*
G01X495890Y640729D02*
Y625729D01*
G01X508890D02*
Y640729D01*
G01X495890Y625729D02*
X508890D01*
G01X511043Y640712D02*
X510830Y640504D01*
X510590Y640379D01*
X510376D01*
X510163Y640504D01*
X510003Y640712D01*
X509923Y641004D01*
X509976Y641296D01*
X510110Y641546D01*
X510350Y641712D01*
X510670Y641796D01*
X510856Y641962D01*
X510936Y642254D01*
X510883Y642546D01*
X510750Y642754D01*
X510563Y642879D01*
X510376D01*
X510190Y642796D01*
X510030Y642587D01*
G01X508890Y640729D02*
X495890D01*
G01X508392Y653407D02*
X514592D01*
G01X508392Y656607D02*
Y653407D01*
G01X514592Y656607D02*
X508392D01*
G01X512707Y660999D02*
Y664099D01*
X511748D01*
X511442Y663944D01*
X511250Y663737D01*
X511173Y663324D01*
X511250Y662911D01*
X511480Y662652D01*
X511748Y662497D01*
X512707D01*
G01X511748D02*
X511173Y660999D01*
G01X509492Y661361D02*
X509223Y661102D01*
X508917Y660999D01*
X508610Y661102D01*
X508342Y661412D01*
X508150Y661877D01*
X508073Y662342D01*
Y662911D01*
X508150Y663376D01*
X508342Y663789D01*
X508572Y663996D01*
X508840Y664099D01*
X509147Y663996D01*
X509377Y663789D01*
X509530Y663479D01*
X509607Y663066D01*
X509530Y662704D01*
X509338Y662342D01*
X509108Y662136D01*
X508840Y662084D01*
X508533Y662187D01*
X508303Y662446D01*
X508073Y662911D01*
G01X506392Y661361D02*
X506123Y661102D01*
X505817Y660999D01*
X505510Y661102D01*
X505242Y661412D01*
X505050Y661877D01*
X504973Y662342D01*
Y662911D01*
X505050Y663376D01*
X505242Y663789D01*
X505472Y663996D01*
X505740Y664099D01*
X506047Y663996D01*
X506277Y663789D01*
X506430Y663479D01*
X506507Y663066D01*
X506430Y662704D01*
X506238Y662342D01*
X506008Y662136D01*
X505740Y662084D01*
X505433Y662187D01*
X505203Y662446D01*
X504973Y662911D01*
G01X502180Y660999D02*
Y664099D01*
X503598Y661877D01*
X501682D01*
G01X507053Y664797D02*
X513253D01*
G01X507053Y667997D02*
Y664797D01*
G01X513253Y667997D02*
X507053D01*
G01X508359Y668888D02*
X514559D01*
G01X508359Y672088D02*
Y668888D01*
G01X514559Y672088D02*
X508359D01*
G01X506618Y673060D02*
X512818D01*
G01X506618Y676260D02*
Y673060D01*
G01X508298Y677402D02*
X514498D01*
G01X508298Y680602D02*
Y677402D01*
G01X514498Y680602D02*
X508298D01*
G01X512818Y676260D02*
X506618D01*
G01X506742Y747293D02*
X506897Y747063D01*
X507000Y746795D01*
Y746488D01*
X506845Y746143D01*
X506587Y745875D01*
X506277Y745683D01*
X505760Y745530D01*
X505295Y745492D01*
X504830Y745568D01*
X504520Y745683D01*
X504210Y745913D01*
X504003Y746182D01*
X503900Y746450D01*
Y746718D01*
X504003Y746987D01*
X504158Y747217D01*
X504365Y747408D01*
G01X503900Y749473D02*
X504572Y749550D01*
X505140Y749665D01*
X505657Y749818D01*
X506225Y750010D01*
X507000Y750317D01*
Y748783D01*
G01X504520Y751807D02*
X504158Y752037D01*
X503952Y752343D01*
X503900Y752688D01*
X503952Y752995D01*
X504210Y753302D01*
X504520Y753493D01*
X504830Y753532D01*
X505192Y753455D01*
X505450Y753187D01*
X505553Y752918D01*
Y752573D01*
G01Y752918D02*
X505708Y753148D01*
X505967Y753340D01*
X506277Y753417D01*
X506587Y753340D01*
X506845Y753148D01*
X507000Y752803D01*
X506948Y752458D01*
X506742Y752113D01*
G01X503900Y755750D02*
X507000D01*
X506380Y755290D01*
G01X503900D02*
Y756210D01*
G01X507700Y745583D02*
X510800D01*
Y746542D01*
X510645Y746848D01*
X510438Y747040D01*
X510025Y747117D01*
X509612Y747040D01*
X509353Y746810D01*
X509198Y746542D01*
Y745583D01*
G01Y746542D02*
X507700Y747117D01*
G01X508062Y748798D02*
X507803Y749067D01*
X507700Y749373D01*
X507803Y749680D01*
X508113Y749948D01*
X508578Y750140D01*
X509043Y750217D01*
X509612D01*
X510077Y750140D01*
X510490Y749948D01*
X510697Y749718D01*
X510800Y749450D01*
X510697Y749143D01*
X510490Y748913D01*
X510180Y748760D01*
X509767Y748683D01*
X509405Y748760D01*
X509043Y748952D01*
X508837Y749182D01*
X508785Y749450D01*
X508888Y749757D01*
X509147Y749987D01*
X509612Y750217D01*
G01X508992Y751822D02*
X509353Y752090D01*
X509560Y752320D01*
X509663Y752627D01*
X509560Y752895D01*
X509353Y753087D01*
X509043Y753240D01*
X508682Y753278D01*
X508372Y753240D01*
X508062Y753087D01*
X507803Y752857D01*
X507700Y752588D01*
X507803Y752282D01*
X508113Y752013D01*
X508578Y751860D01*
X509095Y751822D01*
X509767Y751898D01*
X510128Y752013D01*
X510490Y752205D01*
X510748Y752473D01*
X510800Y752742D01*
X510697Y753010D01*
X510438Y753202D01*
G01X508165Y754807D02*
X507907Y755037D01*
X507752Y755305D01*
X507700Y755650D01*
X507803Y755995D01*
X508010Y756263D01*
X508372Y756455D01*
X508785Y756493D01*
X509198Y756417D01*
X509457Y756225D01*
X509663Y755957D01*
X509715Y755688D01*
X509663Y755420D01*
X509457Y755075D01*
X510800Y755190D01*
Y756225D01*
G01X509394Y758013D02*
X512494D01*
Y758972D01*
X512339Y759278D01*
X512132Y759470D01*
X511719Y759547D01*
X511306Y759470D01*
X511047Y759240D01*
X510892Y758972D01*
Y758013D01*
G01Y758972D02*
X509394Y759547D01*
G01X509756Y761228D02*
X509497Y761497D01*
X509394Y761803D01*
X509497Y762110D01*
X509807Y762378D01*
X510272Y762570D01*
X510737Y762647D01*
X511306D01*
X511771Y762570D01*
X512184Y762378D01*
X512391Y762148D01*
X512494Y761880D01*
X512391Y761573D01*
X512184Y761343D01*
X511874Y761190D01*
X511461Y761113D01*
X511099Y761190D01*
X510737Y761382D01*
X510531Y761612D01*
X510479Y761880D01*
X510582Y762187D01*
X510841Y762417D01*
X511306Y762647D01*
G01X510686Y764252D02*
X511047Y764520D01*
X511254Y764750D01*
X511357Y765057D01*
X511254Y765325D01*
X511047Y765517D01*
X510737Y765670D01*
X510376Y765708D01*
X510066Y765670D01*
X509756Y765517D01*
X509497Y765287D01*
X509394Y765018D01*
X509497Y764712D01*
X509807Y764443D01*
X510272Y764290D01*
X510789Y764252D01*
X511461Y764328D01*
X511822Y764443D01*
X512184Y764635D01*
X512442Y764903D01*
X512494Y765172D01*
X512391Y765440D01*
X512132Y765632D01*
G01X509394Y768080D02*
X509446Y768348D01*
X509601Y768655D01*
X509859Y768847D01*
X510221Y768923D01*
X510582Y768847D01*
X510892Y768617D01*
X511047Y768272D01*
Y767888D01*
X511151Y767658D01*
X511409Y767467D01*
X511771Y767390D01*
X512132Y767505D01*
X512391Y767773D01*
X512494Y768080D01*
X512391Y768387D01*
X512132Y768655D01*
X511771Y768770D01*
X511409Y768693D01*
X511151Y768502D01*
X511047Y768272D01*
Y767888D01*
X510892Y767543D01*
X510582Y767313D01*
X510221Y767237D01*
X509859Y767313D01*
X509601Y767505D01*
X509446Y767812D01*
X509394Y768080D01*
G01X525900Y782281D02*
X504800D01*
G01X526379Y61123D02*
Y64223D01*
X525420D01*
X525114Y64068D01*
X524922Y63861D01*
X524845Y63448D01*
X524922Y63035D01*
X525152Y62776D01*
X525420Y62621D01*
X526379D01*
G01X525420D02*
X524845Y61123D01*
G01X522512D02*
Y64223D01*
X522972Y63603D01*
G01Y61123D02*
X522052D01*
G01X519412D02*
Y64223D01*
X519872Y63603D01*
G01Y61123D02*
X518952D01*
G01X516312D02*
X516044Y61175D01*
X515737Y61330D01*
X515545Y61588D01*
X515469Y61950D01*
X515545Y62311D01*
X515775Y62621D01*
X516120Y62776D01*
X516504D01*
X516734Y62880D01*
X516925Y63138D01*
X517002Y63500D01*
X516887Y63861D01*
X516619Y64120D01*
X516312Y64223D01*
X516005Y64120D01*
X515737Y63861D01*
X515622Y63500D01*
X515699Y63138D01*
X515890Y62880D01*
X516120Y62776D01*
X516504D01*
X516849Y62621D01*
X517079Y62311D01*
X517155Y61950D01*
X517079Y61588D01*
X516887Y61330D01*
X516580Y61175D01*
X516312Y61123D01*
G01X513940Y62415D02*
X513672Y62776D01*
X513442Y62983D01*
X513135Y63086D01*
X512867Y62983D01*
X512675Y62776D01*
X512522Y62466D01*
X512484Y62105D01*
X512522Y61795D01*
X512675Y61485D01*
X512905Y61226D01*
X513174Y61123D01*
X513480Y61226D01*
X513749Y61536D01*
X513902Y62001D01*
X513940Y62518D01*
X513864Y63190D01*
X513749Y63551D01*
X513557Y63913D01*
X513289Y64171D01*
X513020Y64223D01*
X512752Y64120D01*
X512560Y63861D01*
G01X526379Y77942D02*
Y81042D01*
X525420D01*
X525114Y80887D01*
X524922Y80680D01*
X524845Y80267D01*
X524922Y79854D01*
X525152Y79595D01*
X525420Y79440D01*
X526379D01*
G01X525420D02*
X524845Y77942D01*
G01X522512D02*
Y81042D01*
X522972Y80422D01*
G01Y77942D02*
X522052D01*
G01X519412D02*
Y81042D01*
X519872Y80422D01*
G01Y77942D02*
X518952D01*
G01X516389D02*
X516312Y78614D01*
X516197Y79182D01*
X516044Y79699D01*
X515852Y80267D01*
X515545Y81042D01*
X517079D01*
G01X513864Y78304D02*
X513595Y78045D01*
X513289Y77942D01*
X512982Y78045D01*
X512714Y78355D01*
X512522Y78820D01*
X512445Y79285D01*
Y79854D01*
X512522Y80319D01*
X512714Y80732D01*
X512944Y80939D01*
X513212Y81042D01*
X513519Y80939D01*
X513749Y80732D01*
X513902Y80422D01*
X513979Y80009D01*
X513902Y79647D01*
X513710Y79285D01*
X513480Y79079D01*
X513212Y79027D01*
X512905Y79130D01*
X512675Y79389D01*
X512445Y79854D01*
G01X526379Y65123D02*
Y68223D01*
X525420D01*
X525114Y68068D01*
X524922Y67861D01*
X524845Y67448D01*
X524922Y67035D01*
X525152Y66776D01*
X525420Y66621D01*
X526379D01*
G01X525420D02*
X524845Y65123D01*
G01X522512D02*
Y68223D01*
X522972Y67603D01*
G01Y65123D02*
X522052D01*
G01X519412D02*
Y68223D01*
X519872Y67603D01*
G01Y65123D02*
X518952D01*
G01X516312D02*
X516044Y65175D01*
X515737Y65330D01*
X515545Y65588D01*
X515469Y65950D01*
X515545Y66311D01*
X515775Y66621D01*
X516120Y66776D01*
X516504D01*
X516734Y66880D01*
X516925Y67138D01*
X517002Y67500D01*
X516887Y67861D01*
X516619Y68120D01*
X516312Y68223D01*
X516005Y68120D01*
X515737Y67861D01*
X515622Y67500D01*
X515699Y67138D01*
X515890Y66880D01*
X516120Y66776D01*
X516504D01*
X516849Y66621D01*
X517079Y66311D01*
X517155Y65950D01*
X517079Y65588D01*
X516887Y65330D01*
X516580Y65175D01*
X516312Y65123D01*
G01X512752D02*
Y68223D01*
X514170Y66001D01*
X512254D01*
G01X528517Y73100D02*
Y76200D01*
X527558D01*
X527252Y76045D01*
X527060Y75838D01*
X526983Y75425D01*
X527060Y75012D01*
X527290Y74753D01*
X527558Y74598D01*
X528517D01*
G01X527558D02*
X526983Y73100D01*
G01X524650D02*
Y76200D01*
X525110Y75580D01*
G01Y73100D02*
X524190D01*
G01X521550D02*
Y76200D01*
X522010Y75580D01*
G01Y73100D02*
X521090D01*
G01X518450D02*
X518182Y73152D01*
X517875Y73307D01*
X517683Y73565D01*
X517607Y73927D01*
X517683Y74288D01*
X517913Y74598D01*
X518258Y74753D01*
X518642D01*
X518872Y74857D01*
X519063Y75115D01*
X519140Y75477D01*
X519025Y75838D01*
X518757Y76097D01*
X518450Y76200D01*
X518143Y76097D01*
X517875Y75838D01*
X517760Y75477D01*
X517837Y75115D01*
X518028Y74857D01*
X518258Y74753D01*
X518642D01*
X518987Y74598D01*
X519217Y74288D01*
X519293Y73927D01*
X519217Y73565D01*
X519025Y73307D01*
X518718Y73152D01*
X518450Y73100D01*
G01X515427D02*
X515350Y73772D01*
X515235Y74340D01*
X515082Y74857D01*
X514890Y75425D01*
X514583Y76200D01*
X516117D01*
G01X528917Y68900D02*
Y72000D01*
X527958D01*
X527652Y71845D01*
X527460Y71638D01*
X527383Y71225D01*
X527460Y70812D01*
X527690Y70553D01*
X527958Y70398D01*
X528917D01*
G01X527958D02*
X527383Y68900D01*
G01X525050D02*
Y72000D01*
X525510Y71380D01*
G01Y68900D02*
X524590D01*
G01X521950D02*
Y72000D01*
X522410Y71380D01*
G01Y68900D02*
X521490D01*
G01X518850D02*
X518582Y68952D01*
X518275Y69107D01*
X518083Y69365D01*
X518007Y69727D01*
X518083Y70088D01*
X518313Y70398D01*
X518658Y70553D01*
X519042D01*
X519272Y70657D01*
X519463Y70915D01*
X519540Y71277D01*
X519425Y71638D01*
X519157Y71897D01*
X518850Y72000D01*
X518543Y71897D01*
X518275Y71638D01*
X518160Y71277D01*
X518237Y70915D01*
X518428Y70657D01*
X518658Y70553D01*
X519042D01*
X519387Y70398D01*
X519617Y70088D01*
X519693Y69727D01*
X519617Y69365D01*
X519425Y69107D01*
X519118Y68952D01*
X518850Y68900D01*
G01X516478Y71483D02*
X516248Y71793D01*
X515980Y71948D01*
X515673Y72000D01*
X515290Y71897D01*
X515022Y71638D01*
X514945Y71328D01*
X514983Y71018D01*
X515137Y70760D01*
X515903Y70243D01*
X516248Y69882D01*
X516478Y69365D01*
X516555Y68900D01*
X514945D01*
G01X526379Y81942D02*
Y85042D01*
X525420D01*
X525114Y84887D01*
X524922Y84680D01*
X524845Y84267D01*
X524922Y83854D01*
X525152Y83595D01*
X525420Y83440D01*
X526379D01*
G01X525420D02*
X524845Y81942D01*
G01X522512D02*
Y85042D01*
X522972Y84422D01*
G01Y81942D02*
X522052D01*
G01X519412D02*
Y85042D01*
X519872Y84422D01*
G01Y81942D02*
X518952D01*
G01X516964Y82304D02*
X516695Y82045D01*
X516389Y81942D01*
X516082Y82045D01*
X515814Y82355D01*
X515622Y82820D01*
X515545Y83285D01*
Y83854D01*
X515622Y84319D01*
X515814Y84732D01*
X516044Y84939D01*
X516312Y85042D01*
X516619Y84939D01*
X516849Y84732D01*
X517002Y84422D01*
X517079Y84009D01*
X517002Y83647D01*
X516810Y83285D01*
X516580Y83079D01*
X516312Y83027D01*
X516005Y83130D01*
X515775Y83389D01*
X515545Y83854D01*
G01X513212Y85042D02*
X513519Y84939D01*
X513749Y84680D01*
X513902Y84370D01*
X514017Y83957D01*
X514055Y83492D01*
X514017Y83027D01*
X513902Y82614D01*
X513749Y82304D01*
X513519Y82045D01*
X513212Y81942D01*
X512905Y82045D01*
X512675Y82304D01*
X512522Y82614D01*
X512407Y83027D01*
X512369Y83492D01*
X512407Y83957D01*
X512522Y84370D01*
X512675Y84680D01*
X512905Y84939D01*
X513212Y85042D01*
G01X526379Y89777D02*
Y92877D01*
X525420D01*
X525114Y92722D01*
X524922Y92515D01*
X524845Y92102D01*
X524922Y91689D01*
X525152Y91430D01*
X525420Y91275D01*
X526379D01*
G01X525420D02*
X524845Y89777D01*
G01X522512D02*
Y92877D01*
X522972Y92257D01*
G01Y89777D02*
X522052D01*
G01X519412Y92877D02*
X519719Y92774D01*
X519949Y92515D01*
X520102Y92205D01*
X520217Y91792D01*
X520255Y91327D01*
X520217Y90862D01*
X520102Y90449D01*
X519949Y90139D01*
X519719Y89880D01*
X519412Y89777D01*
X519105Y89880D01*
X518875Y90139D01*
X518722Y90449D01*
X518607Y90862D01*
X518569Y91327D01*
X518607Y91792D01*
X518722Y92205D01*
X518875Y92515D01*
X519105Y92774D01*
X519412Y92877D01*
G01X516312Y89777D02*
X516044Y89829D01*
X515737Y89984D01*
X515545Y90242D01*
X515469Y90604D01*
X515545Y90965D01*
X515775Y91275D01*
X516120Y91430D01*
X516504D01*
X516734Y91534D01*
X516925Y91792D01*
X517002Y92154D01*
X516887Y92515D01*
X516619Y92774D01*
X516312Y92877D01*
X516005Y92774D01*
X515737Y92515D01*
X515622Y92154D01*
X515699Y91792D01*
X515890Y91534D01*
X516120Y91430D01*
X516504D01*
X516849Y91275D01*
X517079Y90965D01*
X517155Y90604D01*
X517079Y90242D01*
X516887Y89984D01*
X516580Y89829D01*
X516312Y89777D01*
G01X513212Y92877D02*
X513519Y92774D01*
X513749Y92515D01*
X513902Y92205D01*
X514017Y91792D01*
X514055Y91327D01*
X514017Y90862D01*
X513902Y90449D01*
X513749Y90139D01*
X513519Y89880D01*
X513212Y89777D01*
X512905Y89880D01*
X512675Y90139D01*
X512522Y90449D01*
X512407Y90862D01*
X512369Y91327D01*
X512407Y91792D01*
X512522Y92205D01*
X512675Y92515D01*
X512905Y92774D01*
X513212Y92877D01*
G01X526379Y85805D02*
Y88905D01*
X525420D01*
X525114Y88750D01*
X524922Y88543D01*
X524845Y88130D01*
X524922Y87717D01*
X525152Y87458D01*
X525420Y87303D01*
X526379D01*
G01X525420D02*
X524845Y85805D01*
G01X522512D02*
Y88905D01*
X522972Y88285D01*
G01Y85805D02*
X522052D01*
G01X519412Y88905D02*
X519719Y88802D01*
X519949Y88543D01*
X520102Y88233D01*
X520217Y87820D01*
X520255Y87355D01*
X520217Y86890D01*
X520102Y86477D01*
X519949Y86167D01*
X519719Y85908D01*
X519412Y85805D01*
X519105Y85908D01*
X518875Y86167D01*
X518722Y86477D01*
X518607Y86890D01*
X518569Y87355D01*
X518607Y87820D01*
X518722Y88233D01*
X518875Y88543D01*
X519105Y88802D01*
X519412Y88905D01*
G01X517040Y87097D02*
X516772Y87458D01*
X516542Y87665D01*
X516235Y87768D01*
X515967Y87665D01*
X515775Y87458D01*
X515622Y87148D01*
X515584Y86787D01*
X515622Y86477D01*
X515775Y86167D01*
X516005Y85908D01*
X516274Y85805D01*
X516580Y85908D01*
X516849Y86218D01*
X517002Y86683D01*
X517040Y87200D01*
X516964Y87872D01*
X516849Y88233D01*
X516657Y88595D01*
X516389Y88853D01*
X516120Y88905D01*
X515852Y88802D01*
X515660Y88543D01*
G01X514055Y86270D02*
X513825Y86012D01*
X513557Y85857D01*
X513212Y85805D01*
X512867Y85908D01*
X512599Y86115D01*
X512407Y86477D01*
X512369Y86890D01*
X512445Y87303D01*
X512637Y87562D01*
X512905Y87768D01*
X513174Y87820D01*
X513442Y87768D01*
X513787Y87562D01*
X513672Y88905D01*
X512637D01*
G01X534345Y122830D02*
Y125930D01*
X533386D01*
X533080Y125775D01*
X532888Y125568D01*
X532811Y125155D01*
X532888Y124742D01*
X533118Y124483D01*
X533386Y124328D01*
X534345D01*
G01X533386D02*
X532811Y122830D01*
G01X530478D02*
Y125930D01*
X530938Y125310D01*
G01Y122830D02*
X530018D01*
G01X528106Y125413D02*
X527876Y125723D01*
X527608Y125878D01*
X527301Y125930D01*
X526918Y125827D01*
X526650Y125568D01*
X526573Y125258D01*
X526611Y124948D01*
X526765Y124690D01*
X527531Y124173D01*
X527876Y123812D01*
X528106Y123295D01*
X528183Y122830D01*
X526573D01*
G01X524278Y125930D02*
X524585Y125827D01*
X524815Y125568D01*
X524968Y125258D01*
X525083Y124845D01*
X525121Y124380D01*
X525083Y123915D01*
X524968Y123502D01*
X524815Y123192D01*
X524585Y122933D01*
X524278Y122830D01*
X523971Y122933D01*
X523741Y123192D01*
X523588Y123502D01*
X523473Y123915D01*
X523435Y124380D01*
X523473Y124845D01*
X523588Y125258D01*
X523741Y125568D01*
X523971Y125827D01*
X524278Y125930D01*
G01X521830Y123192D02*
X521561Y122933D01*
X521255Y122830D01*
X520948Y122933D01*
X520680Y123243D01*
X520488Y123708D01*
X520411Y124173D01*
Y124742D01*
X520488Y125207D01*
X520680Y125620D01*
X520910Y125827D01*
X521178Y125930D01*
X521485Y125827D01*
X521715Y125620D01*
X521868Y125310D01*
X521945Y124897D01*
X521868Y124535D01*
X521676Y124173D01*
X521446Y123967D01*
X521178Y123915D01*
X520871Y124018D01*
X520641Y124277D01*
X520411Y124742D01*
G01X528647Y117113D02*
Y120213D01*
X527688D01*
X527382Y120058D01*
X527190Y119851D01*
X527113Y119438D01*
X527190Y119025D01*
X527420Y118766D01*
X527688Y118611D01*
X528647D01*
G01X527688D02*
X527113Y117113D01*
G01X524857D02*
X524780Y117785D01*
X524665Y118353D01*
X524512Y118870D01*
X524320Y119438D01*
X524013Y120213D01*
X525547D01*
G01X521757Y117113D02*
X521680Y117785D01*
X521565Y118353D01*
X521412Y118870D01*
X521220Y119438D01*
X520913Y120213D01*
X522447D01*
G01X519308Y118405D02*
X519040Y118766D01*
X518810Y118973D01*
X518503Y119076D01*
X518235Y118973D01*
X518043Y118766D01*
X517890Y118456D01*
X517852Y118095D01*
X517890Y117785D01*
X518043Y117475D01*
X518273Y117216D01*
X518542Y117113D01*
X518848Y117216D01*
X519117Y117526D01*
X519270Y117991D01*
X519308Y118508D01*
X519232Y119180D01*
X519117Y119541D01*
X518925Y119903D01*
X518657Y120161D01*
X518388Y120213D01*
X518120Y120110D01*
X517928Y119851D01*
G01X510940Y118912D02*
X517140D01*
Y122112D01*
X510940D01*
Y118912D01*
G01X534345Y126968D02*
Y130068D01*
X533386D01*
X533080Y129913D01*
X532888Y129706D01*
X532811Y129293D01*
X532888Y128880D01*
X533118Y128621D01*
X533386Y128466D01*
X534345D01*
G01X533386D02*
X532811Y126968D01*
G01X530478D02*
Y130068D01*
X530938Y129448D01*
G01Y126968D02*
X530018D01*
G01X528106Y129551D02*
X527876Y129861D01*
X527608Y130016D01*
X527301Y130068D01*
X526918Y129965D01*
X526650Y129706D01*
X526573Y129396D01*
X526611Y129086D01*
X526765Y128828D01*
X527531Y128311D01*
X527876Y127950D01*
X528106Y127433D01*
X528183Y126968D01*
X526573D01*
G01X524278Y130068D02*
X524585Y129965D01*
X524815Y129706D01*
X524968Y129396D01*
X525083Y128983D01*
X525121Y128518D01*
X525083Y128053D01*
X524968Y127640D01*
X524815Y127330D01*
X524585Y127071D01*
X524278Y126968D01*
X523971Y127071D01*
X523741Y127330D01*
X523588Y127640D01*
X523473Y128053D01*
X523435Y128518D01*
X523473Y128983D01*
X523588Y129396D01*
X523741Y129706D01*
X523971Y129965D01*
X524278Y130068D01*
G01X521906Y128260D02*
X521638Y128621D01*
X521408Y128828D01*
X521101Y128931D01*
X520833Y128828D01*
X520641Y128621D01*
X520488Y128311D01*
X520450Y127950D01*
X520488Y127640D01*
X520641Y127330D01*
X520871Y127071D01*
X521140Y126968D01*
X521446Y127071D01*
X521715Y127381D01*
X521868Y127846D01*
X521906Y128363D01*
X521830Y129035D01*
X521715Y129396D01*
X521523Y129758D01*
X521255Y130016D01*
X520986Y130068D01*
X520718Y129965D01*
X520526Y129706D01*
G01X516963Y136092D02*
Y139292D01*
G01D02*
X510763D01*
G01D02*
Y136092D01*
G01D02*
X516963D01*
G01X520076Y155397D02*
X513876D01*
G01Y152197D02*
X520076D01*
G01D02*
Y155397D01*
G01X513876D02*
Y152197D01*
G01X516983Y140589D02*
Y143789D01*
G01D02*
X510783D01*
G01D02*
Y140589D01*
G01D02*
X516983D01*
G01X513850Y158340D02*
X520050D01*
G01D02*
Y161540D01*
G01D02*
X513850D01*
G01D02*
Y158340D01*
G01X523600Y161383D02*
X526700D01*
Y162342D01*
X526545Y162648D01*
X526338Y162840D01*
X525925Y162917D01*
X525512Y162840D01*
X525253Y162610D01*
X525098Y162342D01*
Y161383D01*
G01Y162342D02*
X523600Y162917D01*
G01Y165250D02*
X526700D01*
X526080Y164790D01*
G01X523600D02*
Y165710D01*
G01X524220Y167507D02*
X523858Y167737D01*
X523652Y168043D01*
X523600Y168388D01*
X523652Y168695D01*
X523910Y169002D01*
X524220Y169193D01*
X524530Y169232D01*
X524892Y169155D01*
X525150Y168887D01*
X525253Y168618D01*
Y168273D01*
G01Y168618D02*
X525408Y168848D01*
X525667Y169040D01*
X525977Y169117D01*
X526287Y169040D01*
X526545Y168848D01*
X526700Y168503D01*
X526648Y168158D01*
X526442Y167813D01*
G01X526183Y170722D02*
X526493Y170952D01*
X526648Y171220D01*
X526700Y171527D01*
X526597Y171910D01*
X526338Y172178D01*
X526028Y172255D01*
X525718Y172217D01*
X525460Y172063D01*
X524943Y171297D01*
X524582Y170952D01*
X524065Y170722D01*
X523600Y170645D01*
Y172255D01*
G01X523962Y173898D02*
X523703Y174167D01*
X523600Y174473D01*
X523703Y174780D01*
X524013Y175048D01*
X524478Y175240D01*
X524943Y175317D01*
X525512D01*
X525977Y175240D01*
X526390Y175048D01*
X526597Y174818D01*
X526700Y174550D01*
X526597Y174243D01*
X526390Y174013D01*
X526080Y173860D01*
X525667Y173783D01*
X525305Y173860D01*
X524943Y174052D01*
X524737Y174282D01*
X524685Y174550D01*
X524788Y174857D01*
X525047Y175087D01*
X525512Y175317D01*
G01X522920Y169000D02*
Y175200D01*
X519720D01*
Y169000D01*
X522920D01*
G01X519800Y189100D02*
X563900D01*
Y213600D01*
X596200D01*
Y195400D01*
X574800D01*
Y185800D01*
X550200D01*
Y181200D01*
X519000D01*
Y189100D01*
X519800D01*
G01X523800Y188000D02*
Y181800D01*
X527000D01*
Y188000D01*
X523800D01*
G01X518400Y184200D02*
X512200D01*
Y181000D01*
X518400D01*
Y184200D01*
G01X519800Y188000D02*
Y181800D01*
X523000D01*
Y188000D01*
X519800D01*
G01X526400Y214500D02*
X520700D01*
G01Y223300D02*
Y214500D01*
G01X528400D02*
X527400Y216100D01*
X526400Y214500D01*
G01X511900Y216500D02*
Y210800D01*
G01Y224200D02*
Y218500D01*
G01X531893Y227500D02*
Y225278D01*
X531740Y224813D01*
X531433Y224503D01*
X531050Y224400D01*
X530667Y224503D01*
X530360Y224813D01*
X530207Y225278D01*
Y227500D01*
G01X527950Y224400D02*
Y227500D01*
X528410Y226880D01*
G01Y224400D02*
X527490D01*
G01X524390D02*
Y227500D01*
X525808Y225278D01*
X523892D01*
G01X522593Y224865D02*
X522363Y224607D01*
X522095Y224452D01*
X521750Y224400D01*
X521405Y224503D01*
X521137Y224710D01*
X520945Y225072D01*
X520907Y225485D01*
X520983Y225898D01*
X521175Y226157D01*
X521443Y226363D01*
X521712Y226415D01*
X521980Y226363D01*
X522325Y226157D01*
X522210Y227500D01*
X521175D01*
G01X534100Y223300D02*
X520700D01*
G01X516842Y234993D02*
X516997Y234763D01*
X517100Y234495D01*
Y234188D01*
X516945Y233843D01*
X516687Y233575D01*
X516377Y233383D01*
X515860Y233230D01*
X515395Y233192D01*
X514930Y233268D01*
X514620Y233383D01*
X514310Y233613D01*
X514103Y233882D01*
X514000Y234150D01*
Y234418D01*
X514103Y234687D01*
X514258Y234917D01*
X514465Y235108D01*
G01Y236407D02*
X514207Y236637D01*
X514052Y236905D01*
X514000Y237250D01*
X514103Y237595D01*
X514310Y237863D01*
X514672Y238055D01*
X515085Y238093D01*
X515498Y238017D01*
X515757Y237825D01*
X515963Y237557D01*
X516015Y237288D01*
X515963Y237020D01*
X515757Y236675D01*
X517100Y236790D01*
Y237825D01*
G01X514362Y239698D02*
X514103Y239967D01*
X514000Y240273D01*
X514103Y240580D01*
X514413Y240848D01*
X514878Y241040D01*
X515343Y241117D01*
X515912D01*
X516377Y241040D01*
X516790Y240848D01*
X516997Y240618D01*
X517100Y240350D01*
X516997Y240043D01*
X516790Y239813D01*
X516480Y239660D01*
X516067Y239583D01*
X515705Y239660D01*
X515343Y239852D01*
X515137Y240082D01*
X515085Y240350D01*
X515188Y240657D01*
X515447Y240887D01*
X515912Y241117D01*
G01X514362Y242798D02*
X514103Y243067D01*
X514000Y243373D01*
X514103Y243680D01*
X514413Y243948D01*
X514878Y244140D01*
X515343Y244217D01*
X515912D01*
X516377Y244140D01*
X516790Y243948D01*
X516997Y243718D01*
X517100Y243450D01*
X516997Y243143D01*
X516790Y242913D01*
X516480Y242760D01*
X516067Y242683D01*
X515705Y242760D01*
X515343Y242952D01*
X515137Y243182D01*
X515085Y243450D01*
X515188Y243757D01*
X515447Y243987D01*
X515912Y244217D01*
G01X515559Y228500D02*
X512559D01*
G01X512459Y231600D02*
Y225400D01*
X515659D01*
Y231600D01*
X512459D01*
G01X532690Y240917D02*
X532920Y241072D01*
X533188Y241175D01*
X533495D01*
X533840Y241020D01*
X534108Y240762D01*
X534300Y240452D01*
X534453Y239935D01*
X534491Y239470D01*
X534415Y239005D01*
X534300Y238695D01*
X534070Y238385D01*
X533801Y238178D01*
X533533Y238075D01*
X533265D01*
X532996Y238178D01*
X532766Y238333D01*
X532575Y238540D01*
G01X531276Y238695D02*
X531046Y238333D01*
X530740Y238127D01*
X530395Y238075D01*
X530088Y238127D01*
X529781Y238385D01*
X529590Y238695D01*
X529551Y239005D01*
X529628Y239367D01*
X529896Y239625D01*
X530165Y239728D01*
X530510D01*
G01X530165D02*
X529935Y239883D01*
X529743Y240142D01*
X529666Y240452D01*
X529743Y240762D01*
X529935Y241020D01*
X530280Y241175D01*
X530625Y241123D01*
X530970Y240917D01*
G01X528176Y238540D02*
X527946Y238282D01*
X527678Y238127D01*
X527333Y238075D01*
X526988Y238178D01*
X526720Y238385D01*
X526528Y238747D01*
X526490Y239160D01*
X526566Y239573D01*
X526758Y239832D01*
X527026Y240038D01*
X527295Y240090D01*
X527563Y240038D01*
X527908Y239832D01*
X527793Y241175D01*
X526758D01*
G01X524961Y240658D02*
X524731Y240968D01*
X524463Y241123D01*
X524156Y241175D01*
X523773Y241072D01*
X523505Y240813D01*
X523428Y240503D01*
X523466Y240193D01*
X523620Y239935D01*
X524386Y239418D01*
X524731Y239057D01*
X524961Y238540D01*
X525038Y238075D01*
X523428D01*
G01X532733Y244811D02*
X532963Y244966D01*
X533231Y245069D01*
X533538D01*
X533883Y244914D01*
X534151Y244656D01*
X534343Y244346D01*
X534496Y243829D01*
X534534Y243364D01*
X534458Y242899D01*
X534343Y242589D01*
X534113Y242279D01*
X533844Y242072D01*
X533576Y241969D01*
X533308D01*
X533039Y242072D01*
X532809Y242227D01*
X532618Y242434D01*
G01X531319Y242589D02*
X531089Y242227D01*
X530783Y242021D01*
X530438Y241969D01*
X530131Y242021D01*
X529824Y242279D01*
X529633Y242589D01*
X529594Y242899D01*
X529671Y243261D01*
X529939Y243519D01*
X530208Y243622D01*
X530553D01*
G01X530208D02*
X529978Y243777D01*
X529786Y244036D01*
X529709Y244346D01*
X529786Y244656D01*
X529978Y244914D01*
X530323Y245069D01*
X530668Y245017D01*
X531013Y244811D01*
G01X528219Y242434D02*
X527989Y242176D01*
X527721Y242021D01*
X527376Y241969D01*
X527031Y242072D01*
X526763Y242279D01*
X526571Y242641D01*
X526533Y243054D01*
X526609Y243467D01*
X526801Y243726D01*
X527069Y243932D01*
X527338Y243984D01*
X527606Y243932D01*
X527951Y243726D01*
X527836Y245069D01*
X526801D01*
G01X525119Y242589D02*
X524889Y242227D01*
X524583Y242021D01*
X524238Y241969D01*
X523931Y242021D01*
X523624Y242279D01*
X523433Y242589D01*
X523394Y242899D01*
X523471Y243261D01*
X523739Y243519D01*
X524008Y243622D01*
X524353D01*
G01X524008D02*
X523778Y243777D01*
X523586Y244036D01*
X523509Y244346D01*
X523586Y244656D01*
X523778Y244914D01*
X524123Y245069D01*
X524468Y245017D01*
X524813Y244811D01*
G01X532825Y248781D02*
X533055Y248936D01*
X533323Y249039D01*
X533630D01*
X533975Y248884D01*
X534243Y248626D01*
X534435Y248316D01*
X534588Y247799D01*
X534626Y247334D01*
X534550Y246869D01*
X534435Y246559D01*
X534205Y246249D01*
X533936Y246042D01*
X533668Y245939D01*
X533400D01*
X533131Y246042D01*
X532901Y246197D01*
X532710Y246404D01*
G01X531411Y246559D02*
X531181Y246197D01*
X530875Y245991D01*
X530530Y245939D01*
X530223Y245991D01*
X529916Y246249D01*
X529725Y246559D01*
X529686Y246869D01*
X529763Y247231D01*
X530031Y247489D01*
X530300Y247592D01*
X530645D01*
G01X530300D02*
X530070Y247747D01*
X529878Y248006D01*
X529801Y248316D01*
X529878Y248626D01*
X530070Y248884D01*
X530415Y249039D01*
X530760Y248987D01*
X531105Y248781D01*
G01X527008Y245939D02*
Y249039D01*
X528426Y246817D01*
X526510D01*
G01X524368Y249039D02*
X524675Y248936D01*
X524905Y248677D01*
X525058Y248367D01*
X525173Y247954D01*
X525211Y247489D01*
X525173Y247024D01*
X525058Y246611D01*
X524905Y246301D01*
X524675Y246042D01*
X524368Y245939D01*
X524061Y246042D01*
X523831Y246301D01*
X523678Y246611D01*
X523563Y247024D01*
X523525Y247489D01*
X523563Y247954D01*
X523678Y248367D01*
X523831Y248677D01*
X524061Y248936D01*
X524368Y249039D01*
G01X529935Y407543D02*
X526835D01*
Y409077D01*
G01X529418Y410682D02*
X529728Y410912D01*
X529883Y411180D01*
X529935Y411487D01*
X529832Y411870D01*
X529573Y412138D01*
X529263Y412215D01*
X528953Y412177D01*
X528695Y412023D01*
X528178Y411257D01*
X527817Y410912D01*
X527300Y410682D01*
X526835Y410605D01*
Y412215D01*
G01X520906Y455839D02*
X521061Y455609D01*
X521164Y455341D01*
Y455034D01*
X521009Y454689D01*
X520751Y454421D01*
X520441Y454229D01*
X519924Y454076D01*
X519459Y454038D01*
X518994Y454114D01*
X518684Y454229D01*
X518374Y454459D01*
X518167Y454728D01*
X518064Y454996D01*
Y455264D01*
X518167Y455533D01*
X518322Y455763D01*
X518529Y455954D01*
G01X520647Y457368D02*
X520957Y457598D01*
X521112Y457866D01*
X521164Y458173D01*
X521061Y458556D01*
X520802Y458824D01*
X520492Y458901D01*
X520182Y458863D01*
X519924Y458709D01*
X519407Y457943D01*
X519046Y457598D01*
X518529Y457368D01*
X518064Y457291D01*
Y458901D01*
G01X519077Y448476D02*
X516077D01*
G01X519177Y451576D02*
X515977D01*
G01X519177Y445376D02*
Y451576D01*
G01X515977Y445376D02*
X519177D01*
G01X515977Y451576D02*
Y445376D01*
G01X525276Y455648D02*
X525431Y455418D01*
X525534Y455150D01*
Y454843D01*
X525379Y454498D01*
X525121Y454230D01*
X524811Y454038D01*
X524294Y453885D01*
X523829Y453847D01*
X523364Y453923D01*
X523054Y454038D01*
X522744Y454268D01*
X522537Y454537D01*
X522434Y454805D01*
Y455073D01*
X522537Y455342D01*
X522692Y455572D01*
X522899Y455763D01*
G01X522434Y458365D02*
X525534D01*
X523312Y456947D01*
Y458863D01*
G01X524238Y451823D02*
X521038D01*
G01X524238Y445623D02*
Y451823D01*
G01X521038Y445623D02*
X524238D01*
G01X521038Y451823D02*
Y445623D01*
G01X524138Y448723D02*
X521138D01*
G01X510802Y458290D02*
Y453690D01*
G01X515902D02*
Y458290D01*
G01X520876Y464206D02*
X521106Y464361D01*
X521374Y464464D01*
X521681D01*
X522026Y464309D01*
X522294Y464051D01*
X522486Y463741D01*
X522639Y463224D01*
X522677Y462759D01*
X522601Y462294D01*
X522486Y461984D01*
X522256Y461674D01*
X521987Y461467D01*
X521719Y461364D01*
X521451D01*
X521182Y461467D01*
X520952Y461622D01*
X520761Y461829D01*
G01X518619Y461364D02*
Y464464D01*
X519079Y463844D01*
G01Y461364D02*
X518159D01*
G01X515519Y464464D02*
X515826Y464361D01*
X516056Y464102D01*
X516209Y463792D01*
X516324Y463379D01*
X516362Y462914D01*
X516324Y462449D01*
X516209Y462036D01*
X516056Y461726D01*
X515826Y461467D01*
X515519Y461364D01*
X515212Y461467D01*
X514982Y461726D01*
X514829Y462036D01*
X514714Y462449D01*
X514676Y462914D01*
X514714Y463379D01*
X514829Y463792D01*
X514982Y464102D01*
X515212Y464361D01*
X515519Y464464D01*
G01X513338Y461623D02*
Y464823D01*
G01X518392Y469724D02*
X518622Y469879D01*
X518890Y469982D01*
X519197D01*
X519542Y469827D01*
X519810Y469569D01*
X520002Y469259D01*
X520155Y468742D01*
X520193Y468277D01*
X520117Y467812D01*
X520002Y467502D01*
X519772Y467192D01*
X519503Y466985D01*
X519235Y466882D01*
X518967D01*
X518698Y466985D01*
X518468Y467140D01*
X518277Y467347D01*
G01X516212Y466882D02*
X516135Y467554D01*
X516020Y468122D01*
X515867Y468639D01*
X515675Y469207D01*
X515368Y469982D01*
X516902D01*
G01X513338Y467123D02*
Y470323D01*
G01X524259Y475785D02*
X524414Y475555D01*
X524517Y475287D01*
Y474980D01*
X524362Y474635D01*
X524104Y474367D01*
X523794Y474175D01*
X523277Y474022D01*
X522812Y473984D01*
X522347Y474060D01*
X522037Y474175D01*
X521727Y474405D01*
X521520Y474674D01*
X521417Y474942D01*
Y475210D01*
X521520Y475479D01*
X521675Y475709D01*
X521882Y475900D01*
G01X521417Y478042D02*
X524517D01*
X523897Y477582D01*
G01X521417D02*
Y478502D01*
G01Y481142D02*
X524517D01*
X523897Y480682D01*
G01X521417D02*
Y481602D01*
G01X510738Y482100D02*
Y492300D01*
G01X529140Y516943D02*
X529295Y516713D01*
X529398Y516445D01*
Y516138D01*
X529243Y515793D01*
X528985Y515525D01*
X528675Y515333D01*
X528158Y515180D01*
X527693Y515142D01*
X527228Y515218D01*
X526918Y515333D01*
X526608Y515563D01*
X526401Y515832D01*
X526298Y516100D01*
Y516368D01*
X526401Y516637D01*
X526556Y516867D01*
X526763Y517058D01*
G01X526660Y518548D02*
X526401Y518817D01*
X526298Y519123D01*
X526401Y519430D01*
X526711Y519698D01*
X527176Y519890D01*
X527641Y519967D01*
X528210D01*
X528675Y519890D01*
X529088Y519698D01*
X529295Y519468D01*
X529398Y519200D01*
X529295Y518893D01*
X529088Y518663D01*
X528778Y518510D01*
X528365Y518433D01*
X528003Y518510D01*
X527641Y518702D01*
X527435Y518932D01*
X527383Y519200D01*
X527486Y519507D01*
X527745Y519737D01*
X528210Y519967D01*
G01X526918Y521457D02*
X526556Y521687D01*
X526350Y521993D01*
X526298Y522338D01*
X526350Y522645D01*
X526608Y522952D01*
X526918Y523143D01*
X527228Y523182D01*
X527590Y523105D01*
X527848Y522837D01*
X527951Y522568D01*
Y522223D01*
G01Y522568D02*
X528106Y522798D01*
X528365Y522990D01*
X528675Y523067D01*
X528985Y522990D01*
X529243Y522798D01*
X529398Y522453D01*
X529346Y522108D01*
X529140Y521763D01*
G01X529398Y525400D02*
X529295Y525093D01*
X529036Y524863D01*
X528726Y524710D01*
X528313Y524595D01*
X527848Y524557D01*
X527383Y524595D01*
X526970Y524710D01*
X526660Y524863D01*
X526401Y525093D01*
X526298Y525400D01*
X526401Y525707D01*
X526660Y525937D01*
X526970Y526090D01*
X527383Y526205D01*
X527848Y526243D01*
X528313Y526205D01*
X528726Y526090D01*
X529036Y525937D01*
X529295Y525707D01*
X529398Y525400D01*
G01X521300Y516943D02*
X521455Y516713D01*
X521558Y516445D01*
Y516138D01*
X521403Y515793D01*
X521145Y515525D01*
X520835Y515333D01*
X520318Y515180D01*
X519853Y515142D01*
X519388Y515218D01*
X519078Y515333D01*
X518768Y515563D01*
X518561Y515832D01*
X518458Y516100D01*
Y516368D01*
X518561Y516637D01*
X518716Y516867D01*
X518923Y517058D01*
G01X518458Y519200D02*
X518510Y519468D01*
X518665Y519775D01*
X518923Y519967D01*
X519285Y520043D01*
X519646Y519967D01*
X519956Y519737D01*
X520111Y519392D01*
Y519008D01*
X520215Y518778D01*
X520473Y518587D01*
X520835Y518510D01*
X521196Y518625D01*
X521455Y518893D01*
X521558Y519200D01*
X521455Y519507D01*
X521196Y519775D01*
X520835Y519890D01*
X520473Y519813D01*
X520215Y519622D01*
X520111Y519392D01*
Y519008D01*
X519956Y518663D01*
X519646Y518433D01*
X519285Y518357D01*
X518923Y518433D01*
X518665Y518625D01*
X518510Y518932D01*
X518458Y519200D01*
G01X518820Y521648D02*
X518561Y521917D01*
X518458Y522223D01*
X518561Y522530D01*
X518871Y522798D01*
X519336Y522990D01*
X519801Y523067D01*
X520370D01*
X520835Y522990D01*
X521248Y522798D01*
X521455Y522568D01*
X521558Y522300D01*
X521455Y521993D01*
X521248Y521763D01*
X520938Y521610D01*
X520525Y521533D01*
X520163Y521610D01*
X519801Y521802D01*
X519595Y522032D01*
X519543Y522300D01*
X519646Y522607D01*
X519905Y522837D01*
X520370Y523067D01*
G01X519078Y524557D02*
X518716Y524787D01*
X518510Y525093D01*
X518458Y525438D01*
X518510Y525745D01*
X518768Y526052D01*
X519078Y526243D01*
X519388Y526282D01*
X519750Y526205D01*
X520008Y525937D01*
X520111Y525668D01*
Y525323D01*
G01Y525668D02*
X520266Y525898D01*
X520525Y526090D01*
X520835Y526167D01*
X521145Y526090D01*
X521403Y525898D01*
X521558Y525553D01*
X521506Y525208D01*
X521300Y524863D01*
G01X517480Y516943D02*
X517635Y516713D01*
X517738Y516445D01*
Y516138D01*
X517583Y515793D01*
X517325Y515525D01*
X517015Y515333D01*
X516498Y515180D01*
X516033Y515142D01*
X515568Y515218D01*
X515258Y515333D01*
X514948Y515563D01*
X514741Y515832D01*
X514638Y516100D01*
Y516368D01*
X514741Y516637D01*
X514896Y516867D01*
X515103Y517058D01*
G01X514638Y519200D02*
X514690Y519468D01*
X514845Y519775D01*
X515103Y519967D01*
X515465Y520043D01*
X515826Y519967D01*
X516136Y519737D01*
X516291Y519392D01*
Y519008D01*
X516395Y518778D01*
X516653Y518587D01*
X517015Y518510D01*
X517376Y518625D01*
X517635Y518893D01*
X517738Y519200D01*
X517635Y519507D01*
X517376Y519775D01*
X517015Y519890D01*
X516653Y519813D01*
X516395Y519622D01*
X516291Y519392D01*
Y519008D01*
X516136Y518663D01*
X515826Y518433D01*
X515465Y518357D01*
X515103Y518433D01*
X514845Y518625D01*
X514690Y518932D01*
X514638Y519200D01*
G01Y522223D02*
X515310Y522300D01*
X515878Y522415D01*
X516395Y522568D01*
X516963Y522760D01*
X517738Y523067D01*
Y521533D01*
G01X515930Y524672D02*
X516291Y524940D01*
X516498Y525170D01*
X516601Y525477D01*
X516498Y525745D01*
X516291Y525937D01*
X515981Y526090D01*
X515620Y526128D01*
X515310Y526090D01*
X515000Y525937D01*
X514741Y525707D01*
X514638Y525438D01*
X514741Y525132D01*
X515051Y524863D01*
X515516Y524710D01*
X516033Y524672D01*
X516705Y524748D01*
X517066Y524863D01*
X517428Y525055D01*
X517686Y525323D01*
X517738Y525592D01*
X517635Y525860D01*
X517376Y526052D01*
G01X525240Y516943D02*
X525395Y516713D01*
X525498Y516445D01*
Y516138D01*
X525343Y515793D01*
X525085Y515525D01*
X524775Y515333D01*
X524258Y515180D01*
X523793Y515142D01*
X523328Y515218D01*
X523018Y515333D01*
X522708Y515563D01*
X522501Y515832D01*
X522398Y516100D01*
Y516368D01*
X522501Y516637D01*
X522656Y516867D01*
X522863Y517058D01*
G01X522398Y519200D02*
X522450Y519468D01*
X522605Y519775D01*
X522863Y519967D01*
X523225Y520043D01*
X523586Y519967D01*
X523896Y519737D01*
X524051Y519392D01*
Y519008D01*
X524155Y518778D01*
X524413Y518587D01*
X524775Y518510D01*
X525136Y518625D01*
X525395Y518893D01*
X525498Y519200D01*
X525395Y519507D01*
X525136Y519775D01*
X524775Y519890D01*
X524413Y519813D01*
X524155Y519622D01*
X524051Y519392D01*
Y519008D01*
X523896Y518663D01*
X523586Y518433D01*
X523225Y518357D01*
X522863Y518433D01*
X522605Y518625D01*
X522450Y518932D01*
X522398Y519200D01*
G01Y522223D02*
X523070Y522300D01*
X523638Y522415D01*
X524155Y522568D01*
X524723Y522760D01*
X525498Y523067D01*
Y521533D01*
G01X523018Y524557D02*
X522656Y524787D01*
X522450Y525093D01*
X522398Y525438D01*
X522450Y525745D01*
X522708Y526052D01*
X523018Y526243D01*
X523328Y526282D01*
X523690Y526205D01*
X523948Y525937D01*
X524051Y525668D01*
Y525323D01*
G01Y525668D02*
X524206Y525898D01*
X524465Y526090D01*
X524775Y526167D01*
X525085Y526090D01*
X525343Y525898D01*
X525498Y525553D01*
X525446Y525208D01*
X525240Y524863D01*
G01X525038Y531825D02*
X528238D01*
G01X525038Y538025D02*
Y531825D01*
G01X517238D02*
X520438D01*
G01X517238Y538025D02*
Y531825D01*
G01X520438D02*
Y538025D01*
G01X513338Y531825D02*
X516538D01*
G01X513338Y538025D02*
Y531825D01*
G01X516538D02*
Y538025D01*
G01X521138Y531825D02*
X524338D01*
G01X521138Y538025D02*
Y531825D01*
G01X524338D02*
Y538025D01*
G01X512538Y535265D02*
Y541465D01*
G01X525138Y534925D02*
X528138D01*
G01X528238Y538025D02*
X525038D01*
G01X523538Y544525D02*
Y541525D01*
G01X520438Y544625D02*
Y541425D01*
G01X526638Y544625D02*
X520438D01*
G01Y541425D02*
X526638D01*
G01X517338Y534925D02*
X520338D01*
G01X520438Y538025D02*
X517238D01*
G01X513438Y534925D02*
X516438D01*
G01X516538Y538025D02*
X513338D01*
G01X521238Y534925D02*
X524238D01*
G01X524338Y538025D02*
X521138D01*
G01X524535Y560319D02*
X524765Y560474D01*
X525033Y560577D01*
X525340D01*
X525685Y560422D01*
X525953Y560164D01*
X526145Y559854D01*
X526298Y559337D01*
X526336Y558872D01*
X526260Y558407D01*
X526145Y558097D01*
X525915Y557787D01*
X525646Y557580D01*
X525378Y557477D01*
X525110D01*
X524841Y557580D01*
X524611Y557735D01*
X524420Y557942D01*
G01X522278Y557477D02*
Y560577D01*
X522738Y559957D01*
G01Y557477D02*
X521818D01*
G01X519830Y557839D02*
X519561Y557580D01*
X519255Y557477D01*
X518948Y557580D01*
X518680Y557890D01*
X518488Y558355D01*
X518411Y558820D01*
Y559389D01*
X518488Y559854D01*
X518680Y560267D01*
X518910Y560474D01*
X519178Y560577D01*
X519485Y560474D01*
X519715Y560267D01*
X519868Y559957D01*
X519945Y559544D01*
X519868Y559182D01*
X519676Y558820D01*
X519446Y558614D01*
X519178Y558562D01*
X518871Y558665D01*
X518641Y558924D01*
X518411Y559389D01*
G01X516730Y557839D02*
X516461Y557580D01*
X516155Y557477D01*
X515848Y557580D01*
X515580Y557890D01*
X515388Y558355D01*
X515311Y558820D01*
Y559389D01*
X515388Y559854D01*
X515580Y560267D01*
X515810Y560474D01*
X516078Y560577D01*
X516385Y560474D01*
X516615Y560267D01*
X516768Y559957D01*
X516845Y559544D01*
X516768Y559182D01*
X516576Y558820D01*
X516346Y558614D01*
X516078Y558562D01*
X515771Y558665D01*
X515541Y558924D01*
X515311Y559389D01*
G01X512538Y554625D02*
Y559225D01*
G01X525757Y564509D02*
Y561409D01*
X524223D01*
G01X522733Y561874D02*
X522503Y561616D01*
X522235Y561461D01*
X521890Y561409D01*
X521545Y561512D01*
X521277Y561719D01*
X521085Y562081D01*
X521047Y562494D01*
X521123Y562907D01*
X521315Y563166D01*
X521583Y563372D01*
X521852Y563424D01*
X522120Y563372D01*
X522465Y563166D01*
X522350Y564509D01*
X521315D01*
G01X519633Y562029D02*
X519403Y561667D01*
X519097Y561461D01*
X518752Y561409D01*
X518445Y561461D01*
X518138Y561719D01*
X517947Y562029D01*
X517908Y562339D01*
X517985Y562701D01*
X518253Y562959D01*
X518522Y563062D01*
X518867D01*
G01X518522D02*
X518292Y563217D01*
X518100Y563476D01*
X518023Y563786D01*
X518100Y564096D01*
X518292Y564354D01*
X518637Y564509D01*
X518982Y564457D01*
X519327Y564251D01*
G01X512538Y559925D02*
Y564925D01*
G01X518620Y572488D02*
X518775Y572258D01*
X518878Y571990D01*
Y571683D01*
X518723Y571338D01*
X518465Y571070D01*
X518155Y570878D01*
X517638Y570725D01*
X517173Y570687D01*
X516708Y570763D01*
X516398Y570878D01*
X516088Y571108D01*
X515881Y571377D01*
X515778Y571645D01*
Y571913D01*
X515881Y572182D01*
X516036Y572412D01*
X516243Y572603D01*
G01X516140Y574093D02*
X515881Y574362D01*
X515778Y574668D01*
X515881Y574975D01*
X516191Y575243D01*
X516656Y575435D01*
X517121Y575512D01*
X517690D01*
X518155Y575435D01*
X518568Y575243D01*
X518775Y575013D01*
X518878Y574745D01*
X518775Y574438D01*
X518568Y574208D01*
X518258Y574055D01*
X517845Y573978D01*
X517483Y574055D01*
X517121Y574247D01*
X516915Y574477D01*
X516863Y574745D01*
X516966Y575052D01*
X517225Y575282D01*
X517690Y575512D01*
G01X516398Y577002D02*
X516036Y577232D01*
X515830Y577538D01*
X515778Y577883D01*
X515830Y578190D01*
X516088Y578497D01*
X516398Y578688D01*
X516708Y578727D01*
X517070Y578650D01*
X517328Y578382D01*
X517431Y578113D01*
Y577768D01*
G01Y578113D02*
X517586Y578343D01*
X517845Y578535D01*
X518155Y578612D01*
X518465Y578535D01*
X518723Y578343D01*
X518878Y577998D01*
X518826Y577653D01*
X518620Y577308D01*
G01X515778Y580945D02*
X518878D01*
X518258Y580485D01*
G01X515778D02*
Y581405D01*
G01X521238Y592525D02*
Y598725D01*
G01X518038D02*
Y592525D01*
G01X521138Y595625D02*
X518138D01*
G01X518038Y592525D02*
X521238D01*
G01X516938Y596225D02*
X510738D01*
G01X516938Y593025D02*
Y596225D01*
G01X510738Y593025D02*
X516938D01*
G01X510738Y596225D02*
Y593025D01*
G01X513838Y596125D02*
Y593125D01*
G01X525138Y592625D02*
Y598825D01*
G01X521938Y592625D02*
X525138D01*
G01X521938Y598825D02*
Y592625D01*
G01X525038Y595725D02*
X522038D01*
G01X525838Y598825D02*
Y592625D01*
G01D02*
X529038D01*
G01X528938Y595725D02*
X525938D01*
G01X521945Y604327D02*
X522100Y604097D01*
X522203Y603829D01*
Y603522D01*
X522048Y603177D01*
X521790Y602909D01*
X521480Y602717D01*
X520963Y602564D01*
X520498Y602526D01*
X520033Y602602D01*
X519723Y602717D01*
X519413Y602947D01*
X519206Y603216D01*
X519103Y603484D01*
Y603752D01*
X519206Y604021D01*
X519361Y604251D01*
X519568Y604442D01*
G01X519103Y606584D02*
X519155Y606852D01*
X519310Y607159D01*
X519568Y607351D01*
X519930Y607427D01*
X520291Y607351D01*
X520601Y607121D01*
X520756Y606776D01*
Y606392D01*
X520860Y606162D01*
X521118Y605971D01*
X521480Y605894D01*
X521841Y606009D01*
X522100Y606277D01*
X522203Y606584D01*
X522100Y606891D01*
X521841Y607159D01*
X521480Y607274D01*
X521118Y607197D01*
X520860Y607006D01*
X520756Y606776D01*
Y606392D01*
X520601Y606047D01*
X520291Y605817D01*
X519930Y605741D01*
X519568Y605817D01*
X519310Y606009D01*
X519155Y606316D01*
X519103Y606584D01*
G01Y609607D02*
X519775Y609684D01*
X520343Y609799D01*
X520860Y609952D01*
X521428Y610144D01*
X522203Y610451D01*
Y608917D01*
G01X519568Y611941D02*
X519310Y612171D01*
X519155Y612439D01*
X519103Y612784D01*
X519206Y613129D01*
X519413Y613397D01*
X519775Y613589D01*
X520188Y613627D01*
X520601Y613551D01*
X520860Y613359D01*
X521066Y613091D01*
X521118Y612822D01*
X521066Y612554D01*
X520860Y612209D01*
X522203Y612324D01*
Y613359D01*
G01X521238Y598725D02*
X518038D01*
G01X527584Y603387D02*
X527739Y603157D01*
X527842Y602889D01*
Y602582D01*
X527687Y602237D01*
X527429Y601969D01*
X527119Y601777D01*
X526602Y601624D01*
X526137Y601586D01*
X525672Y601662D01*
X525362Y601777D01*
X525052Y602007D01*
X524845Y602276D01*
X524742Y602544D01*
Y602812D01*
X524845Y603081D01*
X525000Y603311D01*
X525207Y603502D01*
G01X525362Y604801D02*
X525000Y605031D01*
X524794Y605337D01*
X524742Y605682D01*
X524794Y605989D01*
X525052Y606296D01*
X525362Y606487D01*
X525672Y606526D01*
X526034Y606449D01*
X526292Y606181D01*
X526395Y605912D01*
Y605567D01*
G01Y605912D02*
X526550Y606142D01*
X526809Y606334D01*
X527119Y606411D01*
X527429Y606334D01*
X527687Y606142D01*
X527842Y605797D01*
X527790Y605452D01*
X527584Y605107D01*
G01X525362Y607901D02*
X525000Y608131D01*
X524794Y608437D01*
X524742Y608782D01*
X524794Y609089D01*
X525052Y609396D01*
X525362Y609587D01*
X525672Y609626D01*
X526034Y609549D01*
X526292Y609281D01*
X526395Y609012D01*
Y608667D01*
G01Y609012D02*
X526550Y609242D01*
X526809Y609434D01*
X527119Y609511D01*
X527429Y609434D01*
X527687Y609242D01*
X527842Y608897D01*
X527790Y608552D01*
X527584Y608207D01*
G01X524742Y611844D02*
X527842D01*
X527222Y611384D01*
G01X524742D02*
Y612304D01*
G01X525138Y598825D02*
X521938D01*
G01X529038D02*
X525838D01*
G01X511799Y608748D02*
X514899D01*
Y609707D01*
X514744Y610013D01*
X514537Y610205D01*
X514124Y610282D01*
X513711Y610205D01*
X513452Y609975D01*
X513297Y609707D01*
Y608748D01*
G01Y609707D02*
X511799Y610282D01*
G01Y612615D02*
X514899D01*
X514279Y612155D01*
G01X511799D02*
Y613075D01*
G01X514899Y615715D02*
X514796Y615408D01*
X514537Y615178D01*
X514227Y615025D01*
X513814Y614910D01*
X513349Y614872D01*
X512884Y614910D01*
X512471Y615025D01*
X512161Y615178D01*
X511902Y615408D01*
X511799Y615715D01*
X511902Y616022D01*
X512161Y616252D01*
X512471Y616405D01*
X512884Y616520D01*
X513349Y616558D01*
X513814Y616520D01*
X514227Y616405D01*
X514537Y616252D01*
X514796Y616022D01*
X514899Y615715D01*
G01X513091Y618087D02*
X513452Y618355D01*
X513659Y618585D01*
X513762Y618892D01*
X513659Y619160D01*
X513452Y619352D01*
X513142Y619505D01*
X512781Y619543D01*
X512471Y619505D01*
X512161Y619352D01*
X511902Y619122D01*
X511799Y618853D01*
X511902Y618547D01*
X512212Y618278D01*
X512677Y618125D01*
X513194Y618087D01*
X513866Y618163D01*
X514227Y618278D01*
X514589Y618470D01*
X514847Y618738D01*
X514899Y619007D01*
X514796Y619275D01*
X514537Y619467D01*
G01X512161Y621263D02*
X511902Y621532D01*
X511799Y621838D01*
X511902Y622145D01*
X512212Y622413D01*
X512677Y622605D01*
X513142Y622682D01*
X513711D01*
X514176Y622605D01*
X514589Y622413D01*
X514796Y622183D01*
X514899Y621915D01*
X514796Y621608D01*
X514589Y621378D01*
X514279Y621225D01*
X513866Y621148D01*
X513504Y621225D01*
X513142Y621417D01*
X512936Y621647D01*
X512884Y621915D01*
X512987Y622222D01*
X513246Y622452D01*
X513711Y622682D01*
G01X510933Y625266D02*
X514133D01*
G01X510933Y631466D02*
Y625266D01*
G01X514133D02*
Y631466D01*
G01X516129Y629427D02*
X516342Y629635D01*
X516582Y629760D01*
X516796D01*
X517009Y629635D01*
X517169Y629427D01*
X517249Y629135D01*
X517196Y628843D01*
X517062Y628593D01*
X516822Y628427D01*
X516502Y628343D01*
X516316Y628177D01*
X516236Y627885D01*
X516289Y627593D01*
X516422Y627385D01*
X516609Y627260D01*
X516796D01*
X516982Y627343D01*
X517142Y627552D01*
G01X529854Y621304D02*
Y619512D01*
X529747Y619137D01*
X529534Y618887D01*
X529267Y618804D01*
X529000Y618887D01*
X528787Y619137D01*
X528680Y619512D01*
Y621304D01*
G01X527067Y618804D02*
Y621304D01*
X527387Y620804D01*
G01Y618804D02*
X526747D01*
G01X524547D02*
Y621304D01*
X525534Y619512D01*
X524200D01*
G01X522667Y621304D02*
X522880Y621221D01*
X523040Y621012D01*
X523147Y620762D01*
X523227Y620429D01*
X523254Y620054D01*
X523227Y619679D01*
X523147Y619346D01*
X523040Y619096D01*
X522880Y618887D01*
X522667Y618804D01*
X522454Y618887D01*
X522294Y619096D01*
X522187Y619346D01*
X522107Y619679D01*
X522080Y620054D01*
X522107Y620429D01*
X522187Y620762D01*
X522294Y621012D01*
X522454Y621221D01*
X522667Y621304D01*
G01X518282Y626498D02*
X531282D01*
G01X518282Y641498D02*
Y626498D01*
G01X522874Y646814D02*
Y643614D01*
G01D02*
X529074D01*
G01X514133Y631466D02*
X510933D01*
G01X519174Y644491D02*
Y641991D01*
X519708D01*
X519921Y642116D01*
X520081Y642283D01*
X520214Y642533D01*
X520321Y642824D01*
X520348Y643241D01*
X520321Y643658D01*
X520214Y643949D01*
X520081Y644199D01*
X519921Y644366D01*
X519708Y644491D01*
X519174D01*
G01X531282Y641498D02*
X518282D01*
G01X529074Y646814D02*
X522874D01*
G01X514592Y653407D02*
Y656607D01*
G01X513253Y664797D02*
Y667997D01*
G01X532579Y670966D02*
Y674066D01*
X531620D01*
X531314Y673911D01*
X531122Y673704D01*
X531045Y673291D01*
X531122Y672878D01*
X531352Y672619D01*
X531620Y672464D01*
X532579D01*
G01X531620D02*
X531045Y670966D01*
G01X529364Y671328D02*
X529095Y671069D01*
X528789Y670966D01*
X528482Y671069D01*
X528214Y671379D01*
X528022Y671844D01*
X527945Y672309D01*
Y672878D01*
X528022Y673343D01*
X528214Y673756D01*
X528444Y673963D01*
X528712Y674066D01*
X529019Y673963D01*
X529249Y673756D01*
X529402Y673446D01*
X529479Y673033D01*
X529402Y672671D01*
X529210Y672309D01*
X528980Y672103D01*
X528712Y672051D01*
X528405Y672154D01*
X528175Y672413D01*
X527945Y672878D01*
G01X525612Y670966D02*
X525344Y671018D01*
X525037Y671173D01*
X524845Y671431D01*
X524769Y671793D01*
X524845Y672154D01*
X525075Y672464D01*
X525420Y672619D01*
X525804D01*
X526034Y672723D01*
X526225Y672981D01*
X526302Y673343D01*
X526187Y673704D01*
X525919Y673963D01*
X525612Y674066D01*
X525305Y673963D01*
X525037Y673704D01*
X524922Y673343D01*
X524999Y672981D01*
X525190Y672723D01*
X525420Y672619D01*
X525804D01*
X526149Y672464D01*
X526379Y672154D01*
X526455Y671793D01*
X526379Y671431D01*
X526187Y671173D01*
X525880Y671018D01*
X525612Y670966D01*
G01X522512D02*
X522244Y671018D01*
X521937Y671173D01*
X521745Y671431D01*
X521669Y671793D01*
X521745Y672154D01*
X521975Y672464D01*
X522320Y672619D01*
X522704D01*
X522934Y672723D01*
X523125Y672981D01*
X523202Y673343D01*
X523087Y673704D01*
X522819Y673963D01*
X522512Y674066D01*
X522205Y673963D01*
X521937Y673704D01*
X521822Y673343D01*
X521899Y672981D01*
X522090Y672723D01*
X522320Y672619D01*
X522704D01*
X523049Y672464D01*
X523279Y672154D01*
X523355Y671793D01*
X523279Y671431D01*
X523087Y671173D01*
X522780Y671018D01*
X522512Y670966D01*
G01X514559Y668888D02*
Y672088D01*
G01X532391Y674727D02*
Y677827D01*
X531432D01*
X531126Y677672D01*
X530934Y677465D01*
X530857Y677052D01*
X530934Y676639D01*
X531164Y676380D01*
X531432Y676225D01*
X532391D01*
G01X531432D02*
X530857Y674727D01*
G01X529176Y675089D02*
X528907Y674830D01*
X528601Y674727D01*
X528294Y674830D01*
X528026Y675140D01*
X527834Y675605D01*
X527757Y676070D01*
Y676639D01*
X527834Y677104D01*
X528026Y677517D01*
X528256Y677724D01*
X528524Y677827D01*
X528831Y677724D01*
X529061Y677517D01*
X529214Y677207D01*
X529291Y676794D01*
X529214Y676432D01*
X529022Y676070D01*
X528792Y675864D01*
X528524Y675812D01*
X528217Y675915D01*
X527987Y676174D01*
X527757Y676639D01*
G01X525424Y674727D02*
X525156Y674779D01*
X524849Y674934D01*
X524657Y675192D01*
X524581Y675554D01*
X524657Y675915D01*
X524887Y676225D01*
X525232Y676380D01*
X525616D01*
X525846Y676484D01*
X526037Y676742D01*
X526114Y677104D01*
X525999Y677465D01*
X525731Y677724D01*
X525424Y677827D01*
X525117Y677724D01*
X524849Y677465D01*
X524734Y677104D01*
X524811Y676742D01*
X525002Y676484D01*
X525232Y676380D01*
X525616D01*
X525961Y676225D01*
X526191Y675915D01*
X526267Y675554D01*
X526191Y675192D01*
X525999Y674934D01*
X525692Y674779D01*
X525424Y674727D01*
G01X523052Y677310D02*
X522822Y677620D01*
X522554Y677775D01*
X522247Y677827D01*
X521864Y677724D01*
X521596Y677465D01*
X521519Y677155D01*
X521557Y676845D01*
X521711Y676587D01*
X522477Y676070D01*
X522822Y675709D01*
X523052Y675192D01*
X523129Y674727D01*
X521519D01*
G01X512818Y673060D02*
Y676260D01*
G01X531702Y680871D02*
Y683971D01*
X530743D01*
X530437Y683816D01*
X530245Y683609D01*
X530168Y683196D01*
X530245Y682783D01*
X530475Y682524D01*
X530743Y682369D01*
X531702D01*
G01X530743D02*
X530168Y680871D01*
G01X528487Y681233D02*
X528218Y680974D01*
X527912Y680871D01*
X527605Y680974D01*
X527337Y681284D01*
X527145Y681749D01*
X527068Y682214D01*
Y682783D01*
X527145Y683248D01*
X527337Y683661D01*
X527567Y683868D01*
X527835Y683971D01*
X528142Y683868D01*
X528372Y683661D01*
X528525Y683351D01*
X528602Y682938D01*
X528525Y682576D01*
X528333Y682214D01*
X528103Y682008D01*
X527835Y681956D01*
X527528Y682059D01*
X527298Y682318D01*
X527068Y682783D01*
G01X524812Y680871D02*
X524735Y681543D01*
X524620Y682111D01*
X524467Y682628D01*
X524275Y683196D01*
X523968Y683971D01*
X525502D01*
G01X522363Y682163D02*
X522095Y682524D01*
X521865Y682731D01*
X521558Y682834D01*
X521290Y682731D01*
X521098Y682524D01*
X520945Y682214D01*
X520907Y681853D01*
X520945Y681543D01*
X521098Y681233D01*
X521328Y680974D01*
X521597Y680871D01*
X521903Y680974D01*
X522172Y681284D01*
X522325Y681749D01*
X522363Y682266D01*
X522287Y682938D01*
X522172Y683299D01*
X521980Y683661D01*
X521712Y683919D01*
X521443Y683971D01*
X521175Y683868D01*
X520983Y683609D01*
G01X514498Y677402D02*
Y680602D01*
G01X513440Y728156D02*
X516440D01*
G01X513340Y725056D02*
X516540D01*
G01X513340Y731256D02*
Y725056D01*
G01X516540Y731256D02*
X513340D01*
G01X516540Y725056D02*
Y731256D01*
G01X517840Y736556D02*
X521040D01*
G01X517840Y742756D02*
Y736556D01*
G01X521040D02*
Y742756D01*
G01X522440Y728156D02*
X525440D01*
G01X522340Y725056D02*
X525540D01*
G01X522340Y731256D02*
Y725056D01*
G01X525540Y731256D02*
X522340D01*
G01X525540Y725056D02*
Y731256D01*
G01X521040D02*
X517840D01*
G01X521040Y725056D02*
Y731256D01*
G01X517840Y725056D02*
X521040D01*
G01X517840Y731256D02*
Y725056D01*
G01X516540Y736556D02*
Y742756D01*
G01X513340Y736556D02*
X516540D01*
G01X513340Y742756D02*
Y736556D01*
G01X525540D02*
Y742756D01*
G01X522340Y736556D02*
X525540D01*
G01X522340Y742756D02*
Y736556D01*
G01X527465Y747305D02*
X527620Y747075D01*
X527723Y746807D01*
Y746500D01*
X527568Y746155D01*
X527310Y745887D01*
X527000Y745695D01*
X526483Y745542D01*
X526018Y745504D01*
X525553Y745580D01*
X525243Y745695D01*
X524933Y745925D01*
X524726Y746194D01*
X524623Y746462D01*
Y746730D01*
X524726Y746999D01*
X524881Y747229D01*
X525088Y747420D01*
G01X524623Y749485D02*
X525295Y749562D01*
X525863Y749677D01*
X526380Y749830D01*
X526948Y750022D01*
X527723Y750329D01*
Y748795D01*
G01X524623Y752662D02*
X527723D01*
X527103Y752202D01*
G01X524623D02*
Y753122D01*
G01X524985Y755110D02*
X524726Y755379D01*
X524623Y755685D01*
X524726Y755992D01*
X525036Y756260D01*
X525501Y756452D01*
X525966Y756529D01*
X526535D01*
X527000Y756452D01*
X527413Y756260D01*
X527620Y756030D01*
X527723Y755762D01*
X527620Y755455D01*
X527413Y755225D01*
X527103Y755072D01*
X526690Y754995D01*
X526328Y755072D01*
X525966Y755264D01*
X525760Y755494D01*
X525708Y755762D01*
X525811Y756069D01*
X526070Y756299D01*
X526535Y756529D01*
G01X517940Y739656D02*
X520940D01*
G01X521040Y742756D02*
X517840D01*
G01X519309Y747305D02*
X519464Y747075D01*
X519567Y746807D01*
Y746500D01*
X519412Y746155D01*
X519154Y745887D01*
X518844Y745695D01*
X518327Y745542D01*
X517862Y745504D01*
X517397Y745580D01*
X517087Y745695D01*
X516777Y745925D01*
X516570Y746194D01*
X516467Y746462D01*
Y746730D01*
X516570Y746999D01*
X516725Y747229D01*
X516932Y747420D01*
G01X516467Y749485D02*
X517139Y749562D01*
X517707Y749677D01*
X518224Y749830D01*
X518792Y750022D01*
X519567Y750329D01*
Y748795D01*
G01X519050Y751934D02*
X519360Y752164D01*
X519515Y752432D01*
X519567Y752739D01*
X519464Y753122D01*
X519205Y753390D01*
X518895Y753467D01*
X518585Y753429D01*
X518327Y753275D01*
X517810Y752509D01*
X517449Y752164D01*
X516932Y751934D01*
X516467Y751857D01*
Y753467D01*
G01X516932Y754919D02*
X516674Y755149D01*
X516519Y755417D01*
X516467Y755762D01*
X516570Y756107D01*
X516777Y756375D01*
X517139Y756567D01*
X517552Y756605D01*
X517965Y756529D01*
X518224Y756337D01*
X518430Y756069D01*
X518482Y755800D01*
X518430Y755532D01*
X518224Y755187D01*
X519567Y755302D01*
Y756337D01*
G01X520514Y745695D02*
X523614D01*
Y746654D01*
X523459Y746960D01*
X523252Y747152D01*
X522839Y747229D01*
X522426Y747152D01*
X522167Y746922D01*
X522012Y746654D01*
Y745695D01*
G01Y746654D02*
X520514Y747229D01*
G01X520876Y748910D02*
X520617Y749179D01*
X520514Y749485D01*
X520617Y749792D01*
X520927Y750060D01*
X521392Y750252D01*
X521857Y750329D01*
X522426D01*
X522891Y750252D01*
X523304Y750060D01*
X523511Y749830D01*
X523614Y749562D01*
X523511Y749255D01*
X523304Y749025D01*
X522994Y748872D01*
X522581Y748795D01*
X522219Y748872D01*
X521857Y749064D01*
X521651Y749294D01*
X521599Y749562D01*
X521702Y749869D01*
X521961Y750099D01*
X522426Y750329D01*
G01X520979Y751819D02*
X520721Y752049D01*
X520566Y752317D01*
X520514Y752662D01*
X520617Y753007D01*
X520824Y753275D01*
X521186Y753467D01*
X521599Y753505D01*
X522012Y753429D01*
X522271Y753237D01*
X522477Y752969D01*
X522529Y752700D01*
X522477Y752432D01*
X522271Y752087D01*
X523614Y752202D01*
Y753237D01*
G01X520876Y755110D02*
X520617Y755379D01*
X520514Y755685D01*
X520617Y755992D01*
X520927Y756260D01*
X521392Y756452D01*
X521857Y756529D01*
X522426D01*
X522891Y756452D01*
X523304Y756260D01*
X523511Y756030D01*
X523614Y755762D01*
X523511Y755455D01*
X523304Y755225D01*
X522994Y755072D01*
X522581Y754995D01*
X522219Y755072D01*
X521857Y755264D01*
X521651Y755494D01*
X521599Y755762D01*
X521702Y756069D01*
X521961Y756299D01*
X522426Y756529D01*
G01X516540Y742756D02*
X513340D01*
G01X525540D02*
X522340D01*
G01X516262Y759623D02*
X516417Y759393D01*
X516520Y759125D01*
Y758818D01*
X516365Y758473D01*
X516107Y758205D01*
X515797Y758013D01*
X515280Y757860D01*
X514815Y757822D01*
X514350Y757898D01*
X514040Y758013D01*
X513730Y758243D01*
X513523Y758512D01*
X513420Y758780D01*
Y759048D01*
X513523Y759317D01*
X513678Y759547D01*
X513885Y759738D01*
G01X513420Y761803D02*
X514092Y761880D01*
X514660Y761995D01*
X515177Y762148D01*
X515745Y762340D01*
X516520Y762647D01*
Y761113D01*
G01X516003Y764252D02*
X516313Y764482D01*
X516468Y764750D01*
X516520Y765057D01*
X516417Y765440D01*
X516158Y765708D01*
X515848Y765785D01*
X515538Y765747D01*
X515280Y765593D01*
X514763Y764827D01*
X514402Y764482D01*
X513885Y764252D01*
X513420Y764175D01*
Y765785D01*
G01Y768080D02*
X513472Y768348D01*
X513627Y768655D01*
X513885Y768847D01*
X514247Y768923D01*
X514608Y768847D01*
X514918Y768617D01*
X515073Y768272D01*
Y767888D01*
X515177Y767658D01*
X515435Y767467D01*
X515797Y767390D01*
X516158Y767505D01*
X516417Y767773D01*
X516520Y768080D01*
X516417Y768387D01*
X516158Y768655D01*
X515797Y768770D01*
X515435Y768693D01*
X515177Y768502D01*
X515073Y768272D01*
Y767888D01*
X514918Y767543D01*
X514608Y767313D01*
X514247Y767237D01*
X513885Y767313D01*
X513627Y767505D01*
X513472Y767812D01*
X513420Y768080D01*
G01X524525Y759623D02*
X524680Y759393D01*
X524783Y759125D01*
Y758818D01*
X524628Y758473D01*
X524370Y758205D01*
X524060Y758013D01*
X523543Y757860D01*
X523078Y757822D01*
X522613Y757898D01*
X522303Y758013D01*
X521993Y758243D01*
X521786Y758512D01*
X521683Y758780D01*
Y759048D01*
X521786Y759317D01*
X521941Y759547D01*
X522148Y759738D01*
G01X521683Y761803D02*
X522355Y761880D01*
X522923Y761995D01*
X523440Y762148D01*
X524008Y762340D01*
X524783Y762647D01*
Y761113D01*
G01X524266Y764252D02*
X524576Y764482D01*
X524731Y764750D01*
X524783Y765057D01*
X524680Y765440D01*
X524421Y765708D01*
X524111Y765785D01*
X523801Y765747D01*
X523543Y765593D01*
X523026Y764827D01*
X522665Y764482D01*
X522148Y764252D01*
X521683Y764175D01*
Y765785D01*
G01X524266Y767352D02*
X524576Y767582D01*
X524731Y767850D01*
X524783Y768157D01*
X524680Y768540D01*
X524421Y768808D01*
X524111Y768885D01*
X523801Y768847D01*
X523543Y768693D01*
X523026Y767927D01*
X522665Y767582D01*
X522148Y767352D01*
X521683Y767275D01*
Y768885D01*
G01X526194Y758013D02*
X529294D01*
Y758972D01*
X529139Y759278D01*
X528932Y759470D01*
X528519Y759547D01*
X528106Y759470D01*
X527847Y759240D01*
X527692Y758972D01*
Y758013D01*
G01Y758972D02*
X526194Y759547D01*
G01X526556Y761228D02*
X526297Y761497D01*
X526194Y761803D01*
X526297Y762110D01*
X526607Y762378D01*
X527072Y762570D01*
X527537Y762647D01*
X528106D01*
X528571Y762570D01*
X528984Y762378D01*
X529191Y762148D01*
X529294Y761880D01*
X529191Y761573D01*
X528984Y761343D01*
X528674Y761190D01*
X528261Y761113D01*
X527899Y761190D01*
X527537Y761382D01*
X527331Y761612D01*
X527279Y761880D01*
X527382Y762187D01*
X527641Y762417D01*
X528106Y762647D01*
G01X526659Y764137D02*
X526401Y764367D01*
X526246Y764635D01*
X526194Y764980D01*
X526297Y765325D01*
X526504Y765593D01*
X526866Y765785D01*
X527279Y765823D01*
X527692Y765747D01*
X527951Y765555D01*
X528157Y765287D01*
X528209Y765018D01*
X528157Y764750D01*
X527951Y764405D01*
X529294Y764520D01*
Y765555D01*
G01X527486Y767352D02*
X527847Y767620D01*
X528054Y767850D01*
X528157Y768157D01*
X528054Y768425D01*
X527847Y768617D01*
X527537Y768770D01*
X527176Y768808D01*
X526866Y768770D01*
X526556Y768617D01*
X526297Y768387D01*
X526194Y768118D01*
X526297Y767812D01*
X526607Y767543D01*
X527072Y767390D01*
X527589Y767352D01*
X528261Y767428D01*
X528622Y767543D01*
X528984Y767735D01*
X529242Y768003D01*
X529294Y768272D01*
X529191Y768540D01*
X528932Y768732D01*
G01X517647Y758013D02*
X520747D01*
Y758972D01*
X520592Y759278D01*
X520385Y759470D01*
X519972Y759547D01*
X519559Y759470D01*
X519300Y759240D01*
X519145Y758972D01*
Y758013D01*
G01Y758972D02*
X517647Y759547D01*
G01X518009Y761228D02*
X517750Y761497D01*
X517647Y761803D01*
X517750Y762110D01*
X518060Y762378D01*
X518525Y762570D01*
X518990Y762647D01*
X519559D01*
X520024Y762570D01*
X520437Y762378D01*
X520644Y762148D01*
X520747Y761880D01*
X520644Y761573D01*
X520437Y761343D01*
X520127Y761190D01*
X519714Y761113D01*
X519352Y761190D01*
X518990Y761382D01*
X518784Y761612D01*
X518732Y761880D01*
X518835Y762187D01*
X519094Y762417D01*
X519559Y762647D01*
G01X518939Y764252D02*
X519300Y764520D01*
X519507Y764750D01*
X519610Y765057D01*
X519507Y765325D01*
X519300Y765517D01*
X518990Y765670D01*
X518629Y765708D01*
X518319Y765670D01*
X518009Y765517D01*
X517750Y765287D01*
X517647Y765018D01*
X517750Y764712D01*
X518060Y764443D01*
X518525Y764290D01*
X519042Y764252D01*
X519714Y764328D01*
X520075Y764443D01*
X520437Y764635D01*
X520695Y764903D01*
X520747Y765172D01*
X520644Y765440D01*
X520385Y765632D01*
G01X520230Y767352D02*
X520540Y767582D01*
X520695Y767850D01*
X520747Y768157D01*
X520644Y768540D01*
X520385Y768808D01*
X520075Y768885D01*
X519765Y768847D01*
X519507Y768693D01*
X518990Y767927D01*
X518629Y767582D01*
X518112Y767352D01*
X517647Y767275D01*
Y768885D01*
G01X543917Y71400D02*
Y74500D01*
X542958D01*
X542652Y74345D01*
X542460Y74138D01*
X542383Y73725D01*
X542460Y73312D01*
X542690Y73053D01*
X542958Y72898D01*
X543917D01*
G01X542958D02*
X542383Y71400D01*
G01X540050D02*
Y74500D01*
X540510Y73880D01*
G01Y71400D02*
X539590D01*
G01X536950Y74500D02*
X537257Y74397D01*
X537487Y74138D01*
X537640Y73828D01*
X537755Y73415D01*
X537793Y72950D01*
X537755Y72485D01*
X537640Y72072D01*
X537487Y71762D01*
X537257Y71503D01*
X536950Y71400D01*
X536643Y71503D01*
X536413Y71762D01*
X536260Y72072D01*
X536145Y72485D01*
X536107Y72950D01*
X536145Y73415D01*
X536260Y73828D01*
X536413Y74138D01*
X536643Y74397D01*
X536950Y74500D01*
G01X534693Y71865D02*
X534463Y71607D01*
X534195Y71452D01*
X533850Y71400D01*
X533505Y71503D01*
X533237Y71710D01*
X533045Y72072D01*
X533007Y72485D01*
X533083Y72898D01*
X533275Y73157D01*
X533543Y73363D01*
X533812Y73415D01*
X534080Y73363D01*
X534425Y73157D01*
X534310Y74500D01*
X533275D01*
G01X531478Y72692D02*
X531210Y73053D01*
X530980Y73260D01*
X530673Y73363D01*
X530405Y73260D01*
X530213Y73053D01*
X530060Y72743D01*
X530022Y72382D01*
X530060Y72072D01*
X530213Y71762D01*
X530443Y71503D01*
X530712Y71400D01*
X531018Y71503D01*
X531287Y71813D01*
X531440Y72278D01*
X531478Y72795D01*
X531402Y73467D01*
X531287Y73828D01*
X531095Y74190D01*
X530827Y74448D01*
X530558Y74500D01*
X530290Y74397D01*
X530098Y74138D01*
G01X544844Y87145D02*
Y90245D01*
X543885D01*
X543579Y90090D01*
X543387Y89883D01*
X543310Y89470D01*
X543387Y89057D01*
X543617Y88798D01*
X543885Y88643D01*
X544844D01*
G01X543885D02*
X543310Y87145D01*
G01X540977D02*
Y90245D01*
X541437Y89625D01*
G01Y87145D02*
X540517D01*
G01X537877D02*
Y90245D01*
X538337Y89625D01*
G01Y87145D02*
X537417D01*
G01X534777D02*
X534509Y87197D01*
X534202Y87352D01*
X534010Y87610D01*
X533934Y87972D01*
X534010Y88333D01*
X534240Y88643D01*
X534585Y88798D01*
X534969D01*
X535199Y88902D01*
X535390Y89160D01*
X535467Y89522D01*
X535352Y89883D01*
X535084Y90142D01*
X534777Y90245D01*
X534470Y90142D01*
X534202Y89883D01*
X534087Y89522D01*
X534164Y89160D01*
X534355Y88902D01*
X534585Y88798D01*
X534969D01*
X535314Y88643D01*
X535544Y88333D01*
X535620Y87972D01*
X535544Y87610D01*
X535352Y87352D01*
X535045Y87197D01*
X534777Y87145D01*
G01X532329Y87507D02*
X532060Y87248D01*
X531754Y87145D01*
X531447Y87248D01*
X531179Y87558D01*
X530987Y88023D01*
X530910Y88488D01*
Y89057D01*
X530987Y89522D01*
X531179Y89935D01*
X531409Y90142D01*
X531677Y90245D01*
X531984Y90142D01*
X532214Y89935D01*
X532367Y89625D01*
X532444Y89212D01*
X532367Y88850D01*
X532175Y88488D01*
X531945Y88282D01*
X531677Y88230D01*
X531370Y88333D01*
X531140Y88592D01*
X530910Y89057D01*
G01X548221Y132314D02*
X526655D01*
Y157400D01*
X528400D01*
Y172309D01*
X576618D01*
Y132314D01*
X552421D01*
G01X535371Y136746D02*
X529171D01*
G01D02*
Y133546D01*
G01D02*
X535371D01*
G01D02*
Y136746D01*
G01X546289Y137015D02*
X540089D01*
G01D02*
Y133815D01*
G01D02*
X546289D01*
G01X540089Y137815D02*
X546289D01*
G01X540089Y141015D02*
Y137815D01*
G01X529171Y140746D02*
Y137546D01*
G01D02*
X535371D01*
G01D02*
Y140746D01*
G01X546289Y153015D02*
X540089D01*
G01Y149815D02*
X546289D01*
G01X540089Y153015D02*
Y149815D01*
G01X529171Y149546D02*
X535371D01*
G01D02*
Y152746D01*
G01D02*
X529171D01*
G01D02*
Y149546D01*
G01X540089Y153815D02*
X546289D01*
G01X540089Y157015D02*
Y153815D01*
G01X529171Y153546D02*
X535371D01*
G01D02*
Y156746D01*
G01X529171D02*
Y153546D01*
G01X546289Y141015D02*
X540089D01*
G01X535371Y140746D02*
X529171D01*
G01X540089Y145815D02*
X546289D01*
G01Y149015D02*
X540089D01*
G01D02*
Y145815D01*
G01X535371Y144746D02*
X529171D01*
G01D02*
Y141546D01*
G01D02*
X535371D01*
G01D02*
Y144746D01*
G01X529171Y145546D02*
X535371D01*
G01D02*
Y148746D01*
G01D02*
X529171D01*
G01D02*
Y145546D01*
G01X540089Y141815D02*
X546289D01*
G01Y145015D02*
X540089D01*
G01D02*
Y141815D01*
G01X546289Y157015D02*
X540089D01*
G01X535371Y156746D02*
X529171D01*
G01X529034Y165729D02*
X535234D01*
G01D02*
Y168929D01*
G01D02*
X529034D01*
G01D02*
Y165729D01*
G01X540089Y161815D02*
X546289D01*
G01Y165015D02*
X540089D01*
G01D02*
Y161815D01*
G01X529171Y161546D02*
X535371D01*
G01D02*
Y164746D01*
G01D02*
X529171D01*
G01D02*
Y161546D01*
G01X540089Y161015D02*
Y157815D01*
G01X546289Y161015D02*
X540089D01*
G01Y157815D02*
X546289D01*
G01X532168Y187944D02*
Y181744D01*
G01D02*
X535368D01*
G01D02*
Y187944D01*
G01X536328Y187958D02*
Y181758D01*
G01D02*
X539528D01*
G01D02*
Y187958D01*
G01X530872Y181784D02*
Y187984D01*
G01X527672D02*
Y181784D01*
G01D02*
X530872D01*
G01X540402Y187951D02*
Y181751D01*
G01D02*
X543602D01*
G01X535368Y187944D02*
X532168D01*
G01X539528Y187958D02*
X536328D01*
G01X530872Y187984D02*
X527672D01*
G01X543602Y187951D02*
X540402D01*
G01X534100Y214500D02*
X528400D01*
G01X534100D02*
Y223300D01*
G01X540100Y214600D02*
Y217600D01*
G01X543200Y217700D02*
X537000D01*
Y214500D01*
X543200D01*
Y217700D01*
G01X544907Y224742D02*
X545137Y224897D01*
X545405Y225000D01*
X545712D01*
X546057Y224845D01*
X546325Y224587D01*
X546517Y224277D01*
X546670Y223760D01*
X546708Y223295D01*
X546632Y222830D01*
X546517Y222520D01*
X546287Y222210D01*
X546018Y222003D01*
X545750Y221900D01*
X545482D01*
X545213Y222003D01*
X544983Y222158D01*
X544792Y222365D01*
G01X543493D02*
X543263Y222107D01*
X542995Y221952D01*
X542650Y221900D01*
X542305Y222003D01*
X542037Y222210D01*
X541845Y222572D01*
X541807Y222985D01*
X541883Y223398D01*
X542075Y223657D01*
X542343Y223863D01*
X542612Y223915D01*
X542880Y223863D01*
X543225Y223657D01*
X543110Y225000D01*
X542075D01*
G01X540202Y222262D02*
X539933Y222003D01*
X539627Y221900D01*
X539320Y222003D01*
X539052Y222313D01*
X538860Y222778D01*
X538783Y223243D01*
Y223812D01*
X538860Y224277D01*
X539052Y224690D01*
X539282Y224897D01*
X539550Y225000D01*
X539857Y224897D01*
X540087Y224690D01*
X540240Y224380D01*
X540317Y223967D01*
X540240Y223605D01*
X540048Y223243D01*
X539818Y223037D01*
X539550Y222985D01*
X539243Y223088D01*
X539013Y223347D01*
X538783Y223812D01*
G01X536450Y221900D02*
X536182Y221952D01*
X535875Y222107D01*
X535683Y222365D01*
X535607Y222727D01*
X535683Y223088D01*
X535913Y223398D01*
X536258Y223553D01*
X536642D01*
X536872Y223657D01*
X537063Y223915D01*
X537140Y224277D01*
X537025Y224638D01*
X536757Y224897D01*
X536450Y225000D01*
X536143Y224897D01*
X535875Y224638D01*
X535760Y224277D01*
X535837Y223915D01*
X536028Y223657D01*
X536258Y223553D01*
X536642D01*
X536987Y223398D01*
X537217Y223088D01*
X537293Y222727D01*
X537217Y222365D01*
X537025Y222107D01*
X536718Y221952D01*
X536450Y221900D01*
G01X538205Y406621D02*
Y421621D01*
G01X531405D02*
Y406621D01*
G01X538105D02*
X531505D01*
G01X538105Y421621D02*
X531505D01*
G01X538105Y414621D02*
X531505D01*
G01X538105Y413621D02*
X531505D01*
G01X540679Y409320D02*
X550879D01*
G01Y413920D02*
X540679D01*
G01D02*
Y409320D01*
G01X531505Y454390D02*
X531660Y454160D01*
X531763Y453892D01*
Y453585D01*
X531608Y453240D01*
X531350Y452972D01*
X531040Y452780D01*
X530523Y452627D01*
X530058Y452589D01*
X529593Y452665D01*
X529283Y452780D01*
X528973Y453010D01*
X528766Y453279D01*
X528663Y453547D01*
Y453815D01*
X528766Y454084D01*
X528921Y454314D01*
X529128Y454505D01*
G01X528663Y456647D02*
X531763D01*
X531143Y456187D01*
G01X528663D02*
Y457107D01*
G01X529025Y459095D02*
X528766Y459364D01*
X528663Y459670D01*
X528766Y459977D01*
X529076Y460245D01*
X529541Y460437D01*
X530006Y460514D01*
X530575D01*
X531040Y460437D01*
X531453Y460245D01*
X531660Y460015D01*
X531763Y459747D01*
X531660Y459440D01*
X531453Y459210D01*
X531143Y459057D01*
X530730Y458980D01*
X530368Y459057D01*
X530006Y459249D01*
X529800Y459479D01*
X529748Y459747D01*
X529851Y460054D01*
X530110Y460284D01*
X530575Y460514D01*
G01X529955Y462119D02*
X530316Y462387D01*
X530523Y462617D01*
X530626Y462924D01*
X530523Y463192D01*
X530316Y463384D01*
X530006Y463537D01*
X529645Y463575D01*
X529335Y463537D01*
X529025Y463384D01*
X528766Y463154D01*
X528663Y462885D01*
X528766Y462579D01*
X529076Y462310D01*
X529541Y462157D01*
X530058Y462119D01*
X530730Y462195D01*
X531091Y462310D01*
X531453Y462502D01*
X531711Y462770D01*
X531763Y463039D01*
X531660Y463307D01*
X531401Y463499D01*
G01X532838Y451823D02*
X529638D01*
G01X532838Y445623D02*
Y451823D01*
G01X529638Y445623D02*
X532838D01*
G01X529638Y451823D02*
Y445623D01*
G01X532738Y448723D02*
X529738D01*
G01X538258Y457630D02*
X538488Y457785D01*
X538756Y457888D01*
X539063D01*
X539408Y457733D01*
X539676Y457475D01*
X539868Y457165D01*
X540021Y456648D01*
X540059Y456183D01*
X539983Y455718D01*
X539868Y455408D01*
X539638Y455098D01*
X539369Y454891D01*
X539101Y454788D01*
X538833D01*
X538564Y454891D01*
X538334Y455046D01*
X538143Y455253D01*
G01X536844D02*
X536614Y454995D01*
X536346Y454840D01*
X536001Y454788D01*
X535656Y454891D01*
X535388Y455098D01*
X535196Y455460D01*
X535158Y455873D01*
X535234Y456286D01*
X535426Y456545D01*
X535694Y456751D01*
X535963Y456803D01*
X536231Y456751D01*
X536576Y456545D01*
X536461Y457888D01*
X535426D01*
G01X534238Y454023D02*
Y450823D01*
G01X540438D02*
Y454023D01*
G01X534238Y450823D02*
X540438D01*
G01X537338Y453923D02*
Y450923D01*
G01X540438Y454023D02*
X534238D01*
G01X531132Y471225D02*
X531362Y471380D01*
X531630Y471483D01*
X531937D01*
X532282Y471328D01*
X532550Y471070D01*
X532742Y470760D01*
X532895Y470243D01*
X532933Y469778D01*
X532857Y469313D01*
X532742Y469003D01*
X532512Y468693D01*
X532243Y468486D01*
X531975Y468383D01*
X531707D01*
X531438Y468486D01*
X531208Y468641D01*
X531017Y468848D01*
G01X528875Y468383D02*
X528607Y468435D01*
X528300Y468590D01*
X528108Y468848D01*
X528032Y469210D01*
X528108Y469571D01*
X528338Y469881D01*
X528683Y470036D01*
X529067D01*
X529297Y470140D01*
X529488Y470398D01*
X529565Y470760D01*
X529450Y471121D01*
X529182Y471380D01*
X528875Y471483D01*
X528568Y471380D01*
X528300Y471121D01*
X528185Y470760D01*
X528262Y470398D01*
X528453Y470140D01*
X528683Y470036D01*
X529067D01*
X529412Y469881D01*
X529642Y469571D01*
X529718Y469210D01*
X529642Y468848D01*
X529450Y468590D01*
X529143Y468435D01*
X528875Y468383D01*
G01X536938Y471923D02*
Y468923D01*
G01X533838Y468823D02*
X540038D01*
G01D02*
Y472023D01*
G01X533838D02*
Y468823D01*
G01X538258Y465218D02*
X538488Y465373D01*
X538756Y465476D01*
X539063D01*
X539408Y465321D01*
X539676Y465063D01*
X539868Y464753D01*
X540021Y464236D01*
X540059Y463771D01*
X539983Y463306D01*
X539868Y462996D01*
X539638Y462686D01*
X539369Y462479D01*
X539101Y462376D01*
X538833D01*
X538564Y462479D01*
X538334Y462634D01*
X538143Y462841D01*
G01X536844Y462996D02*
X536614Y462634D01*
X536308Y462428D01*
X535963Y462376D01*
X535656Y462428D01*
X535349Y462686D01*
X535158Y462996D01*
X535119Y463306D01*
X535196Y463668D01*
X535464Y463926D01*
X535733Y464029D01*
X536078D01*
G01X535733D02*
X535503Y464184D01*
X535311Y464443D01*
X535234Y464753D01*
X535311Y465063D01*
X535503Y465321D01*
X535848Y465476D01*
X536193Y465424D01*
X536538Y465218D01*
G01X534238Y461723D02*
Y458523D01*
G01X540438Y461723D02*
X534238D01*
G01X540438Y458523D02*
Y461723D01*
G01X534238Y458523D02*
X540438D01*
G01X537338Y461623D02*
Y458623D01*
G01X540038Y472023D02*
X533838D01*
G01X529938Y472823D02*
Y479023D01*
G01X526838Y475923D02*
X529838D01*
G01X529938Y479023D02*
X526738D01*
G01D02*
Y472823D01*
G01D02*
X529938D01*
G01X541891Y482125D02*
Y485225D01*
X540932D01*
X540626Y485070D01*
X540434Y484863D01*
X540357Y484450D01*
X540434Y484037D01*
X540664Y483778D01*
X540932Y483623D01*
X541891D01*
G01X540932D02*
X540357Y482125D01*
G01X538867Y482590D02*
X538637Y482332D01*
X538369Y482177D01*
X538024Y482125D01*
X537679Y482228D01*
X537411Y482435D01*
X537219Y482797D01*
X537181Y483210D01*
X537257Y483623D01*
X537449Y483882D01*
X537717Y484088D01*
X537986Y484140D01*
X538254Y484088D01*
X538599Y483882D01*
X538484Y485225D01*
X537449D01*
G01X536202Y485227D02*
X530002D01*
G01Y482027D02*
X536202D01*
G01D02*
Y485227D01*
G01X530002D02*
Y482027D01*
G01X533290Y516943D02*
X533445Y516713D01*
X533548Y516445D01*
Y516138D01*
X533393Y515793D01*
X533135Y515525D01*
X532825Y515333D01*
X532308Y515180D01*
X531843Y515142D01*
X531378Y515218D01*
X531068Y515333D01*
X530758Y515563D01*
X530551Y515832D01*
X530448Y516100D01*
Y516368D01*
X530551Y516637D01*
X530706Y516867D01*
X530913Y517058D01*
G01X530448Y519200D02*
X530500Y519468D01*
X530655Y519775D01*
X530913Y519967D01*
X531275Y520043D01*
X531636Y519967D01*
X531946Y519737D01*
X532101Y519392D01*
Y519008D01*
X532205Y518778D01*
X532463Y518587D01*
X532825Y518510D01*
X533186Y518625D01*
X533445Y518893D01*
X533548Y519200D01*
X533445Y519507D01*
X533186Y519775D01*
X532825Y519890D01*
X532463Y519813D01*
X532205Y519622D01*
X532101Y519392D01*
Y519008D01*
X531946Y518663D01*
X531636Y518433D01*
X531275Y518357D01*
X530913Y518433D01*
X530655Y518625D01*
X530500Y518932D01*
X530448Y519200D01*
G01X530810Y521648D02*
X530551Y521917D01*
X530448Y522223D01*
X530551Y522530D01*
X530861Y522798D01*
X531326Y522990D01*
X531791Y523067D01*
X532360D01*
X532825Y522990D01*
X533238Y522798D01*
X533445Y522568D01*
X533548Y522300D01*
X533445Y521993D01*
X533238Y521763D01*
X532928Y521610D01*
X532515Y521533D01*
X532153Y521610D01*
X531791Y521802D01*
X531585Y522032D01*
X531533Y522300D01*
X531636Y522607D01*
X531895Y522837D01*
X532360Y523067D01*
G01X533031Y524672D02*
X533341Y524902D01*
X533496Y525170D01*
X533548Y525477D01*
X533445Y525860D01*
X533186Y526128D01*
X532876Y526205D01*
X532566Y526167D01*
X532308Y526013D01*
X531791Y525247D01*
X531430Y524902D01*
X530913Y524672D01*
X530448Y524595D01*
Y526205D01*
G01X542360Y516943D02*
X542515Y516713D01*
X542618Y516445D01*
Y516138D01*
X542463Y515793D01*
X542205Y515525D01*
X541895Y515333D01*
X541378Y515180D01*
X540913Y515142D01*
X540448Y515218D01*
X540138Y515333D01*
X539828Y515563D01*
X539621Y515832D01*
X539518Y516100D01*
Y516368D01*
X539621Y516637D01*
X539776Y516867D01*
X539983Y517058D01*
G01X539518Y519200D02*
X539570Y519468D01*
X539725Y519775D01*
X539983Y519967D01*
X540345Y520043D01*
X540706Y519967D01*
X541016Y519737D01*
X541171Y519392D01*
Y519008D01*
X541275Y518778D01*
X541533Y518587D01*
X541895Y518510D01*
X542256Y518625D01*
X542515Y518893D01*
X542618Y519200D01*
X542515Y519507D01*
X542256Y519775D01*
X541895Y519890D01*
X541533Y519813D01*
X541275Y519622D01*
X541171Y519392D01*
Y519008D01*
X541016Y518663D01*
X540706Y518433D01*
X540345Y518357D01*
X539983Y518433D01*
X539725Y518625D01*
X539570Y518932D01*
X539518Y519200D01*
G01Y522223D02*
X540190Y522300D01*
X540758Y522415D01*
X541275Y522568D01*
X541843Y522760D01*
X542618Y523067D01*
Y521533D01*
G01X539880Y524748D02*
X539621Y525017D01*
X539518Y525323D01*
X539621Y525630D01*
X539931Y525898D01*
X540396Y526090D01*
X540861Y526167D01*
X541430D01*
X541895Y526090D01*
X542308Y525898D01*
X542515Y525668D01*
X542618Y525400D01*
X542515Y525093D01*
X542308Y524863D01*
X541998Y524710D01*
X541585Y524633D01*
X541223Y524710D01*
X540861Y524902D01*
X540655Y525132D01*
X540603Y525400D01*
X540706Y525707D01*
X540965Y525937D01*
X541430Y526167D01*
G01X537230Y516943D02*
X537385Y516713D01*
X537488Y516445D01*
Y516138D01*
X537333Y515793D01*
X537075Y515525D01*
X536765Y515333D01*
X536248Y515180D01*
X535783Y515142D01*
X535318Y515218D01*
X535008Y515333D01*
X534698Y515563D01*
X534491Y515832D01*
X534388Y516100D01*
Y516368D01*
X534491Y516637D01*
X534646Y516867D01*
X534853Y517058D01*
G01X534388Y519200D02*
X534440Y519468D01*
X534595Y519775D01*
X534853Y519967D01*
X535215Y520043D01*
X535576Y519967D01*
X535886Y519737D01*
X536041Y519392D01*
Y519008D01*
X536145Y518778D01*
X536403Y518587D01*
X536765Y518510D01*
X537126Y518625D01*
X537385Y518893D01*
X537488Y519200D01*
X537385Y519507D01*
X537126Y519775D01*
X536765Y519890D01*
X536403Y519813D01*
X536145Y519622D01*
X536041Y519392D01*
Y519008D01*
X535886Y518663D01*
X535576Y518433D01*
X535215Y518357D01*
X534853Y518433D01*
X534595Y518625D01*
X534440Y518932D01*
X534388Y519200D01*
G01X535680Y521572D02*
X536041Y521840D01*
X536248Y522070D01*
X536351Y522377D01*
X536248Y522645D01*
X536041Y522837D01*
X535731Y522990D01*
X535370Y523028D01*
X535060Y522990D01*
X534750Y522837D01*
X534491Y522607D01*
X534388Y522338D01*
X534491Y522032D01*
X534801Y521763D01*
X535266Y521610D01*
X535783Y521572D01*
X536455Y521648D01*
X536816Y521763D01*
X537178Y521955D01*
X537436Y522223D01*
X537488Y522492D01*
X537385Y522760D01*
X537126Y522952D01*
G01X534388Y525400D02*
X537488D01*
X536868Y524940D01*
G01X534388D02*
Y525860D01*
G01X528238Y531825D02*
Y538025D01*
G01X532138Y531825D02*
Y538025D01*
G01X528938Y531825D02*
X532138D01*
G01X528938Y538025D02*
Y531825D01*
G01X539938Y531725D02*
X543138D01*
G01X539938Y537925D02*
Y531725D01*
G01X536038Y531825D02*
Y538025D01*
G01X532838Y531825D02*
X536038D01*
G01X532838Y538025D02*
Y531825D01*
G01X537421Y544727D02*
X537651Y544882D01*
X537919Y544985D01*
X538226D01*
X538571Y544830D01*
X538839Y544572D01*
X539031Y544262D01*
X539184Y543745D01*
X539222Y543280D01*
X539146Y542815D01*
X539031Y542505D01*
X538801Y542195D01*
X538532Y541988D01*
X538264Y541885D01*
X537996D01*
X537727Y541988D01*
X537497Y542143D01*
X537306Y542350D01*
G01X535164Y541885D02*
X534896Y541937D01*
X534589Y542092D01*
X534397Y542350D01*
X534321Y542712D01*
X534397Y543073D01*
X534627Y543383D01*
X534972Y543538D01*
X535356D01*
X535586Y543642D01*
X535777Y543900D01*
X535854Y544262D01*
X535739Y544623D01*
X535471Y544882D01*
X535164Y544985D01*
X534857Y544882D01*
X534589Y544623D01*
X534474Y544262D01*
X534551Y543900D01*
X534742Y543642D01*
X534972Y543538D01*
X535356D01*
X535701Y543383D01*
X535931Y543073D01*
X536007Y542712D01*
X535931Y542350D01*
X535739Y542092D01*
X535432Y541937D01*
X535164Y541885D01*
G01X532716Y542247D02*
X532447Y541988D01*
X532141Y541885D01*
X531834Y541988D01*
X531566Y542298D01*
X531374Y542763D01*
X531297Y543228D01*
Y543797D01*
X531374Y544262D01*
X531566Y544675D01*
X531796Y544882D01*
X532064Y544985D01*
X532371Y544882D01*
X532601Y544675D01*
X532754Y544365D01*
X532831Y543952D01*
X532754Y543590D01*
X532562Y543228D01*
X532332Y543022D01*
X532064Y542970D01*
X531757Y543073D01*
X531527Y543332D01*
X531297Y543797D01*
G01X529807Y542350D02*
X529577Y542092D01*
X529309Y541937D01*
X528964Y541885D01*
X528619Y541988D01*
X528351Y542195D01*
X528159Y542557D01*
X528121Y542970D01*
X528197Y543383D01*
X528389Y543642D01*
X528657Y543848D01*
X528926Y543900D01*
X529194Y543848D01*
X529539Y543642D01*
X529424Y544985D01*
X528389D01*
G01X526638Y541425D02*
Y544625D01*
G01X532038Y534925D02*
X529038D01*
G01X532138Y538025D02*
X528938D01*
G01X543941Y552751D02*
X544171Y552906D01*
X544439Y553009D01*
X544746D01*
X545091Y552854D01*
X545359Y552596D01*
X545551Y552286D01*
X545704Y551769D01*
X545742Y551304D01*
X545666Y550839D01*
X545551Y550529D01*
X545321Y550219D01*
X545052Y550012D01*
X544784Y549909D01*
X544516D01*
X544247Y550012D01*
X544017Y550167D01*
X543826Y550374D01*
G01X541684Y549909D02*
X541416Y549961D01*
X541109Y550116D01*
X540917Y550374D01*
X540841Y550736D01*
X540917Y551097D01*
X541147Y551407D01*
X541492Y551562D01*
X541876D01*
X542106Y551666D01*
X542297Y551924D01*
X542374Y552286D01*
X542259Y552647D01*
X541991Y552906D01*
X541684Y553009D01*
X541377Y552906D01*
X541109Y552647D01*
X540994Y552286D01*
X541071Y551924D01*
X541262Y551666D01*
X541492Y551562D01*
X541876D01*
X542221Y551407D01*
X542451Y551097D01*
X542527Y550736D01*
X542451Y550374D01*
X542259Y550116D01*
X541952Y549961D01*
X541684Y549909D01*
G01X539312Y551201D02*
X539044Y551562D01*
X538814Y551769D01*
X538507Y551872D01*
X538239Y551769D01*
X538047Y551562D01*
X537894Y551252D01*
X537856Y550891D01*
X537894Y550581D01*
X538047Y550271D01*
X538277Y550012D01*
X538546Y549909D01*
X538852Y550012D01*
X539121Y550322D01*
X539274Y550787D01*
X539312Y551304D01*
X539236Y551976D01*
X539121Y552337D01*
X538929Y552699D01*
X538661Y552957D01*
X538392Y553009D01*
X538124Y552906D01*
X537932Y552647D01*
G01X535561Y549909D02*
X535484Y550581D01*
X535369Y551149D01*
X535216Y551666D01*
X535024Y552234D01*
X534717Y553009D01*
X536251D01*
G01X543138Y537925D02*
X539938D01*
G01X543038Y534825D02*
X540038D01*
G01X535938Y534925D02*
X532938D01*
G01X536038Y538025D02*
X532838D01*
G01X548391Y563847D02*
X548621Y564002D01*
X548889Y564105D01*
X549196D01*
X549541Y563950D01*
X549809Y563692D01*
X550001Y563382D01*
X550154Y562865D01*
X550192Y562400D01*
X550116Y561935D01*
X550001Y561625D01*
X549771Y561315D01*
X549502Y561108D01*
X549234Y561005D01*
X548966D01*
X548697Y561108D01*
X548467Y561263D01*
X548276Y561470D01*
G01X546134Y561005D02*
X545866Y561057D01*
X545559Y561212D01*
X545367Y561470D01*
X545291Y561832D01*
X545367Y562193D01*
X545597Y562503D01*
X545942Y562658D01*
X546326D01*
X546556Y562762D01*
X546747Y563020D01*
X546824Y563382D01*
X546709Y563743D01*
X546441Y564002D01*
X546134Y564105D01*
X545827Y564002D01*
X545559Y563743D01*
X545444Y563382D01*
X545521Y563020D01*
X545712Y562762D01*
X545942Y562658D01*
X546326D01*
X546671Y562503D01*
X546901Y562193D01*
X546977Y561832D01*
X546901Y561470D01*
X546709Y561212D01*
X546402Y561057D01*
X546134Y561005D01*
G01X543034D02*
X542766Y561057D01*
X542459Y561212D01*
X542267Y561470D01*
X542191Y561832D01*
X542267Y562193D01*
X542497Y562503D01*
X542842Y562658D01*
X543226D01*
X543456Y562762D01*
X543647Y563020D01*
X543724Y563382D01*
X543609Y563743D01*
X543341Y564002D01*
X543034Y564105D01*
X542727Y564002D01*
X542459Y563743D01*
X542344Y563382D01*
X542421Y563020D01*
X542612Y562762D01*
X542842Y562658D01*
X543226D01*
X543571Y562503D01*
X543801Y562193D01*
X543877Y561832D01*
X543801Y561470D01*
X543609Y561212D01*
X543302Y561057D01*
X543034Y561005D01*
G01X540586Y561367D02*
X540317Y561108D01*
X540011Y561005D01*
X539704Y561108D01*
X539436Y561418D01*
X539244Y561883D01*
X539167Y562348D01*
Y562917D01*
X539244Y563382D01*
X539436Y563795D01*
X539666Y564002D01*
X539934Y564105D01*
X540241Y564002D01*
X540471Y563795D01*
X540624Y563485D01*
X540701Y563072D01*
X540624Y562710D01*
X540432Y562348D01*
X540202Y562142D01*
X539934Y562090D01*
X539627Y562193D01*
X539397Y562452D01*
X539167Y562917D01*
G01X548642Y571495D02*
X548872Y571650D01*
X549140Y571753D01*
X549447D01*
X549792Y571598D01*
X550060Y571340D01*
X550252Y571030D01*
X550405Y570513D01*
X550443Y570048D01*
X550367Y569583D01*
X550252Y569273D01*
X550022Y568963D01*
X549753Y568756D01*
X549485Y568653D01*
X549217D01*
X548948Y568756D01*
X548718Y568911D01*
X548527Y569118D01*
G01X546385Y568653D02*
X546117Y568705D01*
X545810Y568860D01*
X545618Y569118D01*
X545542Y569480D01*
X545618Y569841D01*
X545848Y570151D01*
X546193Y570306D01*
X546577D01*
X546807Y570410D01*
X546998Y570668D01*
X547075Y571030D01*
X546960Y571391D01*
X546692Y571650D01*
X546385Y571753D01*
X546078Y571650D01*
X545810Y571391D01*
X545695Y571030D01*
X545772Y570668D01*
X545963Y570410D01*
X546193Y570306D01*
X546577D01*
X546922Y570151D01*
X547152Y569841D01*
X547228Y569480D01*
X547152Y569118D01*
X546960Y568860D01*
X546653Y568705D01*
X546385Y568653D01*
G01X544013Y569945D02*
X543745Y570306D01*
X543515Y570513D01*
X543208Y570616D01*
X542940Y570513D01*
X542748Y570306D01*
X542595Y569996D01*
X542557Y569635D01*
X542595Y569325D01*
X542748Y569015D01*
X542978Y568756D01*
X543247Y568653D01*
X543553Y568756D01*
X543822Y569066D01*
X543975Y569531D01*
X544013Y570048D01*
X543937Y570720D01*
X543822Y571081D01*
X543630Y571443D01*
X543362Y571701D01*
X543093Y571753D01*
X542825Y571650D01*
X542633Y571391D01*
G01X540913Y569945D02*
X540645Y570306D01*
X540415Y570513D01*
X540108Y570616D01*
X539840Y570513D01*
X539648Y570306D01*
X539495Y569996D01*
X539457Y569635D01*
X539495Y569325D01*
X539648Y569015D01*
X539878Y568756D01*
X540147Y568653D01*
X540453Y568756D01*
X540722Y569066D01*
X540875Y569531D01*
X540913Y570048D01*
X540837Y570720D01*
X540722Y571081D01*
X540530Y571443D01*
X540262Y571701D01*
X539993Y571753D01*
X539725Y571650D01*
X539533Y571391D01*
G01X537938Y595625D02*
X534938D01*
G01X538038Y592525D02*
Y598725D01*
G01X534838Y592525D02*
X538038D01*
G01X534838Y598725D02*
Y592525D01*
G01X533038Y592625D02*
Y598825D01*
G01X529838D02*
Y592625D01*
G01X532938Y595725D02*
X529938D01*
G01X529838Y592625D02*
X533038D01*
G01X547765Y586860D02*
X547995Y587015D01*
X548263Y587118D01*
X548570D01*
X548915Y586963D01*
X549183Y586705D01*
X549375Y586395D01*
X549528Y585878D01*
X549566Y585413D01*
X549490Y584948D01*
X549375Y584638D01*
X549145Y584328D01*
X548876Y584121D01*
X548608Y584018D01*
X548340D01*
X548071Y584121D01*
X547841Y584276D01*
X547650Y584483D01*
G01X545508Y584018D02*
X545240Y584070D01*
X544933Y584225D01*
X544741Y584483D01*
X544665Y584845D01*
X544741Y585206D01*
X544971Y585516D01*
X545316Y585671D01*
X545700D01*
X545930Y585775D01*
X546121Y586033D01*
X546198Y586395D01*
X546083Y586756D01*
X545815Y587015D01*
X545508Y587118D01*
X545201Y587015D01*
X544933Y586756D01*
X544818Y586395D01*
X544895Y586033D01*
X545086Y585775D01*
X545316Y585671D01*
X545700D01*
X546045Y585516D01*
X546275Y585206D01*
X546351Y584845D01*
X546275Y584483D01*
X546083Y584225D01*
X545776Y584070D01*
X545508Y584018D01*
G01X543136Y585310D02*
X542868Y585671D01*
X542638Y585878D01*
X542331Y585981D01*
X542063Y585878D01*
X541871Y585671D01*
X541718Y585361D01*
X541680Y585000D01*
X541718Y584690D01*
X541871Y584380D01*
X542101Y584121D01*
X542370Y584018D01*
X542676Y584121D01*
X542945Y584431D01*
X543098Y584896D01*
X543136Y585413D01*
X543060Y586085D01*
X542945Y586446D01*
X542753Y586808D01*
X542485Y587066D01*
X542216Y587118D01*
X541948Y587015D01*
X541756Y586756D01*
G01X540151Y584638D02*
X539921Y584276D01*
X539615Y584070D01*
X539270Y584018D01*
X538963Y584070D01*
X538656Y584328D01*
X538465Y584638D01*
X538426Y584948D01*
X538503Y585310D01*
X538771Y585568D01*
X539040Y585671D01*
X539385D01*
G01X539040D02*
X538810Y585826D01*
X538618Y586085D01*
X538541Y586395D01*
X538618Y586705D01*
X538810Y586963D01*
X539155Y587118D01*
X539500Y587066D01*
X539845Y586860D01*
G01X529038Y592625D02*
Y598825D01*
G01X541938Y592525D02*
Y598725D01*
G01X538738Y592525D02*
X541938D01*
G01X538738Y598725D02*
Y592525D01*
G01X541838Y595625D02*
X538838D01*
G01X538038Y598725D02*
X534838D01*
G01X539801Y603558D02*
X539956Y603328D01*
X540059Y603060D01*
Y602753D01*
X539904Y602408D01*
X539646Y602140D01*
X539336Y601948D01*
X538819Y601795D01*
X538354Y601757D01*
X537889Y601833D01*
X537579Y601948D01*
X537269Y602178D01*
X537062Y602447D01*
X536959Y602715D01*
Y602983D01*
X537062Y603252D01*
X537217Y603482D01*
X537424Y603673D01*
G01X536959Y605815D02*
X537011Y606083D01*
X537166Y606390D01*
X537424Y606582D01*
X537786Y606658D01*
X538147Y606582D01*
X538457Y606352D01*
X538612Y606007D01*
Y605623D01*
X538716Y605393D01*
X538974Y605202D01*
X539336Y605125D01*
X539697Y605240D01*
X539956Y605508D01*
X540059Y605815D01*
X539956Y606122D01*
X539697Y606390D01*
X539336Y606505D01*
X538974Y606428D01*
X538716Y606237D01*
X538612Y606007D01*
Y605623D01*
X538457Y605278D01*
X538147Y605048D01*
X537786Y604972D01*
X537424Y605048D01*
X537166Y605240D01*
X537011Y605547D01*
X536959Y605815D01*
G01X538251Y608187D02*
X538612Y608455D01*
X538819Y608685D01*
X538922Y608992D01*
X538819Y609260D01*
X538612Y609452D01*
X538302Y609605D01*
X537941Y609643D01*
X537631Y609605D01*
X537321Y609452D01*
X537062Y609222D01*
X536959Y608953D01*
X537062Y608647D01*
X537372Y608378D01*
X537837Y608225D01*
X538354Y608187D01*
X539026Y608263D01*
X539387Y608378D01*
X539749Y608570D01*
X540007Y608838D01*
X540059Y609107D01*
X539956Y609375D01*
X539697Y609567D01*
G01X536959Y612475D02*
X540059D01*
X537837Y611057D01*
Y612973D01*
G01X533038Y598825D02*
X529838D01*
G01X533479Y602618D02*
X533634Y602388D01*
X533737Y602120D01*
Y601813D01*
X533582Y601468D01*
X533324Y601200D01*
X533014Y601008D01*
X532497Y600855D01*
X532032Y600817D01*
X531567Y600893D01*
X531257Y601008D01*
X530947Y601238D01*
X530740Y601507D01*
X530637Y601775D01*
Y602043D01*
X530740Y602312D01*
X530895Y602542D01*
X531102Y602733D01*
G01X530637Y604875D02*
X530689Y605143D01*
X530844Y605450D01*
X531102Y605642D01*
X531464Y605718D01*
X531825Y605642D01*
X532135Y605412D01*
X532290Y605067D01*
Y604683D01*
X532394Y604453D01*
X532652Y604262D01*
X533014Y604185D01*
X533375Y604300D01*
X533634Y604568D01*
X533737Y604875D01*
X533634Y605182D01*
X533375Y605450D01*
X533014Y605565D01*
X532652Y605488D01*
X532394Y605297D01*
X532290Y605067D01*
Y604683D01*
X532135Y604338D01*
X531825Y604108D01*
X531464Y604032D01*
X531102Y604108D01*
X530844Y604300D01*
X530689Y604607D01*
X530637Y604875D01*
G01X531929Y607247D02*
X532290Y607515D01*
X532497Y607745D01*
X532600Y608052D01*
X532497Y608320D01*
X532290Y608512D01*
X531980Y608665D01*
X531619Y608703D01*
X531309Y608665D01*
X530999Y608512D01*
X530740Y608282D01*
X530637Y608013D01*
X530740Y607707D01*
X531050Y607438D01*
X531515Y607285D01*
X532032Y607247D01*
X532704Y607323D01*
X533065Y607438D01*
X533427Y607630D01*
X533685Y607898D01*
X533737Y608167D01*
X533634Y608435D01*
X533375Y608627D01*
G01X530999Y610423D02*
X530740Y610692D01*
X530637Y610998D01*
X530740Y611305D01*
X531050Y611573D01*
X531515Y611765D01*
X531980Y611842D01*
X532549D01*
X533014Y611765D01*
X533427Y611573D01*
X533634Y611343D01*
X533737Y611075D01*
X533634Y610768D01*
X533427Y610538D01*
X533117Y610385D01*
X532704Y610308D01*
X532342Y610385D01*
X531980Y610577D01*
X531774Y610807D01*
X531722Y611075D01*
X531825Y611382D01*
X532084Y611612D01*
X532549Y611842D01*
G01X541938Y598725D02*
X538738D01*
G01X533016Y628403D02*
X532483D01*
Y627653D01*
X532643Y627403D01*
X532829Y627236D01*
X533096Y627153D01*
X533363Y627236D01*
X533549Y627403D01*
X533709Y627653D01*
X533816Y627945D01*
X533869Y628278D01*
Y628570D01*
X533816Y628820D01*
X533709Y629111D01*
X533549Y629361D01*
X533389Y629528D01*
X533176Y629653D01*
X532989D01*
X532776Y629570D01*
X532616Y629403D01*
G01X531282Y626498D02*
Y641498D01*
G01X544192Y641392D02*
X544422Y641547D01*
X544690Y641650D01*
X544997D01*
X545342Y641495D01*
X545610Y641237D01*
X545802Y640927D01*
X545955Y640410D01*
X545993Y639945D01*
X545917Y639480D01*
X545802Y639170D01*
X545572Y638860D01*
X545303Y638653D01*
X545035Y638550D01*
X544767D01*
X544498Y638653D01*
X544268Y638808D01*
X544077Y639015D01*
G01X542587Y638912D02*
X542318Y638653D01*
X542012Y638550D01*
X541705Y638653D01*
X541437Y638963D01*
X541245Y639428D01*
X541168Y639893D01*
Y640462D01*
X541245Y640927D01*
X541437Y641340D01*
X541667Y641547D01*
X541935Y641650D01*
X542242Y641547D01*
X542472Y641340D01*
X542625Y641030D01*
X542702Y640617D01*
X542625Y640255D01*
X542433Y639893D01*
X542203Y639687D01*
X541935Y639635D01*
X541628Y639738D01*
X541398Y639997D01*
X541168Y640462D01*
G01X538835Y641650D02*
X539142Y641547D01*
X539372Y641288D01*
X539525Y640978D01*
X539640Y640565D01*
X539678Y640100D01*
X539640Y639635D01*
X539525Y639222D01*
X539372Y638912D01*
X539142Y638653D01*
X538835Y638550D01*
X538528Y638653D01*
X538298Y638912D01*
X538145Y639222D01*
X538030Y639635D01*
X537992Y640100D01*
X538030Y640565D01*
X538145Y640978D01*
X538298Y641288D01*
X538528Y641547D01*
X538835Y641650D01*
G01X536578Y639015D02*
X536348Y638757D01*
X536080Y638602D01*
X535735Y638550D01*
X535390Y638653D01*
X535122Y638860D01*
X534930Y639222D01*
X534892Y639635D01*
X534968Y640048D01*
X535160Y640307D01*
X535428Y640513D01*
X535697Y640565D01*
X535965Y640513D01*
X536310Y640307D01*
X536195Y641650D01*
X535160D01*
G01X540097Y643331D02*
X546297D01*
G01X540097Y646531D02*
Y643331D01*
G01X530261Y644276D02*
X533361D01*
Y645235D01*
X533206Y645541D01*
X532999Y645733D01*
X532586Y645810D01*
X532173Y645733D01*
X531914Y645503D01*
X531759Y645235D01*
Y644276D01*
G01Y645235D02*
X530261Y645810D01*
G01Y648143D02*
X533361D01*
X532741Y647683D01*
G01X530261D02*
Y648603D01*
G01X530881Y650400D02*
X530519Y650630D01*
X530313Y650936D01*
X530261Y651281D01*
X530313Y651588D01*
X530571Y651895D01*
X530881Y652086D01*
X531191Y652125D01*
X531553Y652048D01*
X531811Y651780D01*
X531914Y651511D01*
Y651166D01*
G01Y651511D02*
X532069Y651741D01*
X532328Y651933D01*
X532638Y652010D01*
X532948Y651933D01*
X533206Y651741D01*
X533361Y651396D01*
X533309Y651051D01*
X533103Y650706D01*
G01X533361Y654343D02*
X533258Y654036D01*
X532999Y653806D01*
X532689Y653653D01*
X532276Y653538D01*
X531811Y653500D01*
X531346Y653538D01*
X530933Y653653D01*
X530623Y653806D01*
X530364Y654036D01*
X530261Y654343D01*
X530364Y654650D01*
X530623Y654880D01*
X530933Y655033D01*
X531346Y655148D01*
X531811Y655186D01*
X532276Y655148D01*
X532689Y655033D01*
X532999Y654880D01*
X533258Y654650D01*
X533361Y654343D01*
G01X530623Y656791D02*
X530364Y657060D01*
X530261Y657366D01*
X530364Y657673D01*
X530674Y657941D01*
X531139Y658133D01*
X531604Y658210D01*
X532173D01*
X532638Y658133D01*
X533051Y657941D01*
X533258Y657711D01*
X533361Y657443D01*
X533258Y657136D01*
X533051Y656906D01*
X532741Y656753D01*
X532328Y656676D01*
X531966Y656753D01*
X531604Y656945D01*
X531398Y657175D01*
X531346Y657443D01*
X531449Y657750D01*
X531708Y657980D01*
X532173Y658210D01*
G01X529074Y643614D02*
Y646814D01*
G01X546297Y646531D02*
X540097D01*
G01X540357Y651877D02*
Y648677D01*
G01X546557Y651877D02*
X540357D01*
G01Y648677D02*
X546557D01*
G01X535840Y736556D02*
X539040D01*
G01X535840Y742756D02*
Y736556D01*
G01X539040D02*
Y742756D01*
G01X540340Y736556D02*
X543540D01*
G01X540340Y742756D02*
Y736556D01*
G01X531440Y728156D02*
X534440D01*
G01X531340Y725056D02*
X534540D01*
G01X531340Y731256D02*
Y725056D01*
G01X534540Y731256D02*
X531340D01*
G01X534540Y725056D02*
Y731256D01*
G01X526840Y736556D02*
X530040D01*
G01X526840Y742756D02*
Y736556D01*
G01X530040D02*
Y742756D01*
G01X543540Y731256D02*
X540340D01*
G01Y725056D02*
X543540D01*
G01X540340Y731256D02*
Y725056D01*
G01X534540Y736556D02*
Y742756D01*
G01X531340Y736556D02*
X534540D01*
G01X531340Y742756D02*
Y736556D01*
G01X539040Y731256D02*
X535840D01*
G01X539040Y725056D02*
Y731256D01*
G01X535840Y725056D02*
X539040D01*
G01X535840Y731256D02*
Y725056D01*
G01X530040Y731256D02*
X526840D01*
G01Y725056D02*
X530040D01*
G01X526840Y731256D02*
Y725056D01*
G01X530040D02*
Y731256D01*
G01X535940Y739656D02*
X538940D01*
G01X539040Y742756D02*
X535840D01*
G01X540440Y739656D02*
X543440D01*
G01X543540Y742756D02*
X540340D01*
G01X526940Y739656D02*
X529940D01*
G01X530040Y742756D02*
X526840D01*
G01X537153Y745695D02*
X540253D01*
Y746654D01*
X540098Y746960D01*
X539891Y747152D01*
X539478Y747229D01*
X539065Y747152D01*
X538806Y746922D01*
X538651Y746654D01*
Y745695D01*
G01Y746654D02*
X537153Y747229D01*
G01Y749562D02*
X537205Y749830D01*
X537360Y750137D01*
X537618Y750329D01*
X537980Y750405D01*
X538341Y750329D01*
X538651Y750099D01*
X538806Y749754D01*
Y749370D01*
X538910Y749140D01*
X539168Y748949D01*
X539530Y748872D01*
X539891Y748987D01*
X540150Y749255D01*
X540253Y749562D01*
X540150Y749869D01*
X539891Y750137D01*
X539530Y750252D01*
X539168Y750175D01*
X538910Y749984D01*
X538806Y749754D01*
Y749370D01*
X538651Y749025D01*
X538341Y748795D01*
X537980Y748719D01*
X537618Y748795D01*
X537360Y748987D01*
X537205Y749294D01*
X537153Y749562D01*
G01X538445Y751934D02*
X538806Y752202D01*
X539013Y752432D01*
X539116Y752739D01*
X539013Y753007D01*
X538806Y753199D01*
X538496Y753352D01*
X538135Y753390D01*
X537825Y753352D01*
X537515Y753199D01*
X537256Y752969D01*
X537153Y752700D01*
X537256Y752394D01*
X537566Y752125D01*
X538031Y751972D01*
X538548Y751934D01*
X539220Y752010D01*
X539581Y752125D01*
X539943Y752317D01*
X540201Y752585D01*
X540253Y752854D01*
X540150Y753122D01*
X539891Y753314D01*
G01X537153Y756222D02*
X540253D01*
X538031Y754804D01*
Y756720D01*
G01X541653Y745695D02*
X544753D01*
Y746654D01*
X544598Y746960D01*
X544391Y747152D01*
X543978Y747229D01*
X543565Y747152D01*
X543306Y746922D01*
X543151Y746654D01*
Y745695D01*
G01Y746654D02*
X541653Y747229D01*
G01Y749562D02*
X541705Y749830D01*
X541860Y750137D01*
X542118Y750329D01*
X542480Y750405D01*
X542841Y750329D01*
X543151Y750099D01*
X543306Y749754D01*
Y749370D01*
X543410Y749140D01*
X543668Y748949D01*
X544030Y748872D01*
X544391Y748987D01*
X544650Y749255D01*
X544753Y749562D01*
X544650Y749869D01*
X544391Y750137D01*
X544030Y750252D01*
X543668Y750175D01*
X543410Y749984D01*
X543306Y749754D01*
Y749370D01*
X543151Y749025D01*
X542841Y748795D01*
X542480Y748719D01*
X542118Y748795D01*
X541860Y748987D01*
X541705Y749294D01*
X541653Y749562D01*
G01X542945Y751934D02*
X543306Y752202D01*
X543513Y752432D01*
X543616Y752739D01*
X543513Y753007D01*
X543306Y753199D01*
X542996Y753352D01*
X542635Y753390D01*
X542325Y753352D01*
X542015Y753199D01*
X541756Y752969D01*
X541653Y752700D01*
X541756Y752394D01*
X542066Y752125D01*
X542531Y751972D01*
X543048Y751934D01*
X543720Y752010D01*
X544081Y752125D01*
X544443Y752317D01*
X544701Y752585D01*
X544753Y752854D01*
X544650Y753122D01*
X544391Y753314D01*
G01X541653Y755762D02*
X544753D01*
X544133Y755302D01*
G01X541653D02*
Y756222D01*
G01X532913Y745695D02*
X536013D01*
Y746654D01*
X535858Y746960D01*
X535651Y747152D01*
X535238Y747229D01*
X534825Y747152D01*
X534566Y746922D01*
X534411Y746654D01*
Y745695D01*
G01Y746654D02*
X532913Y747229D01*
G01Y749562D02*
X532965Y749830D01*
X533120Y750137D01*
X533378Y750329D01*
X533740Y750405D01*
X534101Y750329D01*
X534411Y750099D01*
X534566Y749754D01*
Y749370D01*
X534670Y749140D01*
X534928Y748949D01*
X535290Y748872D01*
X535651Y748987D01*
X535910Y749255D01*
X536013Y749562D01*
X535910Y749869D01*
X535651Y750137D01*
X535290Y750252D01*
X534928Y750175D01*
X534670Y749984D01*
X534566Y749754D01*
Y749370D01*
X534411Y749025D01*
X534101Y748795D01*
X533740Y748719D01*
X533378Y748795D01*
X533120Y748987D01*
X532965Y749294D01*
X532913Y749562D01*
G01X534205Y751934D02*
X534566Y752202D01*
X534773Y752432D01*
X534876Y752739D01*
X534773Y753007D01*
X534566Y753199D01*
X534256Y753352D01*
X533895Y753390D01*
X533585Y753352D01*
X533275Y753199D01*
X533016Y752969D01*
X532913Y752700D01*
X533016Y752394D01*
X533326Y752125D01*
X533791Y751972D01*
X534308Y751934D01*
X534980Y752010D01*
X535341Y752125D01*
X535703Y752317D01*
X535961Y752585D01*
X536013Y752854D01*
X535910Y753122D01*
X535651Y753314D01*
G01X532913Y755685D02*
X533585Y755762D01*
X534153Y755877D01*
X534670Y756030D01*
X535238Y756222D01*
X536013Y756529D01*
Y754995D01*
G01X534540Y742756D02*
X531340D01*
G01X528645Y745695D02*
X531745D01*
Y746654D01*
X531590Y746960D01*
X531383Y747152D01*
X530970Y747229D01*
X530557Y747152D01*
X530298Y746922D01*
X530143Y746654D01*
Y745695D01*
G01Y746654D02*
X528645Y747229D01*
G01Y749562D02*
X528697Y749830D01*
X528852Y750137D01*
X529110Y750329D01*
X529472Y750405D01*
X529833Y750329D01*
X530143Y750099D01*
X530298Y749754D01*
Y749370D01*
X530402Y749140D01*
X530660Y748949D01*
X531022Y748872D01*
X531383Y748987D01*
X531642Y749255D01*
X531745Y749562D01*
X531642Y749869D01*
X531383Y750137D01*
X531022Y750252D01*
X530660Y750175D01*
X530402Y749984D01*
X530298Y749754D01*
Y749370D01*
X530143Y749025D01*
X529833Y748795D01*
X529472Y748719D01*
X529110Y748795D01*
X528852Y748987D01*
X528697Y749294D01*
X528645Y749562D01*
G01Y752585D02*
X529317Y752662D01*
X529885Y752777D01*
X530402Y752930D01*
X530970Y753122D01*
X531745Y753429D01*
Y751895D01*
G01Y755762D02*
X531642Y755455D01*
X531383Y755225D01*
X531073Y755072D01*
X530660Y754957D01*
X530195Y754919D01*
X529730Y754957D01*
X529317Y755072D01*
X529007Y755225D01*
X528748Y755455D01*
X528645Y755762D01*
X528748Y756069D01*
X529007Y756299D01*
X529317Y756452D01*
X529730Y756567D01*
X530195Y756605D01*
X530660Y756567D01*
X531073Y756452D01*
X531383Y756299D01*
X531642Y756069D01*
X531745Y755762D01*
G01X542185Y759623D02*
X542340Y759393D01*
X542443Y759125D01*
Y758818D01*
X542288Y758473D01*
X542030Y758205D01*
X541720Y758013D01*
X541203Y757860D01*
X540738Y757822D01*
X540273Y757898D01*
X539963Y758013D01*
X539653Y758243D01*
X539446Y758512D01*
X539343Y758780D01*
Y759048D01*
X539446Y759317D01*
X539601Y759547D01*
X539808Y759738D01*
G01X540635Y761152D02*
X540996Y761420D01*
X541203Y761650D01*
X541306Y761957D01*
X541203Y762225D01*
X540996Y762417D01*
X540686Y762570D01*
X540325Y762608D01*
X540015Y762570D01*
X539705Y762417D01*
X539446Y762187D01*
X539343Y761918D01*
X539446Y761612D01*
X539756Y761343D01*
X540221Y761190D01*
X540738Y761152D01*
X541410Y761228D01*
X541771Y761343D01*
X542133Y761535D01*
X542391Y761803D01*
X542443Y762072D01*
X542340Y762340D01*
X542081Y762532D01*
G01X541926Y764252D02*
X542236Y764482D01*
X542391Y764750D01*
X542443Y765057D01*
X542340Y765440D01*
X542081Y765708D01*
X541771Y765785D01*
X541461Y765747D01*
X541203Y765593D01*
X540686Y764827D01*
X540325Y764482D01*
X539808Y764252D01*
X539343Y764175D01*
Y765785D01*
G01Y768003D02*
X540015Y768080D01*
X540583Y768195D01*
X541100Y768348D01*
X541668Y768540D01*
X542443Y768847D01*
Y767313D01*
G01X533417Y759623D02*
X533572Y759393D01*
X533675Y759125D01*
Y758818D01*
X533520Y758473D01*
X533262Y758205D01*
X532952Y758013D01*
X532435Y757860D01*
X531970Y757822D01*
X531505Y757898D01*
X531195Y758013D01*
X530885Y758243D01*
X530678Y758512D01*
X530575Y758780D01*
Y759048D01*
X530678Y759317D01*
X530833Y759547D01*
X531040Y759738D01*
G01X531867Y761152D02*
X532228Y761420D01*
X532435Y761650D01*
X532538Y761957D01*
X532435Y762225D01*
X532228Y762417D01*
X531918Y762570D01*
X531557Y762608D01*
X531247Y762570D01*
X530937Y762417D01*
X530678Y762187D01*
X530575Y761918D01*
X530678Y761612D01*
X530988Y761343D01*
X531453Y761190D01*
X531970Y761152D01*
X532642Y761228D01*
X533003Y761343D01*
X533365Y761535D01*
X533623Y761803D01*
X533675Y762072D01*
X533572Y762340D01*
X533313Y762532D01*
G01X531195Y764137D02*
X530833Y764367D01*
X530627Y764673D01*
X530575Y765018D01*
X530627Y765325D01*
X530885Y765632D01*
X531195Y765823D01*
X531505Y765862D01*
X531867Y765785D01*
X532125Y765517D01*
X532228Y765248D01*
Y764903D01*
G01Y765248D02*
X532383Y765478D01*
X532642Y765670D01*
X532952Y765747D01*
X533262Y765670D01*
X533520Y765478D01*
X533675Y765133D01*
X533623Y764788D01*
X533417Y764443D01*
G01X531195Y767237D02*
X530833Y767467D01*
X530627Y767773D01*
X530575Y768118D01*
X530627Y768425D01*
X530885Y768732D01*
X531195Y768923D01*
X531505Y768962D01*
X531867Y768885D01*
X532125Y768617D01*
X532228Y768348D01*
Y768003D01*
G01Y768348D02*
X532383Y768578D01*
X532642Y768770D01*
X532952Y768847D01*
X533262Y768770D01*
X533520Y768578D01*
X533675Y768233D01*
X533623Y767888D01*
X533417Y767543D01*
G01X537685Y759623D02*
X537840Y759393D01*
X537943Y759125D01*
Y758818D01*
X537788Y758473D01*
X537530Y758205D01*
X537220Y758013D01*
X536703Y757860D01*
X536238Y757822D01*
X535773Y757898D01*
X535463Y758013D01*
X535153Y758243D01*
X534946Y758512D01*
X534843Y758780D01*
Y759048D01*
X534946Y759317D01*
X535101Y759547D01*
X535308Y759738D01*
G01X536135Y761152D02*
X536496Y761420D01*
X536703Y761650D01*
X536806Y761957D01*
X536703Y762225D01*
X536496Y762417D01*
X536186Y762570D01*
X535825Y762608D01*
X535515Y762570D01*
X535205Y762417D01*
X534946Y762187D01*
X534843Y761918D01*
X534946Y761612D01*
X535256Y761343D01*
X535721Y761190D01*
X536238Y761152D01*
X536910Y761228D01*
X537271Y761343D01*
X537633Y761535D01*
X537891Y761803D01*
X537943Y762072D01*
X537840Y762340D01*
X537581Y762532D01*
G01X535463Y764137D02*
X535101Y764367D01*
X534895Y764673D01*
X534843Y765018D01*
X534895Y765325D01*
X535153Y765632D01*
X535463Y765823D01*
X535773Y765862D01*
X536135Y765785D01*
X536393Y765517D01*
X536496Y765248D01*
Y764903D01*
G01Y765248D02*
X536651Y765478D01*
X536910Y765670D01*
X537220Y765747D01*
X537530Y765670D01*
X537788Y765478D01*
X537943Y765133D01*
X537891Y764788D01*
X537685Y764443D01*
G01X537943Y768080D02*
X537840Y767773D01*
X537581Y767543D01*
X537271Y767390D01*
X536858Y767275D01*
X536393Y767237D01*
X535928Y767275D01*
X535515Y767390D01*
X535205Y767543D01*
X534946Y767773D01*
X534843Y768080D01*
X534946Y768387D01*
X535205Y768617D01*
X535515Y768770D01*
X535928Y768885D01*
X536393Y768923D01*
X536858Y768885D01*
X537271Y768770D01*
X537581Y768617D01*
X537840Y768387D01*
X537943Y768080D01*
G01X537800Y782281D02*
X530000D01*
G01X557286Y91483D02*
X557056Y91793D01*
X556788Y91948D01*
X556481Y92000D01*
X556098Y91897D01*
X555830Y91638D01*
X555753Y91328D01*
X555791Y91018D01*
X555945Y90760D01*
X556711Y90243D01*
X557056Y89882D01*
X557286Y89365D01*
X557363Y88900D01*
X555753D01*
G01X547029Y86643D02*
Y89743D01*
X547489Y89123D01*
G01Y86643D02*
X546569D01*
G01X546289Y133815D02*
Y137015D01*
G01Y137815D02*
Y141015D01*
G01Y149815D02*
Y153015D01*
G01Y153815D02*
Y157015D01*
G01Y145815D02*
Y149015D01*
G01Y141815D02*
Y145015D01*
G01X555174Y147674D02*
X561374D01*
G01X555174Y150874D02*
Y147674D01*
G01X561374Y150874D02*
X555174D01*
G01X546289Y161815D02*
Y165015D01*
G01X556279Y160941D02*
Y164141D01*
G01X550079Y160941D02*
X556279D01*
G01Y164141D02*
X550079D01*
G01D02*
Y160941D01*
G01X546289Y157815D02*
Y161015D01*
G01X560538Y184623D02*
X554338D01*
G01D02*
Y181423D01*
G01D02*
X560538D01*
G01X557438Y181523D02*
Y184523D01*
G01X543602Y181751D02*
Y187951D01*
G01X544400D02*
Y181751D01*
X547600D01*
Y187951D01*
X544400D01*
G01X557231Y241101D02*
X551031D01*
G01D02*
Y237901D01*
G01D02*
X557231D01*
G01D02*
Y241101D01*
G01X554131Y238001D02*
Y241001D01*
G01X557274Y244995D02*
X551074D01*
G01D02*
Y241795D01*
G01D02*
X557274D01*
G01D02*
Y244995D01*
G01X554174Y241895D02*
Y244895D01*
G01X557274Y249195D02*
X551074D01*
G01D02*
Y245995D01*
G01D02*
X557274D01*
G01D02*
Y249195D01*
G01X554174Y246095D02*
Y249095D01*
G01X558219Y263731D02*
X558449Y263886D01*
X558717Y263989D01*
X559024D01*
X559369Y263834D01*
X559637Y263576D01*
X559829Y263266D01*
X559982Y262749D01*
X560020Y262284D01*
X559944Y261819D01*
X559829Y261509D01*
X559599Y261199D01*
X559330Y260992D01*
X559062Y260889D01*
X558794D01*
X558525Y260992D01*
X558295Y261147D01*
X558104Y261354D01*
G01X556805Y261509D02*
X556575Y261147D01*
X556269Y260941D01*
X555924Y260889D01*
X555617Y260941D01*
X555310Y261199D01*
X555119Y261509D01*
X555080Y261819D01*
X555157Y262181D01*
X555425Y262439D01*
X555694Y262542D01*
X556039D01*
G01X555694D02*
X555464Y262697D01*
X555272Y262956D01*
X555195Y263266D01*
X555272Y263576D01*
X555464Y263834D01*
X555809Y263989D01*
X556154Y263937D01*
X556499Y263731D01*
G01X552402Y260889D02*
Y263989D01*
X553820Y261767D01*
X551904D01*
G01X550490Y263472D02*
X550260Y263782D01*
X549992Y263937D01*
X549685Y263989D01*
X549302Y263886D01*
X549034Y263627D01*
X548957Y263317D01*
X548995Y263007D01*
X549149Y262749D01*
X549915Y262232D01*
X550260Y261871D01*
X550490Y261354D01*
X550567Y260889D01*
X548957D01*
G01X557274Y259695D02*
X551074D01*
G01D02*
Y256495D01*
G01D02*
X557274D01*
G01D02*
Y259695D01*
G01X554174Y256595D02*
Y259595D01*
G01X558774Y273695D02*
X555574D01*
G01D02*
Y267495D01*
G01D02*
X558774D01*
G01X555674Y270595D02*
X558674D01*
G01X550495Y415320D02*
Y418420D01*
X549536D01*
X549230Y418265D01*
X549038Y418058D01*
X548961Y417645D01*
X549038Y417232D01*
X549268Y416973D01*
X549536Y416818D01*
X550495D01*
G01X549536D02*
X548961Y415320D01*
G01X546628D02*
Y418420D01*
X547088Y417800D01*
G01Y415320D02*
X546168D01*
G01X550879Y409320D02*
Y413920D01*
G01X546730Y516943D02*
X546885Y516713D01*
X546988Y516445D01*
Y516138D01*
X546833Y515793D01*
X546575Y515525D01*
X546265Y515333D01*
X545748Y515180D01*
X545283Y515142D01*
X544818Y515218D01*
X544508Y515333D01*
X544198Y515563D01*
X543991Y515832D01*
X543888Y516100D01*
Y516368D01*
X543991Y516637D01*
X544146Y516867D01*
X544353Y517058D01*
G01X543888Y519200D02*
X543940Y519468D01*
X544095Y519775D01*
X544353Y519967D01*
X544715Y520043D01*
X545076Y519967D01*
X545386Y519737D01*
X545541Y519392D01*
Y519008D01*
X545645Y518778D01*
X545903Y518587D01*
X546265Y518510D01*
X546626Y518625D01*
X546885Y518893D01*
X546988Y519200D01*
X546885Y519507D01*
X546626Y519775D01*
X546265Y519890D01*
X545903Y519813D01*
X545645Y519622D01*
X545541Y519392D01*
Y519008D01*
X545386Y518663D01*
X545076Y518433D01*
X544715Y518357D01*
X544353Y518433D01*
X544095Y518625D01*
X543940Y518932D01*
X543888Y519200D01*
G01Y522223D02*
X544560Y522300D01*
X545128Y522415D01*
X545645Y522568D01*
X546213Y522760D01*
X546988Y523067D01*
Y521533D01*
G01Y525400D02*
X546885Y525093D01*
X546626Y524863D01*
X546316Y524710D01*
X545903Y524595D01*
X545438Y524557D01*
X544973Y524595D01*
X544560Y524710D01*
X544250Y524863D01*
X543991Y525093D01*
X543888Y525400D01*
X543991Y525707D01*
X544250Y525937D01*
X544560Y526090D01*
X544973Y526205D01*
X545438Y526243D01*
X545903Y526205D01*
X546316Y526090D01*
X546626Y525937D01*
X546885Y525707D01*
X546988Y525400D01*
G01X543838Y531725D02*
X547038D01*
G01X543838Y537925D02*
Y531725D01*
G01X547038D02*
Y537925D01*
G01X543138Y531725D02*
Y537925D01*
G01X556038Y542725D02*
Y545725D01*
G01X552938Y542625D02*
X559138D01*
G01X552938Y545825D02*
Y542625D01*
G01X559138Y545825D02*
X552938D01*
G01X556138Y546625D02*
Y549625D01*
G01X553038Y546525D02*
X559238D01*
G01X553038Y549725D02*
Y546525D01*
G01X543938Y534825D02*
X546938D01*
G01X547038Y537925D02*
X543838D01*
G01X546638Y546425D02*
X549838D01*
G01X546638Y552625D02*
Y546425D01*
G01X549838D02*
Y552625D01*
G01X552938Y538725D02*
X559138D01*
G01X552938Y541925D02*
Y538725D01*
G01X559138Y541925D02*
X552938D01*
G01X556038Y538825D02*
Y541825D01*
G01X553638Y563025D02*
X556638D01*
G01X553538Y559925D02*
X556738D01*
G01X553538Y566125D02*
Y559925D01*
G01X556738D02*
Y566125D01*
G01X559238Y549725D02*
X553038D01*
G01X546738Y549525D02*
X549738D01*
G01X549838Y552625D02*
X546638D01*
G01X556738Y566125D02*
X553538D01*
G01Y566825D02*
X556738D01*
G01X553538Y573025D02*
Y566825D01*
G01X556738D02*
Y573025D01*
G01X553638Y569925D02*
X556638D01*
G01X556738Y573025D02*
X553538D01*
G01X545838Y592525D02*
Y598725D01*
G01X542638D02*
Y592525D01*
G01X545738Y595625D02*
X542738D01*
G01X542638Y592525D02*
X545838D01*
G01X556738Y582725D02*
Y588925D01*
G01X553538Y582725D02*
X556738D01*
G01X553538Y588925D02*
Y582725D01*
G01X556638Y585825D02*
X553638D01*
G01X556738Y588925D02*
X553538D01*
G01X549738Y592525D02*
Y598725D01*
G01X546538Y592525D02*
X549738D01*
G01X546538Y598725D02*
Y592525D01*
G01X549638Y595625D02*
X546638D01*
G01X547831Y603558D02*
X547986Y603328D01*
X548089Y603060D01*
Y602753D01*
X547934Y602408D01*
X547676Y602140D01*
X547366Y601948D01*
X546849Y601795D01*
X546384Y601757D01*
X545919Y601833D01*
X545609Y601948D01*
X545299Y602178D01*
X545092Y602447D01*
X544989Y602715D01*
Y602983D01*
X545092Y603252D01*
X545247Y603482D01*
X545454Y603673D01*
G01X544989Y605815D02*
X545041Y606083D01*
X545196Y606390D01*
X545454Y606582D01*
X545816Y606658D01*
X546177Y606582D01*
X546487Y606352D01*
X546642Y606007D01*
Y605623D01*
X546746Y605393D01*
X547004Y605202D01*
X547366Y605125D01*
X547727Y605240D01*
X547986Y605508D01*
X548089Y605815D01*
X547986Y606122D01*
X547727Y606390D01*
X547366Y606505D01*
X547004Y606428D01*
X546746Y606237D01*
X546642Y606007D01*
Y605623D01*
X546487Y605278D01*
X546177Y605048D01*
X545816Y604972D01*
X545454Y605048D01*
X545196Y605240D01*
X545041Y605547D01*
X544989Y605815D01*
G01X545351Y608263D02*
X545092Y608532D01*
X544989Y608838D01*
X545092Y609145D01*
X545402Y609413D01*
X545867Y609605D01*
X546332Y609682D01*
X546901D01*
X547366Y609605D01*
X547779Y609413D01*
X547986Y609183D01*
X548089Y608915D01*
X547986Y608608D01*
X547779Y608378D01*
X547469Y608225D01*
X547056Y608148D01*
X546694Y608225D01*
X546332Y608417D01*
X546126Y608647D01*
X546074Y608915D01*
X546177Y609222D01*
X546436Y609452D01*
X546901Y609682D01*
G01X544989Y612015D02*
X548089D01*
X547469Y611555D01*
G01X544989D02*
Y612475D01*
G01X558888Y601688D02*
X559043Y601458D01*
X559146Y601190D01*
Y600883D01*
X558991Y600538D01*
X558733Y600270D01*
X558423Y600078D01*
X557906Y599925D01*
X557441Y599887D01*
X556976Y599963D01*
X556666Y600078D01*
X556356Y600308D01*
X556149Y600577D01*
X556046Y600845D01*
Y601113D01*
X556149Y601382D01*
X556304Y601612D01*
X556511Y601803D01*
G01X556046Y603945D02*
X556098Y604213D01*
X556253Y604520D01*
X556511Y604712D01*
X556873Y604788D01*
X557234Y604712D01*
X557544Y604482D01*
X557699Y604137D01*
Y603753D01*
X557803Y603523D01*
X558061Y603332D01*
X558423Y603255D01*
X558784Y603370D01*
X559043Y603638D01*
X559146Y603945D01*
X559043Y604252D01*
X558784Y604520D01*
X558423Y604635D01*
X558061Y604558D01*
X557803Y604367D01*
X557699Y604137D01*
Y603753D01*
X557544Y603408D01*
X557234Y603178D01*
X556873Y603102D01*
X556511Y603178D01*
X556253Y603370D01*
X556098Y603677D01*
X556046Y603945D01*
G01Y606968D02*
X556718Y607045D01*
X557286Y607160D01*
X557803Y607313D01*
X558371Y607505D01*
X559146Y607812D01*
Y606278D01*
G01X556046Y610605D02*
X559146D01*
X556924Y609187D01*
Y611103D01*
G01X545838Y598725D02*
X542638D01*
G01X554922Y601678D02*
X555077Y601448D01*
X555180Y601180D01*
Y600873D01*
X555025Y600528D01*
X554767Y600260D01*
X554457Y600068D01*
X553940Y599915D01*
X553475Y599877D01*
X553010Y599953D01*
X552700Y600068D01*
X552390Y600298D01*
X552183Y600567D01*
X552080Y600835D01*
Y601103D01*
X552183Y601372D01*
X552338Y601602D01*
X552545Y601793D01*
G01X552080Y603935D02*
X552132Y604203D01*
X552287Y604510D01*
X552545Y604702D01*
X552907Y604778D01*
X553268Y604702D01*
X553578Y604472D01*
X553733Y604127D01*
Y603743D01*
X553837Y603513D01*
X554095Y603322D01*
X554457Y603245D01*
X554818Y603360D01*
X555077Y603628D01*
X555180Y603935D01*
X555077Y604242D01*
X554818Y604510D01*
X554457Y604625D01*
X554095Y604548D01*
X553837Y604357D01*
X553733Y604127D01*
Y603743D01*
X553578Y603398D01*
X553268Y603168D01*
X552907Y603092D01*
X552545Y603168D01*
X552287Y603360D01*
X552132Y603667D01*
X552080Y603935D01*
G01Y607035D02*
X552132Y607303D01*
X552287Y607610D01*
X552545Y607802D01*
X552907Y607878D01*
X553268Y607802D01*
X553578Y607572D01*
X553733Y607227D01*
Y606843D01*
X553837Y606613D01*
X554095Y606422D01*
X554457Y606345D01*
X554818Y606460D01*
X555077Y606728D01*
X555180Y607035D01*
X555077Y607342D01*
X554818Y607610D01*
X554457Y607725D01*
X554095Y607648D01*
X553837Y607457D01*
X553733Y607227D01*
Y606843D01*
X553578Y606498D01*
X553268Y606268D01*
X552907Y606192D01*
X552545Y606268D01*
X552287Y606460D01*
X552132Y606767D01*
X552080Y607035D01*
G01Y610135D02*
X555180D01*
X554560Y609675D01*
G01X552080D02*
Y610595D01*
G01X549738Y598725D02*
X546538D01*
G01X546374Y627460D02*
X549474D01*
Y628419D01*
X549319Y628725D01*
X549112Y628917D01*
X548699Y628994D01*
X548286Y628917D01*
X548027Y628687D01*
X547872Y628419D01*
Y627460D01*
G01Y628419D02*
X546374Y628994D01*
G01X546736Y630675D02*
X546477Y630944D01*
X546374Y631250D01*
X546477Y631557D01*
X546787Y631825D01*
X547252Y632017D01*
X547717Y632094D01*
X548286D01*
X548751Y632017D01*
X549164Y631825D01*
X549371Y631595D01*
X549474Y631327D01*
X549371Y631020D01*
X549164Y630790D01*
X548854Y630637D01*
X548441Y630560D01*
X548079Y630637D01*
X547717Y630829D01*
X547511Y631059D01*
X547459Y631327D01*
X547562Y631634D01*
X547821Y631864D01*
X548286Y632094D01*
G01X546374Y634427D02*
X546426Y634695D01*
X546581Y635002D01*
X546839Y635194D01*
X547201Y635270D01*
X547562Y635194D01*
X547872Y634964D01*
X548027Y634619D01*
Y634235D01*
X548131Y634005D01*
X548389Y633814D01*
X548751Y633737D01*
X549112Y633852D01*
X549371Y634120D01*
X549474Y634427D01*
X549371Y634734D01*
X549112Y635002D01*
X548751Y635117D01*
X548389Y635040D01*
X548131Y634849D01*
X548027Y634619D01*
Y634235D01*
X547872Y633890D01*
X547562Y633660D01*
X547201Y633584D01*
X546839Y633660D01*
X546581Y633852D01*
X546426Y634159D01*
X546374Y634427D01*
G01X546736Y636875D02*
X546477Y637144D01*
X546374Y637450D01*
X546477Y637757D01*
X546787Y638025D01*
X547252Y638217D01*
X547717Y638294D01*
X548286D01*
X548751Y638217D01*
X549164Y638025D01*
X549371Y637795D01*
X549474Y637527D01*
X549371Y637220D01*
X549164Y636990D01*
X548854Y636837D01*
X548441Y636760D01*
X548079Y636837D01*
X547717Y637029D01*
X547511Y637259D01*
X547459Y637527D01*
X547562Y637834D01*
X547821Y638064D01*
X548286Y638294D01*
G01X553834Y625767D02*
X556934D01*
Y626726D01*
X556779Y627032D01*
X556572Y627224D01*
X556159Y627301D01*
X555746Y627224D01*
X555487Y626994D01*
X555332Y626726D01*
Y625767D01*
G01Y626726D02*
X553834Y627301D01*
G01X554196Y628982D02*
X553937Y629251D01*
X553834Y629557D01*
X553937Y629864D01*
X554247Y630132D01*
X554712Y630324D01*
X555177Y630401D01*
X555746D01*
X556211Y630324D01*
X556624Y630132D01*
X556831Y629902D01*
X556934Y629634D01*
X556831Y629327D01*
X556624Y629097D01*
X556314Y628944D01*
X555901Y628867D01*
X555539Y628944D01*
X555177Y629136D01*
X554971Y629366D01*
X554919Y629634D01*
X555022Y629941D01*
X555281Y630171D01*
X555746Y630401D01*
G01X554196Y632082D02*
X553937Y632351D01*
X553834Y632657D01*
X553937Y632964D01*
X554247Y633232D01*
X554712Y633424D01*
X555177Y633501D01*
X555746D01*
X556211Y633424D01*
X556624Y633232D01*
X556831Y633002D01*
X556934Y632734D01*
X556831Y632427D01*
X556624Y632197D01*
X556314Y632044D01*
X555901Y631967D01*
X555539Y632044D01*
X555177Y632236D01*
X554971Y632466D01*
X554919Y632734D01*
X555022Y633041D01*
X555281Y633271D01*
X555746Y633501D01*
G01X554299Y634991D02*
X554041Y635221D01*
X553886Y635489D01*
X553834Y635834D01*
X553937Y636179D01*
X554144Y636447D01*
X554506Y636639D01*
X554919Y636677D01*
X555332Y636601D01*
X555591Y636409D01*
X555797Y636141D01*
X555849Y635872D01*
X555797Y635604D01*
X555591Y635259D01*
X556934Y635374D01*
Y636409D01*
G01X543197Y643431D02*
Y646431D01*
G01X546297Y643331D02*
Y646531D01*
G01X546968Y644763D02*
Y641563D01*
G01X553168D02*
Y644763D01*
G01X546968Y641563D02*
X553168D01*
G01X553908Y646793D02*
Y640593D01*
G01X557108D02*
Y646793D01*
G01X553908Y640593D02*
X557108D01*
G01X557808Y644723D02*
Y641523D01*
G01D02*
X564008D01*
G01X556709Y653815D02*
Y656915D01*
X555750D01*
X555444Y656760D01*
X555252Y656553D01*
X555175Y656140D01*
X555252Y655727D01*
X555482Y655468D01*
X555750Y655313D01*
X556709D01*
G01X555750D02*
X555175Y653815D01*
G01X553494Y654177D02*
X553225Y653918D01*
X552919Y653815D01*
X552612Y653918D01*
X552344Y654228D01*
X552152Y654693D01*
X552075Y655158D01*
Y655727D01*
X552152Y656192D01*
X552344Y656605D01*
X552574Y656812D01*
X552842Y656915D01*
X553149Y656812D01*
X553379Y656605D01*
X553532Y656295D01*
X553609Y655882D01*
X553532Y655520D01*
X553340Y655158D01*
X553110Y654952D01*
X552842Y654900D01*
X552535Y655003D01*
X552305Y655262D01*
X552075Y655727D01*
G01X549819Y653815D02*
X549742Y654487D01*
X549627Y655055D01*
X549474Y655572D01*
X549282Y656140D01*
X548975Y656915D01*
X550509D01*
G01X546719Y653815D02*
X546642Y654487D01*
X546527Y655055D01*
X546374Y655572D01*
X546182Y656140D01*
X545875Y656915D01*
X547409D01*
G01X546557Y648677D02*
Y651877D01*
G01X553168Y644763D02*
X546968D01*
G01X557108Y646793D02*
X553908D01*
G01X564008Y644723D02*
X557808D01*
G01X554086Y665671D02*
Y668771D01*
X553127D01*
X552821Y668616D01*
X552629Y668409D01*
X552552Y667996D01*
X552629Y667583D01*
X552859Y667324D01*
X553127Y667169D01*
X554086D01*
G01X553127D02*
X552552Y665671D01*
G01X550296D02*
X550219Y666343D01*
X550104Y666911D01*
X549951Y667428D01*
X549759Y667996D01*
X549452Y668771D01*
X550986D01*
G01X546659Y665671D02*
Y668771D01*
X548077Y666549D01*
X546161D01*
G01X544862Y666291D02*
X544632Y665929D01*
X544326Y665723D01*
X543981Y665671D01*
X543674Y665723D01*
X543367Y665981D01*
X543176Y666291D01*
X543137Y666601D01*
X543214Y666963D01*
X543482Y667221D01*
X543751Y667324D01*
X544096D01*
G01X543751D02*
X543521Y667479D01*
X543329Y667738D01*
X543252Y668048D01*
X543329Y668358D01*
X543521Y668616D01*
X543866Y668771D01*
X544211Y668719D01*
X544556Y668513D01*
G01X556240Y667556D02*
X562440D01*
G01X556240Y670756D02*
Y667556D01*
G01X562440Y670756D02*
X556240D01*
G01X553935Y672843D02*
Y675943D01*
X552976D01*
X552670Y675788D01*
X552478Y675581D01*
X552401Y675168D01*
X552478Y674755D01*
X552708Y674496D01*
X552976Y674341D01*
X553935D01*
G01X552976D02*
X552401Y672843D01*
G01X550145D02*
X550068Y673515D01*
X549953Y674083D01*
X549800Y674600D01*
X549608Y675168D01*
X549301Y675943D01*
X550835D01*
G01X547696Y675426D02*
X547466Y675736D01*
X547198Y675891D01*
X546891Y675943D01*
X546508Y675840D01*
X546240Y675581D01*
X546163Y675271D01*
X546201Y674961D01*
X546355Y674703D01*
X547121Y674186D01*
X547466Y673825D01*
X547696Y673308D01*
X547773Y672843D01*
X546163D01*
G01X543868D02*
X543600Y672895D01*
X543293Y673050D01*
X543101Y673308D01*
X543025Y673670D01*
X543101Y674031D01*
X543331Y674341D01*
X543676Y674496D01*
X544060D01*
X544290Y674600D01*
X544481Y674858D01*
X544558Y675220D01*
X544443Y675581D01*
X544175Y675840D01*
X543868Y675943D01*
X543561Y675840D01*
X543293Y675581D01*
X543178Y675220D01*
X543255Y674858D01*
X543446Y674600D01*
X543676Y674496D01*
X544060D01*
X544405Y674341D01*
X544635Y674031D01*
X544711Y673670D01*
X544635Y673308D01*
X544443Y673050D01*
X544136Y672895D01*
X543868Y672843D01*
G01X556240Y674756D02*
Y671556D01*
G01X562440Y674756D02*
X556240D01*
G01Y671556D02*
X562440D01*
G01X554086Y661671D02*
Y664771D01*
X553127D01*
X552821Y664616D01*
X552629Y664409D01*
X552552Y663996D01*
X552629Y663583D01*
X552859Y663324D01*
X553127Y663169D01*
X554086D01*
G01X553127D02*
X552552Y661671D01*
G01X550296D02*
X550219Y662343D01*
X550104Y662911D01*
X549951Y663428D01*
X549759Y663996D01*
X549452Y664771D01*
X550986D01*
G01X547962Y662291D02*
X547732Y661929D01*
X547426Y661723D01*
X547081Y661671D01*
X546774Y661723D01*
X546467Y661981D01*
X546276Y662291D01*
X546237Y662601D01*
X546314Y662963D01*
X546582Y663221D01*
X546851Y663324D01*
X547196D01*
G01X546851D02*
X546621Y663479D01*
X546429Y663738D01*
X546352Y664048D01*
X546429Y664358D01*
X546621Y664616D01*
X546966Y664771D01*
X547311Y664719D01*
X547656Y664513D01*
G01X543559Y661671D02*
Y664771D01*
X544977Y662549D01*
X543061D01*
G01X556240Y663556D02*
X562440D01*
G01X556240Y666756D02*
Y663556D01*
G01X562440Y666756D02*
X556240D01*
G01X553935Y676843D02*
Y679943D01*
X552976D01*
X552670Y679788D01*
X552478Y679581D01*
X552401Y679168D01*
X552478Y678755D01*
X552708Y678496D01*
X552976Y678341D01*
X553935D01*
G01X552976D02*
X552401Y676843D01*
G01X550145D02*
X550068Y677515D01*
X549953Y678083D01*
X549800Y678600D01*
X549608Y679168D01*
X549301Y679943D01*
X550835D01*
G01X547696Y679426D02*
X547466Y679736D01*
X547198Y679891D01*
X546891Y679943D01*
X546508Y679840D01*
X546240Y679581D01*
X546163Y679271D01*
X546201Y678961D01*
X546355Y678703D01*
X547121Y678186D01*
X547466Y677825D01*
X547696Y677308D01*
X547773Y676843D01*
X546163D01*
G01X544520Y677205D02*
X544251Y676946D01*
X543945Y676843D01*
X543638Y676946D01*
X543370Y677256D01*
X543178Y677721D01*
X543101Y678186D01*
Y678755D01*
X543178Y679220D01*
X543370Y679633D01*
X543600Y679840D01*
X543868Y679943D01*
X544175Y679840D01*
X544405Y679633D01*
X544558Y679323D01*
X544635Y678910D01*
X544558Y678548D01*
X544366Y678186D01*
X544136Y677980D01*
X543868Y677928D01*
X543561Y678031D01*
X543331Y678290D01*
X543101Y678755D01*
G01X556240Y678756D02*
Y675556D01*
G01D02*
X562440D01*
G01Y678756D02*
X556240D01*
G01X553889Y688935D02*
Y692035D01*
X552930D01*
X552624Y691880D01*
X552432Y691673D01*
X552355Y691260D01*
X552432Y690847D01*
X552662Y690588D01*
X552930Y690433D01*
X553889D01*
G01X552930D02*
X552355Y688935D01*
G01X550099D02*
X550022Y689607D01*
X549907Y690175D01*
X549754Y690692D01*
X549562Y691260D01*
X549255Y692035D01*
X550789D01*
G01X547765Y689555D02*
X547535Y689193D01*
X547229Y688987D01*
X546884Y688935D01*
X546577Y688987D01*
X546270Y689245D01*
X546079Y689555D01*
X546040Y689865D01*
X546117Y690227D01*
X546385Y690485D01*
X546654Y690588D01*
X546999D01*
G01X546654D02*
X546424Y690743D01*
X546232Y691002D01*
X546155Y691312D01*
X546232Y691622D01*
X546424Y691880D01*
X546769Y692035D01*
X547114Y691983D01*
X547459Y691777D01*
G01X544550Y691518D02*
X544320Y691828D01*
X544052Y691983D01*
X543745Y692035D01*
X543362Y691932D01*
X543094Y691673D01*
X543017Y691363D01*
X543055Y691053D01*
X543209Y690795D01*
X543975Y690278D01*
X544320Y689917D01*
X544550Y689400D01*
X544627Y688935D01*
X543017D01*
G01X556240Y690756D02*
Y687556D01*
G01X562440Y690756D02*
X556240D01*
G01Y687556D02*
X562440D01*
G01X553889Y684935D02*
Y688035D01*
X552930D01*
X552624Y687880D01*
X552432Y687673D01*
X552355Y687260D01*
X552432Y686847D01*
X552662Y686588D01*
X552930Y686433D01*
X553889D01*
G01X552930D02*
X552355Y684935D01*
G01X550099D02*
X550022Y685607D01*
X549907Y686175D01*
X549754Y686692D01*
X549562Y687260D01*
X549255Y688035D01*
X550789D01*
G01X547765Y685555D02*
X547535Y685193D01*
X547229Y684987D01*
X546884Y684935D01*
X546577Y684987D01*
X546270Y685245D01*
X546079Y685555D01*
X546040Y685865D01*
X546117Y686227D01*
X546385Y686485D01*
X546654Y686588D01*
X546999D01*
G01X546654D02*
X546424Y686743D01*
X546232Y687002D01*
X546155Y687312D01*
X546232Y687622D01*
X546424Y687880D01*
X546769Y688035D01*
X547114Y687983D01*
X547459Y687777D01*
G01X543822Y684935D02*
Y688035D01*
X544282Y687415D01*
G01Y684935D02*
X543362D01*
G01X556240Y686756D02*
Y683556D01*
G01X562440Y686756D02*
X556240D01*
G01Y683556D02*
X562440D01*
G01X553889Y680935D02*
Y684035D01*
X552930D01*
X552624Y683880D01*
X552432Y683673D01*
X552355Y683260D01*
X552432Y682847D01*
X552662Y682588D01*
X552930Y682433D01*
X553889D01*
G01X552930D02*
X552355Y680935D01*
G01X550099D02*
X550022Y681607D01*
X549907Y682175D01*
X549754Y682692D01*
X549562Y683260D01*
X549255Y684035D01*
X550789D01*
G01X547765Y681555D02*
X547535Y681193D01*
X547229Y680987D01*
X546884Y680935D01*
X546577Y680987D01*
X546270Y681245D01*
X546079Y681555D01*
X546040Y681865D01*
X546117Y682227D01*
X546385Y682485D01*
X546654Y682588D01*
X546999D01*
G01X546654D02*
X546424Y682743D01*
X546232Y683002D01*
X546155Y683312D01*
X546232Y683622D01*
X546424Y683880D01*
X546769Y684035D01*
X547114Y683983D01*
X547459Y683777D01*
G01X543822Y684035D02*
X544129Y683932D01*
X544359Y683673D01*
X544512Y683363D01*
X544627Y682950D01*
X544665Y682485D01*
X544627Y682020D01*
X544512Y681607D01*
X544359Y681297D01*
X544129Y681038D01*
X543822Y680935D01*
X543515Y681038D01*
X543285Y681297D01*
X543132Y681607D01*
X543017Y682020D01*
X542979Y682485D01*
X543017Y682950D01*
X543132Y683363D01*
X543285Y683673D01*
X543515Y683932D01*
X543822Y684035D01*
G01X556240Y682756D02*
Y679556D01*
G01X562440Y682756D02*
X556240D01*
G01Y679556D02*
X562440D01*
G01X553889Y692935D02*
Y696035D01*
X552930D01*
X552624Y695880D01*
X552432Y695673D01*
X552355Y695260D01*
X552432Y694847D01*
X552662Y694588D01*
X552930Y694433D01*
X553889D01*
G01X552930D02*
X552355Y692935D01*
G01X550099D02*
X550022Y693607D01*
X549907Y694175D01*
X549754Y694692D01*
X549562Y695260D01*
X549255Y696035D01*
X550789D01*
G01X547765Y693555D02*
X547535Y693193D01*
X547229Y692987D01*
X546884Y692935D01*
X546577Y692987D01*
X546270Y693245D01*
X546079Y693555D01*
X546040Y693865D01*
X546117Y694227D01*
X546385Y694485D01*
X546654Y694588D01*
X546999D01*
G01X546654D02*
X546424Y694743D01*
X546232Y695002D01*
X546155Y695312D01*
X546232Y695622D01*
X546424Y695880D01*
X546769Y696035D01*
X547114Y695983D01*
X547459Y695777D01*
G01X544665Y693555D02*
X544435Y693193D01*
X544129Y692987D01*
X543784Y692935D01*
X543477Y692987D01*
X543170Y693245D01*
X542979Y693555D01*
X542940Y693865D01*
X543017Y694227D01*
X543285Y694485D01*
X543554Y694588D01*
X543899D01*
G01X543554D02*
X543324Y694743D01*
X543132Y695002D01*
X543055Y695312D01*
X543132Y695622D01*
X543324Y695880D01*
X543669Y696035D01*
X544014Y695983D01*
X544359Y695777D01*
G01X556240Y694756D02*
Y691556D01*
G01D02*
X562440D01*
G01Y694756D02*
X556240D01*
G01X557115Y704504D02*
Y707604D01*
X556156D01*
X555850Y707449D01*
X555658Y707242D01*
X555581Y706829D01*
X555658Y706416D01*
X555888Y706157D01*
X556156Y706002D01*
X557115D01*
G01X556156D02*
X555581Y704504D01*
G01X553325D02*
X553248Y705176D01*
X553133Y705744D01*
X552980Y706261D01*
X552788Y706829D01*
X552481Y707604D01*
X554015D01*
G01X549688Y704504D02*
Y707604D01*
X551106Y705382D01*
X549190D01*
G01X547048Y707604D02*
X547355Y707501D01*
X547585Y707242D01*
X547738Y706932D01*
X547853Y706519D01*
X547891Y706054D01*
X547853Y705589D01*
X547738Y705176D01*
X547585Y704866D01*
X547355Y704607D01*
X547048Y704504D01*
X546741Y704607D01*
X546511Y704866D01*
X546358Y705176D01*
X546243Y705589D01*
X546205Y706054D01*
X546243Y706519D01*
X546358Y706932D01*
X546511Y707242D01*
X546741Y707501D01*
X547048Y707604D01*
G01X556240Y702756D02*
Y699556D01*
G01X562440Y702756D02*
X556240D01*
G01Y699556D02*
X562440D01*
G01X554035Y700646D02*
Y703746D01*
X553076D01*
X552770Y703591D01*
X552578Y703384D01*
X552501Y702971D01*
X552578Y702558D01*
X552808Y702299D01*
X553076Y702144D01*
X554035D01*
G01X553076D02*
X552501Y700646D01*
G01X550245D02*
X550168Y701318D01*
X550053Y701886D01*
X549900Y702403D01*
X549708Y702971D01*
X549401Y703746D01*
X550935D01*
G01X547911Y701266D02*
X547681Y700904D01*
X547375Y700698D01*
X547030Y700646D01*
X546723Y700698D01*
X546416Y700956D01*
X546225Y701266D01*
X546186Y701576D01*
X546263Y701938D01*
X546531Y702196D01*
X546800Y702299D01*
X547145D01*
G01X546800D02*
X546570Y702454D01*
X546378Y702713D01*
X546301Y703023D01*
X546378Y703333D01*
X546570Y703591D01*
X546915Y703746D01*
X547260Y703694D01*
X547605Y703488D01*
G01X544696Y701938D02*
X544428Y702299D01*
X544198Y702506D01*
X543891Y702609D01*
X543623Y702506D01*
X543431Y702299D01*
X543278Y701989D01*
X543240Y701628D01*
X543278Y701318D01*
X543431Y701008D01*
X543661Y700749D01*
X543930Y700646D01*
X544236Y700749D01*
X544505Y701059D01*
X544658Y701524D01*
X544696Y702041D01*
X544620Y702713D01*
X544505Y703074D01*
X544313Y703436D01*
X544045Y703694D01*
X543776Y703746D01*
X543508Y703643D01*
X543316Y703384D01*
G01X556240Y698756D02*
Y695556D01*
G01X562440Y698756D02*
X556240D01*
G01Y695556D02*
X562440D01*
G01X549340Y736556D02*
X552540D01*
G01X549340Y742756D02*
Y736556D01*
G01X552540D02*
Y742756D01*
G01X544840Y736556D02*
X548040D01*
G01X544840Y742756D02*
Y736556D01*
G01X548040D02*
Y742756D01*
G01X553840Y736856D02*
X557040D01*
G01X553840Y743056D02*
Y736856D01*
G01X557040D02*
Y743056D01*
G01X543540Y736556D02*
Y742756D01*
G01X548040Y731256D02*
X544840D01*
G01X548040Y725056D02*
Y731256D01*
G01X544840Y725056D02*
X548040D01*
G01X544840Y731256D02*
Y725056D01*
G01X557040Y731256D02*
X553840D01*
G01X557040Y725056D02*
Y731256D01*
G01X553840Y725056D02*
X557040D01*
G01X553840Y731256D02*
Y725056D01*
G01X552540Y731256D02*
X549340D01*
G01X552540Y725056D02*
Y731256D01*
G01X549340Y725056D02*
X552540D01*
G01X549340Y731256D02*
Y725056D01*
G01X543540D02*
Y731256D01*
G01X560882Y747305D02*
X561037Y747075D01*
X561140Y746807D01*
Y746500D01*
X560985Y746155D01*
X560727Y745887D01*
X560417Y745695D01*
X559900Y745542D01*
X559435Y745504D01*
X558970Y745580D01*
X558660Y745695D01*
X558350Y745925D01*
X558143Y746194D01*
X558040Y746462D01*
Y746730D01*
X558143Y746999D01*
X558298Y747229D01*
X558505Y747420D01*
G01X558040Y749485D02*
X558712Y749562D01*
X559280Y749677D01*
X559797Y749830D01*
X560365Y750022D01*
X561140Y750329D01*
Y748795D01*
G01X558660Y751819D02*
X558298Y752049D01*
X558092Y752355D01*
X558040Y752700D01*
X558092Y753007D01*
X558350Y753314D01*
X558660Y753505D01*
X558970Y753544D01*
X559332Y753467D01*
X559590Y753199D01*
X559693Y752930D01*
Y752585D01*
G01Y752930D02*
X559848Y753160D01*
X560107Y753352D01*
X560417Y753429D01*
X560727Y753352D01*
X560985Y753160D01*
X561140Y752815D01*
X561088Y752470D01*
X560882Y752125D01*
G01X560623Y755034D02*
X560933Y755264D01*
X561088Y755532D01*
X561140Y755839D01*
X561037Y756222D01*
X560778Y756490D01*
X560468Y756567D01*
X560158Y756529D01*
X559900Y756375D01*
X559383Y755609D01*
X559022Y755264D01*
X558505Y755034D01*
X558040Y754957D01*
Y756567D01*
G01X549440Y739656D02*
X552440D01*
G01X552540Y742756D02*
X549340D01*
G01X552840Y747305D02*
X552995Y747075D01*
X553098Y746807D01*
Y746500D01*
X552943Y746155D01*
X552685Y745887D01*
X552375Y745695D01*
X551858Y745542D01*
X551393Y745504D01*
X550928Y745580D01*
X550618Y745695D01*
X550308Y745925D01*
X550101Y746194D01*
X549998Y746462D01*
Y746730D01*
X550101Y746999D01*
X550256Y747229D01*
X550463Y747420D01*
G01X549998Y749485D02*
X550670Y749562D01*
X551238Y749677D01*
X551755Y749830D01*
X552323Y750022D01*
X553098Y750329D01*
Y748795D01*
G01X550618Y751819D02*
X550256Y752049D01*
X550050Y752355D01*
X549998Y752700D01*
X550050Y753007D01*
X550308Y753314D01*
X550618Y753505D01*
X550928Y753544D01*
X551290Y753467D01*
X551548Y753199D01*
X551651Y752930D01*
Y752585D01*
G01Y752930D02*
X551806Y753160D01*
X552065Y753352D01*
X552375Y753429D01*
X552685Y753352D01*
X552943Y753160D01*
X553098Y752815D01*
X553046Y752470D01*
X552840Y752125D01*
G01X549998Y755762D02*
X550050Y756030D01*
X550205Y756337D01*
X550463Y756529D01*
X550825Y756605D01*
X551186Y756529D01*
X551496Y756299D01*
X551651Y755954D01*
Y755570D01*
X551755Y755340D01*
X552013Y755149D01*
X552375Y755072D01*
X552736Y755187D01*
X552995Y755455D01*
X553098Y755762D01*
X552995Y756069D01*
X552736Y756337D01*
X552375Y756452D01*
X552013Y756375D01*
X551755Y756184D01*
X551651Y755954D01*
Y755570D01*
X551496Y755225D01*
X551186Y754995D01*
X550825Y754919D01*
X550463Y754995D01*
X550205Y755187D01*
X550050Y755494D01*
X549998Y755762D01*
G01X544940Y739656D02*
X547940D01*
G01X548040Y742756D02*
X544840D01*
G01X553940Y739956D02*
X556940D01*
G01X557040Y743056D02*
X553840D01*
G01X553920Y745833D02*
X557020D01*
Y746792D01*
X556865Y747098D01*
X556658Y747290D01*
X556245Y747367D01*
X555832Y747290D01*
X555573Y747060D01*
X555418Y746792D01*
Y745833D01*
G01Y746792D02*
X553920Y747367D01*
G01X554282Y749048D02*
X554023Y749317D01*
X553920Y749623D01*
X554023Y749930D01*
X554333Y750198D01*
X554798Y750390D01*
X555263Y750467D01*
X555832D01*
X556297Y750390D01*
X556710Y750198D01*
X556917Y749968D01*
X557020Y749700D01*
X556917Y749393D01*
X556710Y749163D01*
X556400Y749010D01*
X555987Y748933D01*
X555625Y749010D01*
X555263Y749202D01*
X555057Y749432D01*
X555005Y749700D01*
X555108Y750007D01*
X555367Y750237D01*
X555832Y750467D01*
G01X553920Y752723D02*
X554592Y752800D01*
X555160Y752915D01*
X555677Y753068D01*
X556245Y753260D01*
X557020Y753567D01*
Y752033D01*
G01X556503Y755172D02*
X556813Y755402D01*
X556968Y755670D01*
X557020Y755977D01*
X556917Y756360D01*
X556658Y756628D01*
X556348Y756705D01*
X556038Y756667D01*
X555780Y756513D01*
X555263Y755747D01*
X554902Y755402D01*
X554385Y755172D01*
X553920Y755095D01*
Y756705D01*
G01X545767Y745695D02*
X548867D01*
Y746654D01*
X548712Y746960D01*
X548505Y747152D01*
X548092Y747229D01*
X547679Y747152D01*
X547420Y746922D01*
X547265Y746654D01*
Y745695D01*
G01Y746654D02*
X545767Y747229D01*
G01X546129Y748910D02*
X545870Y749179D01*
X545767Y749485D01*
X545870Y749792D01*
X546180Y750060D01*
X546645Y750252D01*
X547110Y750329D01*
X547679D01*
X548144Y750252D01*
X548557Y750060D01*
X548764Y749830D01*
X548867Y749562D01*
X548764Y749255D01*
X548557Y749025D01*
X548247Y748872D01*
X547834Y748795D01*
X547472Y748872D01*
X547110Y749064D01*
X546904Y749294D01*
X546852Y749562D01*
X546955Y749869D01*
X547214Y750099D01*
X547679Y750329D01*
G01X545767Y752585D02*
X546439Y752662D01*
X547007Y752777D01*
X547524Y752930D01*
X548092Y753122D01*
X548867Y753429D01*
Y751895D01*
G01X545767Y755762D02*
X545819Y756030D01*
X545974Y756337D01*
X546232Y756529D01*
X546594Y756605D01*
X546955Y756529D01*
X547265Y756299D01*
X547420Y755954D01*
Y755570D01*
X547524Y755340D01*
X547782Y755149D01*
X548144Y755072D01*
X548505Y755187D01*
X548764Y755455D01*
X548867Y755762D01*
X548764Y756069D01*
X548505Y756337D01*
X548144Y756452D01*
X547782Y756375D01*
X547524Y756184D01*
X547420Y755954D01*
Y755570D01*
X547265Y755225D01*
X546955Y754995D01*
X546594Y754919D01*
X546232Y754995D01*
X545974Y755187D01*
X545819Y755494D01*
X545767Y755762D01*
G01X558984Y759623D02*
X559139Y759393D01*
X559242Y759125D01*
Y758818D01*
X559087Y758473D01*
X558829Y758205D01*
X558519Y758013D01*
X558002Y757860D01*
X557537Y757822D01*
X557072Y757898D01*
X556762Y758013D01*
X556452Y758243D01*
X556245Y758512D01*
X556142Y758780D01*
Y759048D01*
X556245Y759317D01*
X556400Y759547D01*
X556607Y759738D01*
G01X556142Y761803D02*
X556814Y761880D01*
X557382Y761995D01*
X557899Y762148D01*
X558467Y762340D01*
X559242Y762647D01*
Y761113D01*
G01X556762Y764137D02*
X556400Y764367D01*
X556194Y764673D01*
X556142Y765018D01*
X556194Y765325D01*
X556452Y765632D01*
X556762Y765823D01*
X557072Y765862D01*
X557434Y765785D01*
X557692Y765517D01*
X557795Y765248D01*
Y764903D01*
G01Y765248D02*
X557950Y765478D01*
X558209Y765670D01*
X558519Y765747D01*
X558829Y765670D01*
X559087Y765478D01*
X559242Y765133D01*
X559190Y764788D01*
X558984Y764443D01*
G01X556607Y767237D02*
X556349Y767467D01*
X556194Y767735D01*
X556142Y768080D01*
X556245Y768425D01*
X556452Y768693D01*
X556814Y768885D01*
X557227Y768923D01*
X557640Y768847D01*
X557899Y768655D01*
X558105Y768387D01*
X558157Y768118D01*
X558105Y767850D01*
X557899Y767505D01*
X559242Y767620D01*
Y768655D01*
G01X546685Y759623D02*
X546840Y759393D01*
X546943Y759125D01*
Y758818D01*
X546788Y758473D01*
X546530Y758205D01*
X546220Y758013D01*
X545703Y757860D01*
X545238Y757822D01*
X544773Y757898D01*
X544463Y758013D01*
X544153Y758243D01*
X543946Y758512D01*
X543843Y758780D01*
Y759048D01*
X543946Y759317D01*
X544101Y759547D01*
X544308Y759738D01*
G01X545135Y761152D02*
X545496Y761420D01*
X545703Y761650D01*
X545806Y761957D01*
X545703Y762225D01*
X545496Y762417D01*
X545186Y762570D01*
X544825Y762608D01*
X544515Y762570D01*
X544205Y762417D01*
X543946Y762187D01*
X543843Y761918D01*
X543946Y761612D01*
X544256Y761343D01*
X544721Y761190D01*
X545238Y761152D01*
X545910Y761228D01*
X546271Y761343D01*
X546633Y761535D01*
X546891Y761803D01*
X546943Y762072D01*
X546840Y762340D01*
X546581Y762532D01*
G01X546426Y764252D02*
X546736Y764482D01*
X546891Y764750D01*
X546943Y765057D01*
X546840Y765440D01*
X546581Y765708D01*
X546271Y765785D01*
X545961Y765747D01*
X545703Y765593D01*
X545186Y764827D01*
X544825Y764482D01*
X544308Y764252D01*
X543843Y764175D01*
Y765785D01*
G01Y768540D02*
X546943D01*
X544721Y767122D01*
Y769038D01*
G01X551019Y759841D02*
X551174Y759611D01*
X551277Y759343D01*
Y759036D01*
X551122Y758691D01*
X550864Y758423D01*
X550554Y758231D01*
X550037Y758078D01*
X549572Y758040D01*
X549107Y758116D01*
X548797Y758231D01*
X548487Y758461D01*
X548280Y758730D01*
X548177Y758998D01*
Y759266D01*
X548280Y759535D01*
X548435Y759765D01*
X548642Y759956D01*
G01X548177Y762021D02*
X548849Y762098D01*
X549417Y762213D01*
X549934Y762366D01*
X550502Y762558D01*
X551277Y762865D01*
Y761331D01*
G01X548177Y765658D02*
X551277D01*
X549055Y764240D01*
Y766156D01*
G01X548177Y768298D02*
X551277D01*
X550657Y767838D01*
G01X548177D02*
Y768758D01*
G01X552188Y758013D02*
X555288D01*
Y758972D01*
X555133Y759278D01*
X554926Y759470D01*
X554513Y759547D01*
X554100Y759470D01*
X553841Y759240D01*
X553686Y758972D01*
Y758013D01*
G01Y758972D02*
X552188Y759547D01*
G01X552550Y761228D02*
X552291Y761497D01*
X552188Y761803D01*
X552291Y762110D01*
X552601Y762378D01*
X553066Y762570D01*
X553531Y762647D01*
X554100D01*
X554565Y762570D01*
X554978Y762378D01*
X555185Y762148D01*
X555288Y761880D01*
X555185Y761573D01*
X554978Y761343D01*
X554668Y761190D01*
X554255Y761113D01*
X553893Y761190D01*
X553531Y761382D01*
X553325Y761612D01*
X553273Y761880D01*
X553376Y762187D01*
X553635Y762417D01*
X554100Y762647D01*
G01X552188Y764903D02*
X552860Y764980D01*
X553428Y765095D01*
X553945Y765248D01*
X554513Y765440D01*
X555288Y765747D01*
Y764213D01*
G01X552653Y767237D02*
X552395Y767467D01*
X552240Y767735D01*
X552188Y768080D01*
X552291Y768425D01*
X552498Y768693D01*
X552860Y768885D01*
X553273Y768923D01*
X553686Y768847D01*
X553945Y768655D01*
X554151Y768387D01*
X554203Y768118D01*
X554151Y767850D01*
X553945Y767505D01*
X555288Y767620D01*
Y768655D01*
G01X610900Y782281D02*
X547400D01*
G01X561533Y29707D02*
X561303Y30017D01*
X561035Y30172D01*
X560728Y30224D01*
X560345Y30121D01*
X560077Y29862D01*
X560000Y29552D01*
X560038Y29242D01*
X560192Y28984D01*
X560958Y28467D01*
X561303Y28106D01*
X561533Y27589D01*
X561610Y27124D01*
X560000D01*
G01X572038Y27000D02*
Y30100D01*
X572498Y29480D01*
G01Y27000D02*
X571578D01*
G01X568938Y30100D02*
X569245Y29997D01*
X569475Y29738D01*
X569628Y29428D01*
X569743Y29015D01*
X569781Y28550D01*
X569743Y28085D01*
X569628Y27672D01*
X569475Y27362D01*
X569245Y27103D01*
X568938Y27000D01*
X568631Y27103D01*
X568401Y27362D01*
X568248Y27672D01*
X568133Y28085D01*
X568095Y28550D01*
X568133Y29015D01*
X568248Y29428D01*
X568401Y29738D01*
X568631Y29997D01*
X568938Y30100D01*
G01X560597Y37312D02*
Y40412D01*
X561057Y39792D01*
G01Y37312D02*
X560137D01*
G01X572050Y37100D02*
X571781Y36841D01*
X571475Y36738D01*
X571168Y36841D01*
X570900Y37151D01*
X570708Y37616D01*
X570631Y38081D01*
Y38650D01*
X570708Y39115D01*
X570900Y39528D01*
X571130Y39735D01*
X571398Y39838D01*
X571705Y39735D01*
X571935Y39528D01*
X572088Y39218D01*
X572165Y38805D01*
X572088Y38443D01*
X571896Y38081D01*
X571666Y37875D01*
X571398Y37823D01*
X571091Y37926D01*
X570861Y38185D01*
X570631Y38650D01*
G01X575035Y74403D02*
Y77503D01*
X574076D01*
X573770Y77348D01*
X573578Y77141D01*
X573501Y76728D01*
X573578Y76315D01*
X573808Y76056D01*
X574076Y75901D01*
X575035D01*
G01X574076D02*
X573501Y74403D01*
G01X571168D02*
Y77503D01*
X571628Y76883D01*
G01Y74403D02*
X570708D01*
G01X568068Y77503D02*
X568375Y77400D01*
X568605Y77141D01*
X568758Y76831D01*
X568873Y76418D01*
X568911Y75953D01*
X568873Y75488D01*
X568758Y75075D01*
X568605Y74765D01*
X568375Y74506D01*
X568068Y74403D01*
X567761Y74506D01*
X567531Y74765D01*
X567378Y75075D01*
X567263Y75488D01*
X567225Y75953D01*
X567263Y76418D01*
X567378Y76831D01*
X567531Y77141D01*
X567761Y77400D01*
X568068Y77503D01*
G01X565045Y74403D02*
X564968Y75075D01*
X564853Y75643D01*
X564700Y76160D01*
X564508Y76728D01*
X564201Y77503D01*
X565735D01*
G01X561868Y74403D02*
X561600Y74455D01*
X561293Y74610D01*
X561101Y74868D01*
X561025Y75230D01*
X561101Y75591D01*
X561331Y75901D01*
X561676Y76056D01*
X562060D01*
X562290Y76160D01*
X562481Y76418D01*
X562558Y76780D01*
X562443Y77141D01*
X562175Y77400D01*
X561868Y77503D01*
X561561Y77400D01*
X561293Y77141D01*
X561178Y76780D01*
X561255Y76418D01*
X561446Y76160D01*
X561676Y76056D01*
X562060D01*
X562405Y75901D01*
X562635Y75591D01*
X562711Y75230D01*
X562635Y74868D01*
X562443Y74610D01*
X562136Y74455D01*
X561868Y74403D01*
G01X575035Y66403D02*
Y69503D01*
X574076D01*
X573770Y69348D01*
X573578Y69141D01*
X573501Y68728D01*
X573578Y68315D01*
X573808Y68056D01*
X574076Y67901D01*
X575035D01*
G01X574076D02*
X573501Y66403D01*
G01X571168D02*
Y69503D01*
X571628Y68883D01*
G01Y66403D02*
X570708D01*
G01X568068D02*
Y69503D01*
X568528Y68883D01*
G01Y66403D02*
X567608D01*
G01X565620Y66765D02*
X565351Y66506D01*
X565045Y66403D01*
X564738Y66506D01*
X564470Y66816D01*
X564278Y67281D01*
X564201Y67746D01*
Y68315D01*
X564278Y68780D01*
X564470Y69193D01*
X564700Y69400D01*
X564968Y69503D01*
X565275Y69400D01*
X565505Y69193D01*
X565658Y68883D01*
X565735Y68470D01*
X565658Y68108D01*
X565466Y67746D01*
X565236Y67540D01*
X564968Y67488D01*
X564661Y67591D01*
X564431Y67850D01*
X564201Y68315D01*
G01X561408Y66403D02*
Y69503D01*
X562826Y67281D01*
X560910D01*
G01X575035Y70403D02*
Y73503D01*
X574076D01*
X573770Y73348D01*
X573578Y73141D01*
X573501Y72728D01*
X573578Y72315D01*
X573808Y72056D01*
X574076Y71901D01*
X575035D01*
G01X574076D02*
X573501Y70403D01*
G01X571168D02*
Y73503D01*
X571628Y72883D01*
G01Y70403D02*
X570708D01*
G01X568068D02*
Y73503D01*
X568528Y72883D01*
G01Y70403D02*
X567608D01*
G01X565620Y70765D02*
X565351Y70506D01*
X565045Y70403D01*
X564738Y70506D01*
X564470Y70816D01*
X564278Y71281D01*
X564201Y71746D01*
Y72315D01*
X564278Y72780D01*
X564470Y73193D01*
X564700Y73400D01*
X564968Y73503D01*
X565275Y73400D01*
X565505Y73193D01*
X565658Y72883D01*
X565735Y72470D01*
X565658Y72108D01*
X565466Y71746D01*
X565236Y71540D01*
X564968Y71488D01*
X564661Y71591D01*
X564431Y71850D01*
X564201Y72315D01*
G01X562711Y71023D02*
X562481Y70661D01*
X562175Y70455D01*
X561830Y70403D01*
X561523Y70455D01*
X561216Y70713D01*
X561025Y71023D01*
X560986Y71333D01*
X561063Y71695D01*
X561331Y71953D01*
X561600Y72056D01*
X561945D01*
G01X561600D02*
X561370Y72211D01*
X561178Y72470D01*
X561101Y72780D01*
X561178Y73090D01*
X561370Y73348D01*
X561715Y73503D01*
X562060Y73451D01*
X562405Y73245D01*
G01X575035Y90673D02*
Y93773D01*
X574076D01*
X573770Y93618D01*
X573578Y93411D01*
X573501Y92998D01*
X573578Y92585D01*
X573808Y92326D01*
X574076Y92171D01*
X575035D01*
G01X574076D02*
X573501Y90673D01*
G01X571168D02*
X570900Y90725D01*
X570593Y90880D01*
X570401Y91138D01*
X570325Y91500D01*
X570401Y91861D01*
X570631Y92171D01*
X570976Y92326D01*
X571360D01*
X571590Y92430D01*
X571781Y92688D01*
X571858Y93050D01*
X571743Y93411D01*
X571475Y93670D01*
X571168Y93773D01*
X570861Y93670D01*
X570593Y93411D01*
X570478Y93050D01*
X570555Y92688D01*
X570746Y92430D01*
X570976Y92326D01*
X571360D01*
X571705Y92171D01*
X571935Y91861D01*
X572011Y91500D01*
X571935Y91138D01*
X571743Y90880D01*
X571436Y90725D01*
X571168Y90673D01*
G01X568068D02*
Y93773D01*
X568528Y93153D01*
G01Y90673D02*
X567608D01*
G01X564508D02*
Y93773D01*
X565926Y91551D01*
X564010D01*
G01X575035Y78403D02*
Y81503D01*
X574076D01*
X573770Y81348D01*
X573578Y81141D01*
X573501Y80728D01*
X573578Y80315D01*
X573808Y80056D01*
X574076Y79901D01*
X575035D01*
G01X574076D02*
X573501Y78403D01*
G01X571168D02*
Y81503D01*
X571628Y80883D01*
G01Y78403D02*
X570708D01*
G01X568068Y81503D02*
X568375Y81400D01*
X568605Y81141D01*
X568758Y80831D01*
X568873Y80418D01*
X568911Y79953D01*
X568873Y79488D01*
X568758Y79075D01*
X568605Y78765D01*
X568375Y78506D01*
X568068Y78403D01*
X567761Y78506D01*
X567531Y78765D01*
X567378Y79075D01*
X567263Y79488D01*
X567225Y79953D01*
X567263Y80418D01*
X567378Y80831D01*
X567531Y81141D01*
X567761Y81400D01*
X568068Y81503D01*
G01X565045Y78403D02*
X564968Y79075D01*
X564853Y79643D01*
X564700Y80160D01*
X564508Y80728D01*
X564201Y81503D01*
X565735D01*
G01X561945Y78403D02*
X561868Y79075D01*
X561753Y79643D01*
X561600Y80160D01*
X561408Y80728D01*
X561101Y81503D01*
X562635D01*
G01X575035Y82403D02*
Y85503D01*
X574076D01*
X573770Y85348D01*
X573578Y85141D01*
X573501Y84728D01*
X573578Y84315D01*
X573808Y84056D01*
X574076Y83901D01*
X575035D01*
G01X574076D02*
X573501Y82403D01*
G01X571168D02*
Y85503D01*
X571628Y84883D01*
G01Y82403D02*
X570708D01*
G01X568068D02*
Y85503D01*
X568528Y84883D01*
G01Y82403D02*
X567608D01*
G01X565620Y82765D02*
X565351Y82506D01*
X565045Y82403D01*
X564738Y82506D01*
X564470Y82816D01*
X564278Y83281D01*
X564201Y83746D01*
Y84315D01*
X564278Y84780D01*
X564470Y85193D01*
X564700Y85400D01*
X564968Y85503D01*
X565275Y85400D01*
X565505Y85193D01*
X565658Y84883D01*
X565735Y84470D01*
X565658Y84108D01*
X565466Y83746D01*
X565236Y83540D01*
X564968Y83488D01*
X564661Y83591D01*
X564431Y83850D01*
X564201Y84315D01*
G01X562711Y82868D02*
X562481Y82610D01*
X562213Y82455D01*
X561868Y82403D01*
X561523Y82506D01*
X561255Y82713D01*
X561063Y83075D01*
X561025Y83488D01*
X561101Y83901D01*
X561293Y84160D01*
X561561Y84366D01*
X561830Y84418D01*
X562098Y84366D01*
X562443Y84160D01*
X562328Y85503D01*
X561293D01*
G01X575035Y86403D02*
Y89503D01*
X574076D01*
X573770Y89348D01*
X573578Y89141D01*
X573501Y88728D01*
X573578Y88315D01*
X573808Y88056D01*
X574076Y87901D01*
X575035D01*
G01X574076D02*
X573501Y86403D01*
G01X571168D02*
X570900Y86455D01*
X570593Y86610D01*
X570401Y86868D01*
X570325Y87230D01*
X570401Y87591D01*
X570631Y87901D01*
X570976Y88056D01*
X571360D01*
X571590Y88160D01*
X571781Y88418D01*
X571858Y88780D01*
X571743Y89141D01*
X571475Y89400D01*
X571168Y89503D01*
X570861Y89400D01*
X570593Y89141D01*
X570478Y88780D01*
X570555Y88418D01*
X570746Y88160D01*
X570976Y88056D01*
X571360D01*
X571705Y87901D01*
X571935Y87591D01*
X572011Y87230D01*
X571935Y86868D01*
X571743Y86610D01*
X571436Y86455D01*
X571168Y86403D01*
G01X568068D02*
Y89503D01*
X568528Y88883D01*
G01Y86403D02*
X567608D01*
G01X565696Y87695D02*
X565428Y88056D01*
X565198Y88263D01*
X564891Y88366D01*
X564623Y88263D01*
X564431Y88056D01*
X564278Y87746D01*
X564240Y87385D01*
X564278Y87075D01*
X564431Y86765D01*
X564661Y86506D01*
X564930Y86403D01*
X565236Y86506D01*
X565505Y86816D01*
X565658Y87281D01*
X565696Y87798D01*
X565620Y88470D01*
X565505Y88831D01*
X565313Y89193D01*
X565045Y89451D01*
X564776Y89503D01*
X564508Y89400D01*
X564316Y89141D01*
G01X573608Y138004D02*
X567408D01*
G01D02*
Y134804D01*
G01D02*
X573608D01*
G01X567408Y142004D02*
Y138804D01*
G01D02*
X573608D01*
G01Y146004D02*
X567408D01*
G01D02*
Y142804D01*
G01D02*
X573608D01*
G01Y150004D02*
X567408D01*
G01D02*
Y146804D01*
G01D02*
X573608D01*
G01Y154004D02*
X567408D01*
G01D02*
Y150804D01*
G01D02*
X573608D01*
G01X567408Y158004D02*
Y154804D01*
G01D02*
X573608D01*
G01Y142004D02*
X567408D01*
G01X561374Y147674D02*
Y150874D01*
G01X567408Y158804D02*
X573608D01*
G01Y162004D02*
X567408D01*
G01D02*
Y158804D01*
G01X573608Y158004D02*
X567408D01*
G01X570827Y184804D02*
X571057Y184959D01*
X571325Y185062D01*
X571632D01*
X571977Y184907D01*
X572245Y184649D01*
X572437Y184339D01*
X572590Y183822D01*
X572628Y183357D01*
X572552Y182892D01*
X572437Y182582D01*
X572207Y182272D01*
X571938Y182065D01*
X571670Y181962D01*
X571402D01*
X571133Y182065D01*
X570903Y182220D01*
X570712Y182427D01*
G01X568110Y181962D02*
Y185062D01*
X569528Y182840D01*
X567612D01*
G01X565470Y181962D02*
X565202Y182014D01*
X564895Y182169D01*
X564703Y182427D01*
X564627Y182789D01*
X564703Y183150D01*
X564933Y183460D01*
X565278Y183615D01*
X565662D01*
X565892Y183719D01*
X566083Y183977D01*
X566160Y184339D01*
X566045Y184700D01*
X565777Y184959D01*
X565470Y185062D01*
X565163Y184959D01*
X564895Y184700D01*
X564780Y184339D01*
X564857Y183977D01*
X565048Y183719D01*
X565278Y183615D01*
X565662D01*
X566007Y183460D01*
X566237Y183150D01*
X566313Y182789D01*
X566237Y182427D01*
X566045Y182169D01*
X565738Y182014D01*
X565470Y181962D01*
G01X562370D02*
Y185062D01*
X562830Y184442D01*
G01Y181962D02*
X561910D01*
G01X560538Y181423D02*
Y184623D01*
G01X572700Y197483D02*
X575800D01*
Y198442D01*
X575645Y198748D01*
X575438Y198940D01*
X575025Y199017D01*
X574612Y198940D01*
X574353Y198710D01*
X574198Y198442D01*
Y197483D01*
G01Y198442D02*
X572700Y199017D01*
G01Y201350D02*
X575800D01*
X575180Y200890D01*
G01X572700D02*
Y201810D01*
G01Y204450D02*
X575800D01*
X575180Y203990D01*
G01X572700D02*
Y204910D01*
G01X573320Y206707D02*
X572958Y206937D01*
X572752Y207243D01*
X572700Y207588D01*
X572752Y207895D01*
X573010Y208202D01*
X573320Y208393D01*
X573630Y208432D01*
X573992Y208355D01*
X574250Y208087D01*
X574353Y207818D01*
Y207473D01*
G01Y207818D02*
X574508Y208048D01*
X574767Y208240D01*
X575077Y208317D01*
X575387Y208240D01*
X575645Y208048D01*
X575800Y207703D01*
X575748Y207358D01*
X575542Y207013D01*
G01X573992Y209922D02*
X574353Y210190D01*
X574560Y210420D01*
X574663Y210727D01*
X574560Y210995D01*
X574353Y211187D01*
X574043Y211340D01*
X573682Y211378D01*
X573372Y211340D01*
X573062Y211187D01*
X572803Y210957D01*
X572700Y210688D01*
X572803Y210382D01*
X573113Y210113D01*
X573578Y209960D01*
X574095Y209922D01*
X574767Y209998D01*
X575128Y210113D01*
X575490Y210305D01*
X575748Y210573D01*
X575800Y210842D01*
X575697Y211110D01*
X575438Y211302D01*
G01X569000Y197483D02*
X572100D01*
Y198442D01*
X571945Y198748D01*
X571738Y198940D01*
X571325Y199017D01*
X570912Y198940D01*
X570653Y198710D01*
X570498Y198442D01*
Y197483D01*
G01Y198442D02*
X569000Y199017D01*
G01Y201350D02*
X572100D01*
X571480Y200890D01*
G01X569000D02*
Y201810D01*
G01X569620Y203607D02*
X569258Y203837D01*
X569052Y204143D01*
X569000Y204488D01*
X569052Y204795D01*
X569310Y205102D01*
X569620Y205293D01*
X569930Y205332D01*
X570292Y205255D01*
X570550Y204987D01*
X570653Y204718D01*
Y204373D01*
G01Y204718D02*
X570808Y204948D01*
X571067Y205140D01*
X571377Y205217D01*
X571687Y205140D01*
X571945Y204948D01*
X572100Y204603D01*
X572048Y204258D01*
X571842Y203913D01*
G01X571583Y206822D02*
X571893Y207052D01*
X572048Y207320D01*
X572100Y207627D01*
X571997Y208010D01*
X571738Y208278D01*
X571428Y208355D01*
X571118Y208317D01*
X570860Y208163D01*
X570343Y207397D01*
X569982Y207052D01*
X569465Y206822D01*
X569000Y206745D01*
Y208355D01*
G01X571583Y209922D02*
X571893Y210152D01*
X572048Y210420D01*
X572100Y210727D01*
X571997Y211110D01*
X571738Y211378D01*
X571428Y211455D01*
X571118Y211417D01*
X570860Y211263D01*
X570343Y210497D01*
X569982Y210152D01*
X569465Y209922D01*
X569000Y209845D01*
Y211455D01*
G01X565000Y197283D02*
X568100D01*
Y198242D01*
X567945Y198548D01*
X567738Y198740D01*
X567325Y198817D01*
X566912Y198740D01*
X566653Y198510D01*
X566498Y198242D01*
Y197283D01*
G01Y198242D02*
X565000Y198817D01*
G01Y201150D02*
X568100D01*
X567480Y200690D01*
G01X565000D02*
Y201610D01*
G01X565620Y203407D02*
X565258Y203637D01*
X565052Y203943D01*
X565000Y204288D01*
X565052Y204595D01*
X565310Y204902D01*
X565620Y205093D01*
X565930Y205132D01*
X566292Y205055D01*
X566550Y204787D01*
X566653Y204518D01*
Y204173D01*
G01Y204518D02*
X566808Y204748D01*
X567067Y204940D01*
X567377Y205017D01*
X567687Y204940D01*
X567945Y204748D01*
X568100Y204403D01*
X568048Y204058D01*
X567842Y203713D01*
G01X567583Y206622D02*
X567893Y206852D01*
X568048Y207120D01*
X568100Y207427D01*
X567997Y207810D01*
X567738Y208078D01*
X567428Y208155D01*
X567118Y208117D01*
X566860Y207963D01*
X566343Y207197D01*
X565982Y206852D01*
X565465Y206622D01*
X565000Y206545D01*
Y208155D01*
G01Y210910D02*
X568100D01*
X565878Y209492D01*
Y211408D01*
G01X561874Y239195D02*
Y232995D01*
G01D02*
X565074D01*
G01D02*
Y239195D01*
G01X568274D02*
Y232995D01*
G01D02*
X571474D01*
G01D02*
Y239195D01*
G01X563784Y242222D02*
X563939Y241992D01*
X564042Y241724D01*
Y241417D01*
X563887Y241072D01*
X563629Y240804D01*
X563319Y240612D01*
X562802Y240459D01*
X562337Y240421D01*
X561872Y240497D01*
X561562Y240612D01*
X561252Y240842D01*
X561045Y241111D01*
X560942Y241379D01*
Y241647D01*
X561045Y241916D01*
X561200Y242146D01*
X561407Y242337D01*
G01X561562Y243636D02*
X561200Y243866D01*
X560994Y244172D01*
X560942Y244517D01*
X560994Y244824D01*
X561252Y245131D01*
X561562Y245322D01*
X561872Y245361D01*
X562234Y245284D01*
X562492Y245016D01*
X562595Y244747D01*
Y244402D01*
G01Y244747D02*
X562750Y244977D01*
X563009Y245169D01*
X563319Y245246D01*
X563629Y245169D01*
X563887Y244977D01*
X564042Y244632D01*
X563990Y244287D01*
X563784Y243942D01*
G01X560942Y248039D02*
X564042D01*
X561820Y246621D01*
Y248537D01*
G01X560942Y250679D02*
X564042D01*
X563422Y250219D01*
G01X560942D02*
Y251139D01*
G01X565074Y239195D02*
X561874D01*
G01X564974Y236095D02*
X561974D01*
G01X569872Y242690D02*
X570027Y242460D01*
X570130Y242192D01*
Y241885D01*
X569975Y241540D01*
X569717Y241272D01*
X569407Y241080D01*
X568890Y240927D01*
X568425Y240889D01*
X567960Y240965D01*
X567650Y241080D01*
X567340Y241310D01*
X567133Y241579D01*
X567030Y241847D01*
Y242115D01*
X567133Y242384D01*
X567288Y242614D01*
X567495Y242805D01*
G01X567650Y244104D02*
X567288Y244334D01*
X567082Y244640D01*
X567030Y244985D01*
X567082Y245292D01*
X567340Y245599D01*
X567650Y245790D01*
X567960Y245829D01*
X568322Y245752D01*
X568580Y245484D01*
X568683Y245215D01*
Y244870D01*
G01Y245215D02*
X568838Y245445D01*
X569097Y245637D01*
X569407Y245714D01*
X569717Y245637D01*
X569975Y245445D01*
X570130Y245100D01*
X570078Y244755D01*
X569872Y244410D01*
G01X567495Y247204D02*
X567237Y247434D01*
X567082Y247702D01*
X567030Y248047D01*
X567133Y248392D01*
X567340Y248660D01*
X567702Y248852D01*
X568115Y248890D01*
X568528Y248814D01*
X568787Y248622D01*
X568993Y248354D01*
X569045Y248085D01*
X568993Y247817D01*
X568787Y247472D01*
X570130Y247587D01*
Y248622D01*
G01X567030Y251607D02*
X570130D01*
X567908Y250189D01*
Y252105D01*
G01X571474Y239195D02*
X568274D01*
G01X571374Y236095D02*
X568374D01*
G01X576384Y242222D02*
X576539Y241992D01*
X576642Y241724D01*
Y241417D01*
X576487Y241072D01*
X576229Y240804D01*
X575919Y240612D01*
X575402Y240459D01*
X574937Y240421D01*
X574472Y240497D01*
X574162Y240612D01*
X573852Y240842D01*
X573645Y241111D01*
X573542Y241379D01*
Y241647D01*
X573645Y241916D01*
X573800Y242146D01*
X574007Y242337D01*
G01X574162Y243636D02*
X573800Y243866D01*
X573594Y244172D01*
X573542Y244517D01*
X573594Y244824D01*
X573852Y245131D01*
X574162Y245322D01*
X574472Y245361D01*
X574834Y245284D01*
X575092Y245016D01*
X575195Y244747D01*
Y244402D01*
G01Y244747D02*
X575350Y244977D01*
X575609Y245169D01*
X575919Y245246D01*
X576229Y245169D01*
X576487Y244977D01*
X576642Y244632D01*
X576590Y244287D01*
X576384Y243942D01*
G01X574162Y246736D02*
X573800Y246966D01*
X573594Y247272D01*
X573542Y247617D01*
X573594Y247924D01*
X573852Y248231D01*
X574162Y248422D01*
X574472Y248461D01*
X574834Y248384D01*
X575092Y248116D01*
X575195Y247847D01*
Y247502D01*
G01Y247847D02*
X575350Y248077D01*
X575609Y248269D01*
X575919Y248346D01*
X576229Y248269D01*
X576487Y248077D01*
X576642Y247732D01*
X576590Y247387D01*
X576384Y247042D01*
G01X573904Y250027D02*
X573645Y250296D01*
X573542Y250602D01*
X573645Y250909D01*
X573955Y251177D01*
X574420Y251369D01*
X574885Y251446D01*
X575454D01*
X575919Y251369D01*
X576332Y251177D01*
X576539Y250947D01*
X576642Y250679D01*
X576539Y250372D01*
X576332Y250142D01*
X576022Y249989D01*
X575609Y249912D01*
X575247Y249989D01*
X574885Y250181D01*
X574679Y250411D01*
X574627Y250679D01*
X574730Y250986D01*
X574989Y251216D01*
X575454Y251446D01*
G01X570390Y276722D02*
X570545Y276492D01*
X570648Y276224D01*
Y275917D01*
X570493Y275572D01*
X570235Y275304D01*
X569925Y275112D01*
X569408Y274959D01*
X568943Y274921D01*
X568478Y274997D01*
X568168Y275112D01*
X567858Y275342D01*
X567651Y275611D01*
X567548Y275879D01*
Y276147D01*
X567651Y276416D01*
X567806Y276646D01*
X568013Y276837D01*
G01X568168Y278136D02*
X567806Y278366D01*
X567600Y278672D01*
X567548Y279017D01*
X567600Y279324D01*
X567858Y279631D01*
X568168Y279822D01*
X568478Y279861D01*
X568840Y279784D01*
X569098Y279516D01*
X569201Y279247D01*
Y278902D01*
G01Y279247D02*
X569356Y279477D01*
X569615Y279669D01*
X569925Y279746D01*
X570235Y279669D01*
X570493Y279477D01*
X570648Y279132D01*
X570596Y278787D01*
X570390Y278442D01*
G01X568168Y281236D02*
X567806Y281466D01*
X567600Y281772D01*
X567548Y282117D01*
X567600Y282424D01*
X567858Y282731D01*
X568168Y282922D01*
X568478Y282961D01*
X568840Y282884D01*
X569098Y282616D01*
X569201Y282347D01*
Y282002D01*
G01Y282347D02*
X569356Y282577D01*
X569615Y282769D01*
X569925Y282846D01*
X570235Y282769D01*
X570493Y282577D01*
X570648Y282232D01*
X570596Y281887D01*
X570390Y281542D01*
G01X567548Y285179D02*
X567600Y285447D01*
X567755Y285754D01*
X568013Y285946D01*
X568375Y286022D01*
X568736Y285946D01*
X569046Y285716D01*
X569201Y285371D01*
Y284987D01*
X569305Y284757D01*
X569563Y284566D01*
X569925Y284489D01*
X570286Y284604D01*
X570545Y284872D01*
X570648Y285179D01*
X570545Y285486D01*
X570286Y285754D01*
X569925Y285869D01*
X569563Y285792D01*
X569305Y285601D01*
X569201Y285371D01*
Y284987D01*
X569046Y284642D01*
X568736Y284412D01*
X568375Y284336D01*
X568013Y284412D01*
X567755Y284604D01*
X567600Y284911D01*
X567548Y285179D01*
G01X568374Y267495D02*
Y273695D01*
G01D02*
X565174D01*
G01D02*
Y267495D01*
G01D02*
X568374D01*
G01X565274Y270595D02*
X568274D01*
G01X574490Y276722D02*
X574645Y276492D01*
X574748Y276224D01*
Y275917D01*
X574593Y275572D01*
X574335Y275304D01*
X574025Y275112D01*
X573508Y274959D01*
X573043Y274921D01*
X572578Y274997D01*
X572268Y275112D01*
X571958Y275342D01*
X571751Y275611D01*
X571648Y275879D01*
Y276147D01*
X571751Y276416D01*
X571906Y276646D01*
X572113Y276837D01*
G01X572268Y278136D02*
X571906Y278366D01*
X571700Y278672D01*
X571648Y279017D01*
X571700Y279324D01*
X571958Y279631D01*
X572268Y279822D01*
X572578Y279861D01*
X572940Y279784D01*
X573198Y279516D01*
X573301Y279247D01*
Y278902D01*
G01Y279247D02*
X573456Y279477D01*
X573715Y279669D01*
X574025Y279746D01*
X574335Y279669D01*
X574593Y279477D01*
X574748Y279132D01*
X574696Y278787D01*
X574490Y278442D01*
G01X572268Y281236D02*
X571906Y281466D01*
X571700Y281772D01*
X571648Y282117D01*
X571700Y282424D01*
X571958Y282731D01*
X572268Y282922D01*
X572578Y282961D01*
X572940Y282884D01*
X573198Y282616D01*
X573301Y282347D01*
Y282002D01*
G01Y282347D02*
X573456Y282577D01*
X573715Y282769D01*
X574025Y282846D01*
X574335Y282769D01*
X574593Y282577D01*
X574748Y282232D01*
X574696Y281887D01*
X574490Y281542D01*
G01X571648Y285102D02*
X572320Y285179D01*
X572888Y285294D01*
X573405Y285447D01*
X573973Y285639D01*
X574748Y285946D01*
Y284412D01*
G01X572474Y267495D02*
Y273695D01*
G01D02*
X569274D01*
G01D02*
Y267495D01*
G01D02*
X572474D01*
G01X569374Y270595D02*
X572374D01*
G01X562674Y269288D02*
X562829Y269058D01*
X562932Y268790D01*
Y268483D01*
X562777Y268138D01*
X562519Y267870D01*
X562209Y267678D01*
X561692Y267525D01*
X561227Y267487D01*
X560762Y267563D01*
X560452Y267678D01*
X560142Y267908D01*
X559935Y268177D01*
X559832Y268445D01*
Y268713D01*
X559935Y268982D01*
X560090Y269212D01*
X560297Y269403D01*
G01X560452Y270702D02*
X560090Y270932D01*
X559884Y271238D01*
X559832Y271583D01*
X559884Y271890D01*
X560142Y272197D01*
X560452Y272388D01*
X560762Y272427D01*
X561124Y272350D01*
X561382Y272082D01*
X561485Y271813D01*
Y271468D01*
G01Y271813D02*
X561640Y272043D01*
X561899Y272235D01*
X562209Y272312D01*
X562519Y272235D01*
X562777Y272043D01*
X562932Y271698D01*
X562880Y271353D01*
X562674Y271008D01*
G01X560297Y273802D02*
X560039Y274032D01*
X559884Y274300D01*
X559832Y274645D01*
X559935Y274990D01*
X560142Y275258D01*
X560504Y275450D01*
X560917Y275488D01*
X561330Y275412D01*
X561589Y275220D01*
X561795Y274952D01*
X561847Y274683D01*
X561795Y274415D01*
X561589Y274070D01*
X562932Y274185D01*
Y275220D01*
G01X559832Y277745D02*
X562932D01*
X562312Y277285D01*
G01X559832D02*
Y278205D01*
G01X558774Y267495D02*
Y273695D01*
G01X559138Y542625D02*
Y545825D01*
G01X559238Y546525D02*
Y549725D01*
G01X570145Y552690D02*
X570375Y552845D01*
X570643Y552948D01*
X570950D01*
X571295Y552793D01*
X571563Y552535D01*
X571755Y552225D01*
X571908Y551708D01*
X571946Y551243D01*
X571870Y550778D01*
X571755Y550468D01*
X571525Y550158D01*
X571256Y549951D01*
X570988Y549848D01*
X570720D01*
X570451Y549951D01*
X570221Y550106D01*
X570030Y550313D01*
G01X568731Y550468D02*
X568501Y550106D01*
X568195Y549900D01*
X567850Y549848D01*
X567543Y549900D01*
X567236Y550158D01*
X567045Y550468D01*
X567006Y550778D01*
X567083Y551140D01*
X567351Y551398D01*
X567620Y551501D01*
X567965D01*
G01X567620D02*
X567390Y551656D01*
X567198Y551915D01*
X567121Y552225D01*
X567198Y552535D01*
X567390Y552793D01*
X567735Y552948D01*
X568080Y552896D01*
X568425Y552690D01*
G01X565631Y550468D02*
X565401Y550106D01*
X565095Y549900D01*
X564750Y549848D01*
X564443Y549900D01*
X564136Y550158D01*
X563945Y550468D01*
X563906Y550778D01*
X563983Y551140D01*
X564251Y551398D01*
X564520Y551501D01*
X564865D01*
G01X564520D02*
X564290Y551656D01*
X564098Y551915D01*
X564021Y552225D01*
X564098Y552535D01*
X564290Y552793D01*
X564635Y552948D01*
X564980Y552896D01*
X565325Y552690D01*
G01X561688Y552948D02*
X561995Y552845D01*
X562225Y552586D01*
X562378Y552276D01*
X562493Y551863D01*
X562531Y551398D01*
X562493Y550933D01*
X562378Y550520D01*
X562225Y550210D01*
X561995Y549951D01*
X561688Y549848D01*
X561381Y549951D01*
X561151Y550210D01*
X560998Y550520D01*
X560883Y550933D01*
X560845Y551398D01*
X560883Y551863D01*
X560998Y552276D01*
X561151Y552586D01*
X561381Y552845D01*
X561688Y552948D01*
G01X559138Y538725D02*
Y541925D01*
G01X569706Y558645D02*
X569936Y558800D01*
X570204Y558903D01*
X570511D01*
X570856Y558748D01*
X571124Y558490D01*
X571316Y558180D01*
X571469Y557663D01*
X571507Y557198D01*
X571431Y556733D01*
X571316Y556423D01*
X571086Y556113D01*
X570817Y555906D01*
X570549Y555803D01*
X570281D01*
X570012Y555906D01*
X569782Y556061D01*
X569591Y556268D01*
G01X567449Y555803D02*
X567181Y555855D01*
X566874Y556010D01*
X566682Y556268D01*
X566606Y556630D01*
X566682Y556991D01*
X566912Y557301D01*
X567257Y557456D01*
X567641D01*
X567871Y557560D01*
X568062Y557818D01*
X568139Y558180D01*
X568024Y558541D01*
X567756Y558800D01*
X567449Y558903D01*
X567142Y558800D01*
X566874Y558541D01*
X566759Y558180D01*
X566836Y557818D01*
X567027Y557560D01*
X567257Y557456D01*
X567641D01*
X567986Y557301D01*
X568216Y556991D01*
X568292Y556630D01*
X568216Y556268D01*
X568024Y556010D01*
X567717Y555855D01*
X567449Y555803D01*
G01X565001Y556165D02*
X564732Y555906D01*
X564426Y555803D01*
X564119Y555906D01*
X563851Y556216D01*
X563659Y556681D01*
X563582Y557146D01*
Y557715D01*
X563659Y558180D01*
X563851Y558593D01*
X564081Y558800D01*
X564349Y558903D01*
X564656Y558800D01*
X564886Y558593D01*
X565039Y558283D01*
X565116Y557870D01*
X565039Y557508D01*
X564847Y557146D01*
X564617Y556940D01*
X564349Y556888D01*
X564042Y556991D01*
X563812Y557250D01*
X563582Y557715D01*
G01X561249Y558903D02*
X561556Y558800D01*
X561786Y558541D01*
X561939Y558231D01*
X562054Y557818D01*
X562092Y557353D01*
X562054Y556888D01*
X561939Y556475D01*
X561786Y556165D01*
X561556Y555906D01*
X561249Y555803D01*
X560942Y555906D01*
X560712Y556165D01*
X560559Y556475D01*
X560444Y556888D01*
X560406Y557353D01*
X560444Y557818D01*
X560559Y558231D01*
X560712Y558541D01*
X560942Y558800D01*
X561249Y558903D01*
G01X569594Y562623D02*
X569824Y562778D01*
X570092Y562881D01*
X570399D01*
X570744Y562726D01*
X571012Y562468D01*
X571204Y562158D01*
X571357Y561641D01*
X571395Y561176D01*
X571319Y560711D01*
X571204Y560401D01*
X570974Y560091D01*
X570705Y559884D01*
X570437Y559781D01*
X570169D01*
X569900Y559884D01*
X569670Y560039D01*
X569479Y560246D01*
G01X567337Y559781D02*
X567069Y559833D01*
X566762Y559988D01*
X566570Y560246D01*
X566494Y560608D01*
X566570Y560969D01*
X566800Y561279D01*
X567145Y561434D01*
X567529D01*
X567759Y561538D01*
X567950Y561796D01*
X568027Y562158D01*
X567912Y562519D01*
X567644Y562778D01*
X567337Y562881D01*
X567030Y562778D01*
X566762Y562519D01*
X566647Y562158D01*
X566724Y561796D01*
X566915Y561538D01*
X567145Y561434D01*
X567529D01*
X567874Y561279D01*
X568104Y560969D01*
X568180Y560608D01*
X568104Y560246D01*
X567912Y559988D01*
X567605Y559833D01*
X567337Y559781D01*
G01X564237D02*
X563969Y559833D01*
X563662Y559988D01*
X563470Y560246D01*
X563394Y560608D01*
X563470Y560969D01*
X563700Y561279D01*
X564045Y561434D01*
X564429D01*
X564659Y561538D01*
X564850Y561796D01*
X564927Y562158D01*
X564812Y562519D01*
X564544Y562778D01*
X564237Y562881D01*
X563930Y562778D01*
X563662Y562519D01*
X563547Y562158D01*
X563624Y561796D01*
X563815Y561538D01*
X564045Y561434D01*
X564429D01*
X564774Y561279D01*
X565004Y560969D01*
X565080Y560608D01*
X565004Y560246D01*
X564812Y559988D01*
X564505Y559833D01*
X564237Y559781D01*
G01X561137D02*
X560869Y559833D01*
X560562Y559988D01*
X560370Y560246D01*
X560294Y560608D01*
X560370Y560969D01*
X560600Y561279D01*
X560945Y561434D01*
X561329D01*
X561559Y561538D01*
X561750Y561796D01*
X561827Y562158D01*
X561712Y562519D01*
X561444Y562778D01*
X561137Y562881D01*
X560830Y562778D01*
X560562Y562519D01*
X560447Y562158D01*
X560524Y561796D01*
X560715Y561538D01*
X560945Y561434D01*
X561329D01*
X561674Y561279D01*
X561904Y560969D01*
X561980Y560608D01*
X561904Y560246D01*
X561712Y559988D01*
X561405Y559833D01*
X561137Y559781D01*
G01X563118Y601688D02*
X563273Y601458D01*
X563376Y601190D01*
Y600883D01*
X563221Y600538D01*
X562963Y600270D01*
X562653Y600078D01*
X562136Y599925D01*
X561671Y599887D01*
X561206Y599963D01*
X560896Y600078D01*
X560586Y600308D01*
X560379Y600577D01*
X560276Y600845D01*
Y601113D01*
X560379Y601382D01*
X560534Y601612D01*
X560741Y601803D01*
G01X560276Y603945D02*
X560328Y604213D01*
X560483Y604520D01*
X560741Y604712D01*
X561103Y604788D01*
X561464Y604712D01*
X561774Y604482D01*
X561929Y604137D01*
Y603753D01*
X562033Y603523D01*
X562291Y603332D01*
X562653Y603255D01*
X563014Y603370D01*
X563273Y603638D01*
X563376Y603945D01*
X563273Y604252D01*
X563014Y604520D01*
X562653Y604635D01*
X562291Y604558D01*
X562033Y604367D01*
X561929Y604137D01*
Y603753D01*
X561774Y603408D01*
X561464Y603178D01*
X561103Y603102D01*
X560741Y603178D01*
X560483Y603370D01*
X560328Y603677D01*
X560276Y603945D01*
G01X561568Y606317D02*
X561929Y606585D01*
X562136Y606815D01*
X562239Y607122D01*
X562136Y607390D01*
X561929Y607582D01*
X561619Y607735D01*
X561258Y607773D01*
X560948Y607735D01*
X560638Y607582D01*
X560379Y607352D01*
X560276Y607083D01*
X560379Y606777D01*
X560689Y606508D01*
X561154Y606355D01*
X561671Y606317D01*
X562343Y606393D01*
X562704Y606508D01*
X563066Y606700D01*
X563324Y606968D01*
X563376Y607237D01*
X563273Y607505D01*
X563014Y607697D01*
G01X560276Y610145D02*
X560328Y610413D01*
X560483Y610720D01*
X560741Y610912D01*
X561103Y610988D01*
X561464Y610912D01*
X561774Y610682D01*
X561929Y610337D01*
Y609953D01*
X562033Y609723D01*
X562291Y609532D01*
X562653Y609455D01*
X563014Y609570D01*
X563273Y609838D01*
X563376Y610145D01*
X563273Y610452D01*
X563014Y610720D01*
X562653Y610835D01*
X562291Y610758D01*
X562033Y610567D01*
X561929Y610337D01*
Y609953D01*
X561774Y609608D01*
X561464Y609378D01*
X561103Y609302D01*
X560741Y609378D01*
X560483Y609570D01*
X560328Y609877D01*
X560276Y610145D01*
G01X560667Y625847D02*
X563767D01*
Y626806D01*
X563612Y627112D01*
X563405Y627304D01*
X562992Y627381D01*
X562579Y627304D01*
X562320Y627074D01*
X562165Y626806D01*
Y625847D01*
G01Y626806D02*
X560667Y627381D01*
G01Y629714D02*
X563767D01*
X563147Y629254D01*
G01X560667D02*
Y630174D01*
G01X563767Y632814D02*
X563664Y632507D01*
X563405Y632277D01*
X563095Y632124D01*
X562682Y632009D01*
X562217Y631971D01*
X561752Y632009D01*
X561339Y632124D01*
X561029Y632277D01*
X560770Y632507D01*
X560667Y632814D01*
X560770Y633121D01*
X561029Y633351D01*
X561339Y633504D01*
X561752Y633619D01*
X562217Y633657D01*
X562682Y633619D01*
X563095Y633504D01*
X563405Y633351D01*
X563664Y633121D01*
X563767Y632814D01*
G01Y635914D02*
X563664Y635607D01*
X563405Y635377D01*
X563095Y635224D01*
X562682Y635109D01*
X562217Y635071D01*
X561752Y635109D01*
X561339Y635224D01*
X561029Y635377D01*
X560770Y635607D01*
X560667Y635914D01*
X560770Y636221D01*
X561029Y636451D01*
X561339Y636604D01*
X561752Y636719D01*
X562217Y636757D01*
X562682Y636719D01*
X563095Y636604D01*
X563405Y636451D01*
X563664Y636221D01*
X563767Y635914D01*
G01X560667Y639014D02*
X563767D01*
X563147Y638554D01*
G01X560667D02*
Y639474D01*
G01X564008Y641523D02*
Y644723D01*
G01X562440Y667556D02*
Y670756D01*
G01Y671556D02*
Y674756D01*
G01Y663556D02*
Y666756D01*
G01Y675556D02*
Y678756D01*
G01Y687556D02*
Y690756D01*
G01Y683556D02*
Y686756D01*
G01Y679556D02*
Y682756D01*
G01X574355Y707786D02*
Y705564D01*
X574202Y705099D01*
X573895Y704789D01*
X573512Y704686D01*
X573129Y704789D01*
X572822Y705099D01*
X572669Y705564D01*
Y707786D01*
G01X571140Y705978D02*
X570872Y706339D01*
X570642Y706546D01*
X570335Y706649D01*
X570067Y706546D01*
X569875Y706339D01*
X569722Y706029D01*
X569684Y705668D01*
X569722Y705358D01*
X569875Y705048D01*
X570105Y704789D01*
X570374Y704686D01*
X570680Y704789D01*
X570949Y705099D01*
X571102Y705564D01*
X571140Y706081D01*
X571064Y706753D01*
X570949Y707114D01*
X570757Y707476D01*
X570489Y707734D01*
X570220Y707786D01*
X569952Y707683D01*
X569760Y707424D01*
G01X568040Y705978D02*
X567772Y706339D01*
X567542Y706546D01*
X567235Y706649D01*
X566967Y706546D01*
X566775Y706339D01*
X566622Y706029D01*
X566584Y705668D01*
X566622Y705358D01*
X566775Y705048D01*
X567005Y704789D01*
X567274Y704686D01*
X567580Y704789D01*
X567849Y705099D01*
X568002Y705564D01*
X568040Y706081D01*
X567964Y706753D01*
X567849Y707114D01*
X567657Y707476D01*
X567389Y707734D01*
X567120Y707786D01*
X566852Y707683D01*
X566660Y707424D01*
G01X562440Y691556D02*
Y694756D01*
G01Y699556D02*
Y702756D01*
G01Y695556D02*
Y698756D01*
G01X567440Y728156D02*
X570440D01*
G01X567340Y725056D02*
X570540D01*
G01X567340Y731256D02*
Y725056D01*
G01X570540Y731256D02*
X567340D01*
G01X570540Y725056D02*
Y731256D01*
G01X562840Y737056D02*
X566040D01*
G01X562840Y743256D02*
Y737056D01*
G01X566040D02*
Y743256D01*
G01X571840Y737056D02*
X575040D01*
G01X571840Y743256D02*
Y737056D01*
G01X558440Y728156D02*
X561440D01*
G01X558340Y725056D02*
X561540D01*
G01X558340Y731256D02*
Y725056D01*
G01X561540Y731256D02*
X558340D01*
G01X561540Y725056D02*
Y731256D01*
G01X570540Y737056D02*
Y743256D01*
G01X567340Y737056D02*
X570540D01*
G01X567340Y743256D02*
Y737056D01*
G01X575040Y731256D02*
X571840D01*
G01Y725056D02*
X575040D01*
G01X571840Y731256D02*
Y725056D01*
G01X566040Y731256D02*
X562840D01*
G01X566040Y725056D02*
Y731256D01*
G01X562840Y725056D02*
X566040D01*
G01X562840Y731256D02*
Y725056D01*
G01X558340Y737056D02*
X561540D01*
G01X558340Y743256D02*
Y737056D01*
G01X561540D02*
Y743256D01*
G01X562940Y740156D02*
X565940D01*
G01X566040Y743256D02*
X562840D01*
G01X571940Y740156D02*
X574940D01*
G01X575040Y743256D02*
X571840D01*
G01X572702Y747305D02*
X572857Y747075D01*
X572960Y746807D01*
Y746500D01*
X572805Y746155D01*
X572547Y745887D01*
X572237Y745695D01*
X571720Y745542D01*
X571255Y745504D01*
X570790Y745580D01*
X570480Y745695D01*
X570170Y745925D01*
X569963Y746194D01*
X569860Y746462D01*
Y746730D01*
X569963Y746999D01*
X570118Y747229D01*
X570325Y747420D01*
G01X569860Y749485D02*
X570532Y749562D01*
X571100Y749677D01*
X571617Y749830D01*
X572185Y750022D01*
X572960Y750329D01*
Y748795D01*
G01X572443Y751934D02*
X572753Y752164D01*
X572908Y752432D01*
X572960Y752739D01*
X572857Y753122D01*
X572598Y753390D01*
X572288Y753467D01*
X571978Y753429D01*
X571720Y753275D01*
X571203Y752509D01*
X570842Y752164D01*
X570325Y751934D01*
X569860Y751857D01*
Y753467D01*
G01X571152Y755034D02*
X571513Y755302D01*
X571720Y755532D01*
X571823Y755839D01*
X571720Y756107D01*
X571513Y756299D01*
X571203Y756452D01*
X570842Y756490D01*
X570532Y756452D01*
X570222Y756299D01*
X569963Y756069D01*
X569860Y755800D01*
X569963Y755494D01*
X570273Y755225D01*
X570738Y755072D01*
X571255Y755034D01*
X571927Y755110D01*
X572288Y755225D01*
X572650Y755417D01*
X572908Y755685D01*
X572960Y755954D01*
X572857Y756222D01*
X572598Y756414D01*
G01X574370Y745695D02*
X577470D01*
Y746654D01*
X577315Y746960D01*
X577108Y747152D01*
X576695Y747229D01*
X576282Y747152D01*
X576023Y746922D01*
X575868Y746654D01*
Y745695D01*
G01Y746654D02*
X574370Y747229D01*
G01X574732Y748910D02*
X574473Y749179D01*
X574370Y749485D01*
X574473Y749792D01*
X574783Y750060D01*
X575248Y750252D01*
X575713Y750329D01*
X576282D01*
X576747Y750252D01*
X577160Y750060D01*
X577367Y749830D01*
X577470Y749562D01*
X577367Y749255D01*
X577160Y749025D01*
X576850Y748872D01*
X576437Y748795D01*
X576075Y748872D01*
X575713Y749064D01*
X575507Y749294D01*
X575455Y749562D01*
X575558Y749869D01*
X575817Y750099D01*
X576282Y750329D01*
G01X575662Y751934D02*
X576023Y752202D01*
X576230Y752432D01*
X576333Y752739D01*
X576230Y753007D01*
X576023Y753199D01*
X575713Y753352D01*
X575352Y753390D01*
X575042Y753352D01*
X574732Y753199D01*
X574473Y752969D01*
X574370Y752700D01*
X574473Y752394D01*
X574783Y752125D01*
X575248Y751972D01*
X575765Y751934D01*
X576437Y752010D01*
X576798Y752125D01*
X577160Y752317D01*
X577418Y752585D01*
X577470Y752854D01*
X577367Y753122D01*
X577108Y753314D01*
G01X577470Y755762D02*
X577367Y755455D01*
X577108Y755225D01*
X576798Y755072D01*
X576385Y754957D01*
X575920Y754919D01*
X575455Y754957D01*
X575042Y755072D01*
X574732Y755225D01*
X574473Y755455D01*
X574370Y755762D01*
X574473Y756069D01*
X574732Y756299D01*
X575042Y756452D01*
X575455Y756567D01*
X575920Y756605D01*
X576385Y756567D01*
X576798Y756452D01*
X577108Y756299D01*
X577367Y756069D01*
X577470Y755762D01*
G01X570540Y743256D02*
X567340D01*
G01X561970Y745695D02*
X565070D01*
Y746654D01*
X564915Y746960D01*
X564708Y747152D01*
X564295Y747229D01*
X563882Y747152D01*
X563623Y746922D01*
X563468Y746654D01*
Y745695D01*
G01Y746654D02*
X561970Y747229D01*
G01X562332Y748910D02*
X562073Y749179D01*
X561970Y749485D01*
X562073Y749792D01*
X562383Y750060D01*
X562848Y750252D01*
X563313Y750329D01*
X563882D01*
X564347Y750252D01*
X564760Y750060D01*
X564967Y749830D01*
X565070Y749562D01*
X564967Y749255D01*
X564760Y749025D01*
X564450Y748872D01*
X564037Y748795D01*
X563675Y748872D01*
X563313Y749064D01*
X563107Y749294D01*
X563055Y749562D01*
X563158Y749869D01*
X563417Y750099D01*
X563882Y750329D01*
G01X563262Y751934D02*
X563623Y752202D01*
X563830Y752432D01*
X563933Y752739D01*
X563830Y753007D01*
X563623Y753199D01*
X563313Y753352D01*
X562952Y753390D01*
X562642Y753352D01*
X562332Y753199D01*
X562073Y752969D01*
X561970Y752700D01*
X562073Y752394D01*
X562383Y752125D01*
X562848Y751972D01*
X563365Y751934D01*
X564037Y752010D01*
X564398Y752125D01*
X564760Y752317D01*
X565018Y752585D01*
X565070Y752854D01*
X564967Y753122D01*
X564708Y753314D01*
G01X563262Y755034D02*
X563623Y755302D01*
X563830Y755532D01*
X563933Y755839D01*
X563830Y756107D01*
X563623Y756299D01*
X563313Y756452D01*
X562952Y756490D01*
X562642Y756452D01*
X562332Y756299D01*
X562073Y756069D01*
X561970Y755800D01*
X562073Y755494D01*
X562383Y755225D01*
X562848Y755072D01*
X563365Y755034D01*
X564037Y755110D01*
X564398Y755225D01*
X564760Y755417D01*
X565018Y755685D01*
X565070Y755954D01*
X564967Y756222D01*
X564708Y756414D01*
G01X561540Y743256D02*
X558340D01*
G01X567601Y759623D02*
X567756Y759393D01*
X567859Y759125D01*
Y758818D01*
X567704Y758473D01*
X567446Y758205D01*
X567136Y758013D01*
X566619Y757860D01*
X566154Y757822D01*
X565689Y757898D01*
X565379Y758013D01*
X565069Y758243D01*
X564862Y758512D01*
X564759Y758780D01*
Y759048D01*
X564862Y759317D01*
X565017Y759547D01*
X565224Y759738D01*
G01X564759Y761803D02*
X565431Y761880D01*
X565999Y761995D01*
X566516Y762148D01*
X567084Y762340D01*
X567859Y762647D01*
Y761113D01*
G01X567342Y764252D02*
X567652Y764482D01*
X567807Y764750D01*
X567859Y765057D01*
X567756Y765440D01*
X567497Y765708D01*
X567187Y765785D01*
X566877Y765747D01*
X566619Y765593D01*
X566102Y764827D01*
X565741Y764482D01*
X565224Y764252D01*
X564759Y764175D01*
Y765785D01*
G01X565121Y767428D02*
X564862Y767697D01*
X564759Y768003D01*
X564862Y768310D01*
X565172Y768578D01*
X565637Y768770D01*
X566102Y768847D01*
X566671D01*
X567136Y768770D01*
X567549Y768578D01*
X567756Y768348D01*
X567859Y768080D01*
X567756Y767773D01*
X567549Y767543D01*
X567239Y767390D01*
X566826Y767313D01*
X566464Y767390D01*
X566102Y767582D01*
X565896Y767812D01*
X565844Y768080D01*
X565947Y768387D01*
X566206Y768617D01*
X566671Y768847D01*
G01X577212Y759623D02*
X577367Y759393D01*
X577470Y759125D01*
Y758818D01*
X577315Y758473D01*
X577057Y758205D01*
X576747Y758013D01*
X576230Y757860D01*
X575765Y757822D01*
X575300Y757898D01*
X574990Y758013D01*
X574680Y758243D01*
X574473Y758512D01*
X574370Y758780D01*
Y759048D01*
X574473Y759317D01*
X574628Y759547D01*
X574835Y759738D01*
G01X574370Y761803D02*
X575042Y761880D01*
X575610Y761995D01*
X576127Y762148D01*
X576695Y762340D01*
X577470Y762647D01*
Y761113D01*
G01X576953Y764252D02*
X577263Y764482D01*
X577418Y764750D01*
X577470Y765057D01*
X577367Y765440D01*
X577108Y765708D01*
X576798Y765785D01*
X576488Y765747D01*
X576230Y765593D01*
X575713Y764827D01*
X575352Y764482D01*
X574835Y764252D01*
X574370Y764175D01*
Y765785D01*
G01X574990Y767237D02*
X574628Y767467D01*
X574422Y767773D01*
X574370Y768118D01*
X574422Y768425D01*
X574680Y768732D01*
X574990Y768923D01*
X575300Y768962D01*
X575662Y768885D01*
X575920Y768617D01*
X576023Y768348D01*
Y768003D01*
G01Y768348D02*
X576178Y768578D01*
X576437Y768770D01*
X576747Y768847D01*
X577057Y768770D01*
X577315Y768578D01*
X577470Y768233D01*
X577418Y767888D01*
X577212Y767543D01*
G01X560556Y758013D02*
X563656D01*
Y758972D01*
X563501Y759278D01*
X563294Y759470D01*
X562881Y759547D01*
X562468Y759470D01*
X562209Y759240D01*
X562054Y758972D01*
Y758013D01*
G01Y758972D02*
X560556Y759547D01*
G01X560918Y761228D02*
X560659Y761497D01*
X560556Y761803D01*
X560659Y762110D01*
X560969Y762378D01*
X561434Y762570D01*
X561899Y762647D01*
X562468D01*
X562933Y762570D01*
X563346Y762378D01*
X563553Y762148D01*
X563656Y761880D01*
X563553Y761573D01*
X563346Y761343D01*
X563036Y761190D01*
X562623Y761113D01*
X562261Y761190D01*
X561899Y761382D01*
X561693Y761612D01*
X561641Y761880D01*
X561744Y762187D01*
X562003Y762417D01*
X562468Y762647D01*
G01X561848Y764252D02*
X562209Y764520D01*
X562416Y764750D01*
X562519Y765057D01*
X562416Y765325D01*
X562209Y765517D01*
X561899Y765670D01*
X561538Y765708D01*
X561228Y765670D01*
X560918Y765517D01*
X560659Y765287D01*
X560556Y765018D01*
X560659Y764712D01*
X560969Y764443D01*
X561434Y764290D01*
X561951Y764252D01*
X562623Y764328D01*
X562984Y764443D01*
X563346Y764635D01*
X563604Y764903D01*
X563656Y765172D01*
X563553Y765440D01*
X563294Y765632D01*
G01X560918Y767428D02*
X560659Y767697D01*
X560556Y768003D01*
X560659Y768310D01*
X560969Y768578D01*
X561434Y768770D01*
X561899Y768847D01*
X562468D01*
X562933Y768770D01*
X563346Y768578D01*
X563553Y768348D01*
X563656Y768080D01*
X563553Y767773D01*
X563346Y767543D01*
X563036Y767390D01*
X562623Y767313D01*
X562261Y767390D01*
X561899Y767582D01*
X561693Y767812D01*
X561641Y768080D01*
X561744Y768387D01*
X562003Y768617D01*
X562468Y768847D01*
G01X569670Y758013D02*
X572770D01*
Y758972D01*
X572615Y759278D01*
X572408Y759470D01*
X571995Y759547D01*
X571582Y759470D01*
X571323Y759240D01*
X571168Y758972D01*
Y758013D01*
G01Y758972D02*
X569670Y759547D01*
G01X570032Y761228D02*
X569773Y761497D01*
X569670Y761803D01*
X569773Y762110D01*
X570083Y762378D01*
X570548Y762570D01*
X571013Y762647D01*
X571582D01*
X572047Y762570D01*
X572460Y762378D01*
X572667Y762148D01*
X572770Y761880D01*
X572667Y761573D01*
X572460Y761343D01*
X572150Y761190D01*
X571737Y761113D01*
X571375Y761190D01*
X571013Y761382D01*
X570807Y761612D01*
X570755Y761880D01*
X570858Y762187D01*
X571117Y762417D01*
X571582Y762647D01*
G01X570962Y764252D02*
X571323Y764520D01*
X571530Y764750D01*
X571633Y765057D01*
X571530Y765325D01*
X571323Y765517D01*
X571013Y765670D01*
X570652Y765708D01*
X570342Y765670D01*
X570032Y765517D01*
X569773Y765287D01*
X569670Y765018D01*
X569773Y764712D01*
X570083Y764443D01*
X570548Y764290D01*
X571065Y764252D01*
X571737Y764328D01*
X572098Y764443D01*
X572460Y764635D01*
X572718Y764903D01*
X572770Y765172D01*
X572667Y765440D01*
X572408Y765632D01*
G01X570290Y767237D02*
X569928Y767467D01*
X569722Y767773D01*
X569670Y768118D01*
X569722Y768425D01*
X569980Y768732D01*
X570290Y768923D01*
X570600Y768962D01*
X570962Y768885D01*
X571220Y768617D01*
X571323Y768348D01*
Y768003D01*
G01Y768348D02*
X571478Y768578D01*
X571737Y768770D01*
X572047Y768847D01*
X572357Y768770D01*
X572615Y768578D01*
X572770Y768233D01*
X572718Y767888D01*
X572512Y767543D01*
G01X573608Y134804D02*
Y138004D01*
G01Y138804D02*
Y142004D01*
G01Y142804D02*
Y146004D01*
G01Y146804D02*
Y150004D01*
G01Y150804D02*
Y154004D01*
G01Y154804D02*
Y158004D01*
G01Y158804D02*
Y162004D01*
G01X576600Y197483D02*
X579700D01*
Y198442D01*
X579545Y198748D01*
X579338Y198940D01*
X578925Y199017D01*
X578512Y198940D01*
X578253Y198710D01*
X578098Y198442D01*
Y197483D01*
G01Y198442D02*
X576600Y199017D01*
G01Y201350D02*
X579700D01*
X579080Y200890D01*
G01X576600D02*
Y201810D01*
G01Y204450D02*
X579700D01*
X579080Y203990D01*
G01X576600D02*
Y204910D01*
G01X577220Y206707D02*
X576858Y206937D01*
X576652Y207243D01*
X576600Y207588D01*
X576652Y207895D01*
X576910Y208202D01*
X577220Y208393D01*
X577530Y208432D01*
X577892Y208355D01*
X578150Y208087D01*
X578253Y207818D01*
Y207473D01*
G01Y207818D02*
X578408Y208048D01*
X578667Y208240D01*
X578977Y208317D01*
X579287Y208240D01*
X579545Y208048D01*
X579700Y207703D01*
X579648Y207358D01*
X579442Y207013D01*
G01X576600Y210573D02*
X577272Y210650D01*
X577840Y210765D01*
X578357Y210918D01*
X578925Y211110D01*
X579700Y211417D01*
Y209883D01*
G01X580500Y197683D02*
X583600D01*
Y198642D01*
X583445Y198948D01*
X583238Y199140D01*
X582825Y199217D01*
X582412Y199140D01*
X582153Y198910D01*
X581998Y198642D01*
Y197683D01*
G01Y198642D02*
X580500Y199217D01*
G01Y201550D02*
X583600D01*
X582980Y201090D01*
G01X580500D02*
Y202010D01*
G01Y204650D02*
X583600D01*
X582980Y204190D01*
G01X580500D02*
Y205110D01*
G01X581120Y206907D02*
X580758Y207137D01*
X580552Y207443D01*
X580500Y207788D01*
X580552Y208095D01*
X580810Y208402D01*
X581120Y208593D01*
X581430Y208632D01*
X581792Y208555D01*
X582050Y208287D01*
X582153Y208018D01*
Y207673D01*
G01Y208018D02*
X582308Y208248D01*
X582567Y208440D01*
X582877Y208517D01*
X583187Y208440D01*
X583445Y208248D01*
X583600Y207903D01*
X583548Y207558D01*
X583342Y207213D01*
G01X581120Y210007D02*
X580758Y210237D01*
X580552Y210543D01*
X580500Y210888D01*
X580552Y211195D01*
X580810Y211502D01*
X581120Y211693D01*
X581430Y211732D01*
X581792Y211655D01*
X582050Y211387D01*
X582153Y211118D01*
Y210773D01*
G01Y211118D02*
X582308Y211348D01*
X582567Y211540D01*
X582877Y211617D01*
X583187Y211540D01*
X583445Y211348D01*
X583600Y211003D01*
X583548Y210658D01*
X583342Y210313D01*
G01X587500Y197883D02*
X590600D01*
Y198842D01*
X590445Y199148D01*
X590238Y199340D01*
X589825Y199417D01*
X589412Y199340D01*
X589153Y199110D01*
X588998Y198842D01*
Y197883D01*
G01Y198842D02*
X587500Y199417D01*
G01Y201750D02*
X590600D01*
X589980Y201290D01*
G01X587500D02*
Y202210D01*
G01Y204850D02*
X590600D01*
X589980Y204390D01*
G01X587500D02*
Y205310D01*
G01X588120Y207107D02*
X587758Y207337D01*
X587552Y207643D01*
X587500Y207988D01*
X587552Y208295D01*
X587810Y208602D01*
X588120Y208793D01*
X588430Y208832D01*
X588792Y208755D01*
X589050Y208487D01*
X589153Y208218D01*
Y207873D01*
G01Y208218D02*
X589308Y208448D01*
X589567Y208640D01*
X589877Y208717D01*
X590187Y208640D01*
X590445Y208448D01*
X590600Y208103D01*
X590548Y207758D01*
X590342Y207413D01*
G01X590083Y210322D02*
X590393Y210552D01*
X590548Y210820D01*
X590600Y211127D01*
X590497Y211510D01*
X590238Y211778D01*
X589928Y211855D01*
X589618Y211817D01*
X589360Y211663D01*
X588843Y210897D01*
X588482Y210552D01*
X587965Y210322D01*
X587500Y210245D01*
Y211855D01*
G01X590445Y237665D02*
X590675Y237820D01*
X590943Y237923D01*
X591250D01*
X591595Y237768D01*
X591863Y237510D01*
X592055Y237200D01*
X592208Y236683D01*
X592246Y236218D01*
X592170Y235753D01*
X592055Y235443D01*
X591825Y235133D01*
X591556Y234926D01*
X591288Y234823D01*
X591020D01*
X590751Y234926D01*
X590521Y235081D01*
X590330Y235288D01*
G01X589031Y235443D02*
X588801Y235081D01*
X588495Y234875D01*
X588150Y234823D01*
X587843Y234875D01*
X587536Y235133D01*
X587345Y235443D01*
X587306Y235753D01*
X587383Y236115D01*
X587651Y236373D01*
X587920Y236476D01*
X588265D01*
G01X587920D02*
X587690Y236631D01*
X587498Y236890D01*
X587421Y237200D01*
X587498Y237510D01*
X587690Y237768D01*
X588035Y237923D01*
X588380Y237871D01*
X588725Y237665D01*
G01X585931Y235443D02*
X585701Y235081D01*
X585395Y234875D01*
X585050Y234823D01*
X584743Y234875D01*
X584436Y235133D01*
X584245Y235443D01*
X584206Y235753D01*
X584283Y236115D01*
X584551Y236373D01*
X584820Y236476D01*
X585165D01*
G01X584820D02*
X584590Y236631D01*
X584398Y236890D01*
X584321Y237200D01*
X584398Y237510D01*
X584590Y237768D01*
X584935Y237923D01*
X585280Y237871D01*
X585625Y237665D01*
G01X582716Y236115D02*
X582448Y236476D01*
X582218Y236683D01*
X581911Y236786D01*
X581643Y236683D01*
X581451Y236476D01*
X581298Y236166D01*
X581260Y235805D01*
X581298Y235495D01*
X581451Y235185D01*
X581681Y234926D01*
X581950Y234823D01*
X582256Y234926D01*
X582525Y235236D01*
X582678Y235701D01*
X582716Y236218D01*
X582640Y236890D01*
X582525Y237251D01*
X582333Y237613D01*
X582065Y237871D01*
X581796Y237923D01*
X581528Y237820D01*
X581336Y237561D01*
G01X577674Y232995D02*
Y239195D01*
G01X574474D02*
Y232995D01*
G01D02*
X577674D01*
G01X585474Y239295D02*
X591674D01*
G01Y242495D02*
X585474D01*
G01D02*
Y239295D01*
G01X588574Y242395D02*
Y239395D01*
G01X577674Y239195D02*
X574474D01*
G01X577574Y236095D02*
X574574D01*
G01X597378Y281737D02*
X597608Y281892D01*
X597876Y281995D01*
X598183D01*
X598528Y281840D01*
X598796Y281582D01*
X598988Y281272D01*
X599141Y280755D01*
X599179Y280290D01*
X599103Y279825D01*
X598988Y279515D01*
X598758Y279205D01*
X598489Y278998D01*
X598221Y278895D01*
X597953D01*
X597684Y278998D01*
X597454Y279153D01*
X597263Y279360D01*
G01X595964Y279515D02*
X595734Y279153D01*
X595428Y278947D01*
X595083Y278895D01*
X594776Y278947D01*
X594469Y279205D01*
X594278Y279515D01*
X594239Y279825D01*
X594316Y280187D01*
X594584Y280445D01*
X594853Y280548D01*
X595198D01*
G01X594853D02*
X594623Y280703D01*
X594431Y280962D01*
X594354Y281272D01*
X594431Y281582D01*
X594623Y281840D01*
X594968Y281995D01*
X595313Y281943D01*
X595658Y281737D01*
G01X592864Y279360D02*
X592634Y279102D01*
X592366Y278947D01*
X592021Y278895D01*
X591676Y278998D01*
X591408Y279205D01*
X591216Y279567D01*
X591178Y279980D01*
X591254Y280393D01*
X591446Y280652D01*
X591714Y280858D01*
X591983Y280910D01*
X592251Y280858D01*
X592596Y280652D01*
X592481Y281995D01*
X591446D01*
G01X588921D02*
X589228Y281892D01*
X589458Y281633D01*
X589611Y281323D01*
X589726Y280910D01*
X589764Y280445D01*
X589726Y279980D01*
X589611Y279567D01*
X589458Y279257D01*
X589228Y278998D01*
X588921Y278895D01*
X588614Y278998D01*
X588384Y279257D01*
X588231Y279567D01*
X588116Y279980D01*
X588078Y280445D01*
X588116Y280910D01*
X588231Y281323D01*
X588384Y281633D01*
X588614Y281892D01*
X588921Y281995D01*
G01X576841Y276493D02*
X583041D01*
G01D02*
Y279693D01*
G01D02*
X576841D01*
G01D02*
Y276493D01*
G01X579941Y279593D02*
Y276593D01*
G01X576841Y283693D02*
Y280493D01*
G01D02*
X583041D01*
G01D02*
Y283693D01*
G01X579941Y280593D02*
Y283593D01*
G01X597378Y290106D02*
X597608Y290261D01*
X597876Y290364D01*
X598183D01*
X598528Y290209D01*
X598796Y289951D01*
X598988Y289641D01*
X599141Y289124D01*
X599179Y288659D01*
X599103Y288194D01*
X598988Y287884D01*
X598758Y287574D01*
X598489Y287367D01*
X598221Y287264D01*
X597953D01*
X597684Y287367D01*
X597454Y287522D01*
X597263Y287729D01*
G01X595964Y287884D02*
X595734Y287522D01*
X595428Y287316D01*
X595083Y287264D01*
X594776Y287316D01*
X594469Y287574D01*
X594278Y287884D01*
X594239Y288194D01*
X594316Y288556D01*
X594584Y288814D01*
X594853Y288917D01*
X595198D01*
G01X594853D02*
X594623Y289072D01*
X594431Y289331D01*
X594354Y289641D01*
X594431Y289951D01*
X594623Y290209D01*
X594968Y290364D01*
X595313Y290312D01*
X595658Y290106D01*
G01X591561Y287264D02*
Y290364D01*
X592979Y288142D01*
X591063D01*
G01X588921Y287264D02*
X588653Y287316D01*
X588346Y287471D01*
X588154Y287729D01*
X588078Y288091D01*
X588154Y288452D01*
X588384Y288762D01*
X588729Y288917D01*
X589113D01*
X589343Y289021D01*
X589534Y289279D01*
X589611Y289641D01*
X589496Y290002D01*
X589228Y290261D01*
X588921Y290364D01*
X588614Y290261D01*
X588346Y290002D01*
X588231Y289641D01*
X588308Y289279D01*
X588499Y289021D01*
X588729Y288917D01*
X589113D01*
X589458Y288762D01*
X589688Y288452D01*
X589764Y288091D01*
X589688Y287729D01*
X589496Y287471D01*
X589189Y287316D01*
X588921Y287264D01*
G01X576841Y284493D02*
X583041D01*
G01D02*
Y287693D01*
G01D02*
X576841D01*
G01D02*
Y284493D01*
G01X579941Y287593D02*
Y284593D01*
G01X597378Y294336D02*
X597608Y294491D01*
X597876Y294594D01*
X598183D01*
X598528Y294439D01*
X598796Y294181D01*
X598988Y293871D01*
X599141Y293354D01*
X599179Y292889D01*
X599103Y292424D01*
X598988Y292114D01*
X598758Y291804D01*
X598489Y291597D01*
X598221Y291494D01*
X597953D01*
X597684Y291597D01*
X597454Y291752D01*
X597263Y291959D01*
G01X595964Y292114D02*
X595734Y291752D01*
X595428Y291546D01*
X595083Y291494D01*
X594776Y291546D01*
X594469Y291804D01*
X594278Y292114D01*
X594239Y292424D01*
X594316Y292786D01*
X594584Y293044D01*
X594853Y293147D01*
X595198D01*
G01X594853D02*
X594623Y293302D01*
X594431Y293561D01*
X594354Y293871D01*
X594431Y294181D01*
X594623Y294439D01*
X594968Y294594D01*
X595313Y294542D01*
X595658Y294336D01*
G01X591561Y291494D02*
Y294594D01*
X592979Y292372D01*
X591063D01*
G01X588998Y291494D02*
X588921Y292166D01*
X588806Y292734D01*
X588653Y293251D01*
X588461Y293819D01*
X588154Y294594D01*
X589688D01*
G01X576841Y288493D02*
X583041D01*
G01D02*
Y291693D01*
G01D02*
X576841D01*
G01D02*
Y288493D01*
G01X579941Y291593D02*
Y288593D01*
G01X597378Y285967D02*
X597608Y286122D01*
X597876Y286225D01*
X598183D01*
X598528Y286070D01*
X598796Y285812D01*
X598988Y285502D01*
X599141Y284985D01*
X599179Y284520D01*
X599103Y284055D01*
X598988Y283745D01*
X598758Y283435D01*
X598489Y283228D01*
X598221Y283125D01*
X597953D01*
X597684Y283228D01*
X597454Y283383D01*
X597263Y283590D01*
G01X595964Y283745D02*
X595734Y283383D01*
X595428Y283177D01*
X595083Y283125D01*
X594776Y283177D01*
X594469Y283435D01*
X594278Y283745D01*
X594239Y284055D01*
X594316Y284417D01*
X594584Y284675D01*
X594853Y284778D01*
X595198D01*
G01X594853D02*
X594623Y284933D01*
X594431Y285192D01*
X594354Y285502D01*
X594431Y285812D01*
X594623Y286070D01*
X594968Y286225D01*
X595313Y286173D01*
X595658Y285967D01*
G01X591561Y283125D02*
Y286225D01*
X592979Y284003D01*
X591063D01*
G01X589573Y283487D02*
X589304Y283228D01*
X588998Y283125D01*
X588691Y283228D01*
X588423Y283538D01*
X588231Y284003D01*
X588154Y284468D01*
Y285037D01*
X588231Y285502D01*
X588423Y285915D01*
X588653Y286122D01*
X588921Y286225D01*
X589228Y286122D01*
X589458Y285915D01*
X589611Y285605D01*
X589688Y285192D01*
X589611Y284830D01*
X589419Y284468D01*
X589189Y284262D01*
X588921Y284210D01*
X588614Y284313D01*
X588384Y284572D01*
X588154Y285037D01*
G01X583041Y283693D02*
X576841D01*
G01X583041Y295693D02*
X576841D01*
G01D02*
Y292493D01*
G01D02*
X583041D01*
G01D02*
Y295693D01*
G01X580291Y292493D02*
Y295693D01*
G01X579591Y292493D02*
Y295693D01*
G01X598872Y666477D02*
X599562D01*
Y654002D01*
X602634D01*
Y621592D01*
X586899D01*
Y653814D01*
X599500D01*
G01X600071Y626698D02*
Y629798D01*
X599112D01*
X598806Y629643D01*
X598614Y629436D01*
X598537Y629023D01*
X598614Y628610D01*
X598844Y628351D01*
X599112Y628196D01*
X600071D01*
G01X599112D02*
X598537Y626698D01*
G01X596281D02*
X596204Y627370D01*
X596089Y627938D01*
X595936Y628455D01*
X595744Y629023D01*
X595437Y629798D01*
X596971D01*
G01X592644Y626698D02*
Y629798D01*
X594062Y627576D01*
X592146D01*
G01X590656Y627060D02*
X590387Y626801D01*
X590081Y626698D01*
X589774Y626801D01*
X589506Y627111D01*
X589314Y627576D01*
X589237Y628041D01*
Y628610D01*
X589314Y629075D01*
X589506Y629488D01*
X589736Y629695D01*
X590004Y629798D01*
X590311Y629695D01*
X590541Y629488D01*
X590694Y629178D01*
X590771Y628765D01*
X590694Y628403D01*
X590502Y628041D01*
X590272Y627835D01*
X590004Y627783D01*
X589697Y627886D01*
X589467Y628145D01*
X589237Y628610D01*
G01X600071Y622698D02*
Y625798D01*
X599112D01*
X598806Y625643D01*
X598614Y625436D01*
X598537Y625023D01*
X598614Y624610D01*
X598844Y624351D01*
X599112Y624196D01*
X600071D01*
G01X599112D02*
X598537Y622698D01*
G01X596281D02*
X596204Y623370D01*
X596089Y623938D01*
X595936Y624455D01*
X595744Y625023D01*
X595437Y625798D01*
X596971D01*
G01X593947Y623163D02*
X593717Y622905D01*
X593449Y622750D01*
X593104Y622698D01*
X592759Y622801D01*
X592491Y623008D01*
X592299Y623370D01*
X592261Y623783D01*
X592337Y624196D01*
X592529Y624455D01*
X592797Y624661D01*
X593066Y624713D01*
X593334Y624661D01*
X593679Y624455D01*
X593564Y625798D01*
X592529D01*
G01X590004D02*
X590311Y625695D01*
X590541Y625436D01*
X590694Y625126D01*
X590809Y624713D01*
X590847Y624248D01*
X590809Y623783D01*
X590694Y623370D01*
X590541Y623060D01*
X590311Y622801D01*
X590004Y622698D01*
X589697Y622801D01*
X589467Y623060D01*
X589314Y623370D01*
X589199Y623783D01*
X589161Y624248D01*
X589199Y624713D01*
X589314Y625126D01*
X589467Y625436D01*
X589697Y625695D01*
X590004Y625798D01*
G01X600071Y630698D02*
Y633798D01*
X599112D01*
X598806Y633643D01*
X598614Y633436D01*
X598537Y633023D01*
X598614Y632610D01*
X598844Y632351D01*
X599112Y632196D01*
X600071D01*
G01X599112D02*
X598537Y630698D01*
G01X596281D02*
X596204Y631370D01*
X596089Y631938D01*
X595936Y632455D01*
X595744Y633023D01*
X595437Y633798D01*
X596971D01*
G01X592644Y630698D02*
Y633798D01*
X594062Y631576D01*
X592146D01*
G01X590004Y630698D02*
X589736Y630750D01*
X589429Y630905D01*
X589237Y631163D01*
X589161Y631525D01*
X589237Y631886D01*
X589467Y632196D01*
X589812Y632351D01*
X590196D01*
X590426Y632455D01*
X590617Y632713D01*
X590694Y633075D01*
X590579Y633436D01*
X590311Y633695D01*
X590004Y633798D01*
X589697Y633695D01*
X589429Y633436D01*
X589314Y633075D01*
X589391Y632713D01*
X589582Y632455D01*
X589812Y632351D01*
X590196D01*
X590541Y632196D01*
X590771Y631886D01*
X590847Y631525D01*
X590771Y631163D01*
X590579Y630905D01*
X590272Y630750D01*
X590004Y630698D01*
G01X591020Y660825D02*
X591250Y660980D01*
X591518Y661083D01*
X591825D01*
X592170Y660928D01*
X592438Y660670D01*
X592630Y660360D01*
X592783Y659843D01*
X592821Y659378D01*
X592745Y658913D01*
X592630Y658603D01*
X592400Y658293D01*
X592131Y658086D01*
X591863Y657983D01*
X591595D01*
X591326Y658086D01*
X591096Y658241D01*
X590905Y658448D01*
G01X589606D02*
X589376Y658190D01*
X589108Y658035D01*
X588763Y657983D01*
X588418Y658086D01*
X588150Y658293D01*
X587958Y658655D01*
X587920Y659068D01*
X587996Y659481D01*
X588188Y659740D01*
X588456Y659946D01*
X588725Y659998D01*
X588993Y659946D01*
X589338Y659740D01*
X589223Y661083D01*
X588188D01*
G01X585740Y657983D02*
X585663Y658655D01*
X585548Y659223D01*
X585395Y659740D01*
X585203Y660308D01*
X584896Y661083D01*
X586430D01*
G01X583291Y660566D02*
X583061Y660876D01*
X582793Y661031D01*
X582486Y661083D01*
X582103Y660980D01*
X581835Y660721D01*
X581758Y660411D01*
X581796Y660101D01*
X581950Y659843D01*
X582716Y659326D01*
X583061Y658965D01*
X583291Y658448D01*
X583368Y657983D01*
X581758D01*
G01X575040Y667556D02*
X580640D01*
G01X575040Y698756D02*
Y667556D01*
G01X585240D02*
X590840D01*
G01X582940Y669856D02*
X585240Y667556D01*
G01X580640D02*
X582940Y669856D01*
G01X577940Y669656D02*
G02I-1000J0D01*
G01X585895Y662228D02*
X592095D01*
G01X585895Y665428D02*
Y662228D01*
G01X592095Y665428D02*
X585895D01*
G01X588995Y662328D02*
Y665328D01*
G01X590840Y698756D02*
X575040D01*
G01X585251Y706976D02*
X582051D01*
G01X585251Y700776D02*
Y706976D01*
G01X582051Y700776D02*
X585251D01*
G01X582051Y706976D02*
Y700776D01*
G01X589751Y706976D02*
X586551D01*
G01Y700776D02*
X589751D01*
G01X586551Y706976D02*
Y700776D01*
G01X580751Y706976D02*
X577551D01*
G01X580751Y700776D02*
Y706976D01*
G01X577551Y700776D02*
X580751D01*
G01X577551Y706976D02*
Y700776D01*
G01X576520Y709526D02*
X579620D01*
Y710485D01*
X579465Y710791D01*
X579258Y710983D01*
X578845Y711060D01*
X578432Y710983D01*
X578173Y710753D01*
X578018Y710485D01*
Y709526D01*
G01Y710485D02*
X576520Y711060D01*
G01Y713316D02*
X577192Y713393D01*
X577760Y713508D01*
X578277Y713661D01*
X578845Y713853D01*
X579620Y714160D01*
Y712626D01*
G01X576520Y716953D02*
X579620D01*
X577398Y715535D01*
Y717451D01*
G01X576520Y720053D02*
X579620D01*
X577398Y718635D01*
Y720551D01*
G01X575040Y737056D02*
Y743256D01*
G01X576440Y728156D02*
X579440D01*
G01X576340Y725056D02*
X579540D01*
G01X576340Y731256D02*
Y725056D01*
G01X579540Y731256D02*
X576340D01*
G01X579540Y725056D02*
Y731256D01*
G01X586340Y736556D02*
X589540D01*
G01X586340Y742756D02*
Y736556D01*
G01X589540Y731256D02*
X586340D01*
G01Y725056D02*
X589540D01*
G01X586340Y731256D02*
Y725056D01*
G01X575040D02*
Y731256D01*
G01X579540Y737056D02*
Y743256D01*
G01X576340Y737056D02*
X579540D01*
G01X576340Y743256D02*
Y737056D01*
G01X581347Y747305D02*
X581502Y747075D01*
X581605Y746807D01*
Y746500D01*
X581450Y746155D01*
X581192Y745887D01*
X580882Y745695D01*
X580365Y745542D01*
X579900Y745504D01*
X579435Y745580D01*
X579125Y745695D01*
X578815Y745925D01*
X578608Y746194D01*
X578505Y746462D01*
Y746730D01*
X578608Y746999D01*
X578763Y747229D01*
X578970Y747420D01*
G01X578505Y749485D02*
X579177Y749562D01*
X579745Y749677D01*
X580262Y749830D01*
X580830Y750022D01*
X581605Y750329D01*
Y748795D01*
G01X581088Y751934D02*
X581398Y752164D01*
X581553Y752432D01*
X581605Y752739D01*
X581502Y753122D01*
X581243Y753390D01*
X580933Y753467D01*
X580623Y753429D01*
X580365Y753275D01*
X579848Y752509D01*
X579487Y752164D01*
X578970Y751934D01*
X578505Y751857D01*
Y753467D01*
G01X581605Y755762D02*
X581502Y755455D01*
X581243Y755225D01*
X580933Y755072D01*
X580520Y754957D01*
X580055Y754919D01*
X579590Y754957D01*
X579177Y755072D01*
X578867Y755225D01*
X578608Y755455D01*
X578505Y755762D01*
X578608Y756069D01*
X578867Y756299D01*
X579177Y756452D01*
X579590Y756567D01*
X580055Y756605D01*
X580520Y756567D01*
X580933Y756452D01*
X581243Y756299D01*
X581502Y756069D01*
X581605Y755762D01*
G01X586440Y739656D02*
X589440D01*
G01X589540Y742756D02*
X586340D01*
G01X582690Y745695D02*
X585790D01*
Y746654D01*
X585635Y746960D01*
X585428Y747152D01*
X585015Y747229D01*
X584602Y747152D01*
X584343Y746922D01*
X584188Y746654D01*
Y745695D01*
G01Y746654D02*
X582690Y747229D01*
G01Y749562D02*
X582742Y749830D01*
X582897Y750137D01*
X583155Y750329D01*
X583517Y750405D01*
X583878Y750329D01*
X584188Y750099D01*
X584343Y749754D01*
Y749370D01*
X584447Y749140D01*
X584705Y748949D01*
X585067Y748872D01*
X585428Y748987D01*
X585687Y749255D01*
X585790Y749562D01*
X585687Y749869D01*
X585428Y750137D01*
X585067Y750252D01*
X584705Y750175D01*
X584447Y749984D01*
X584343Y749754D01*
Y749370D01*
X584188Y749025D01*
X583878Y748795D01*
X583517Y748719D01*
X583155Y748795D01*
X582897Y748987D01*
X582742Y749294D01*
X582690Y749562D01*
G01X583052Y752010D02*
X582793Y752279D01*
X582690Y752585D01*
X582793Y752892D01*
X583103Y753160D01*
X583568Y753352D01*
X584033Y753429D01*
X584602D01*
X585067Y753352D01*
X585480Y753160D01*
X585687Y752930D01*
X585790Y752662D01*
X585687Y752355D01*
X585480Y752125D01*
X585170Y751972D01*
X584757Y751895D01*
X584395Y751972D01*
X584033Y752164D01*
X583827Y752394D01*
X583775Y752662D01*
X583878Y752969D01*
X584137Y753199D01*
X584602Y753429D01*
G01X582690Y756222D02*
X585790D01*
X583568Y754804D01*
Y756720D01*
G01X579540Y743256D02*
X576340D01*
G01X589342Y759623D02*
X589497Y759393D01*
X589600Y759125D01*
Y758818D01*
X589445Y758473D01*
X589187Y758205D01*
X588877Y758013D01*
X588360Y757860D01*
X587895Y757822D01*
X587430Y757898D01*
X587120Y758013D01*
X586810Y758243D01*
X586603Y758512D01*
X586500Y758780D01*
Y759048D01*
X586603Y759317D01*
X586758Y759547D01*
X586965Y759738D01*
G01X587792Y761152D02*
X588153Y761420D01*
X588360Y761650D01*
X588463Y761957D01*
X588360Y762225D01*
X588153Y762417D01*
X587843Y762570D01*
X587482Y762608D01*
X587172Y762570D01*
X586862Y762417D01*
X586603Y762187D01*
X586500Y761918D01*
X586603Y761612D01*
X586913Y761343D01*
X587378Y761190D01*
X587895Y761152D01*
X588567Y761228D01*
X588928Y761343D01*
X589290Y761535D01*
X589548Y761803D01*
X589600Y762072D01*
X589497Y762340D01*
X589238Y762532D01*
G01X586965Y764137D02*
X586707Y764367D01*
X586552Y764635D01*
X586500Y764980D01*
X586603Y765325D01*
X586810Y765593D01*
X587172Y765785D01*
X587585Y765823D01*
X587998Y765747D01*
X588257Y765555D01*
X588463Y765287D01*
X588515Y765018D01*
X588463Y764750D01*
X588257Y764405D01*
X589600Y764520D01*
Y765555D01*
G01X586500Y768540D02*
X589600D01*
X587378Y767122D01*
Y769038D01*
G01X585072Y759623D02*
X585227Y759393D01*
X585330Y759125D01*
Y758818D01*
X585175Y758473D01*
X584917Y758205D01*
X584607Y758013D01*
X584090Y757860D01*
X583625Y757822D01*
X583160Y757898D01*
X582850Y758013D01*
X582540Y758243D01*
X582333Y758512D01*
X582230Y758780D01*
Y759048D01*
X582333Y759317D01*
X582488Y759547D01*
X582695Y759738D01*
G01X583522Y761152D02*
X583883Y761420D01*
X584090Y761650D01*
X584193Y761957D01*
X584090Y762225D01*
X583883Y762417D01*
X583573Y762570D01*
X583212Y762608D01*
X582902Y762570D01*
X582592Y762417D01*
X582333Y762187D01*
X582230Y761918D01*
X582333Y761612D01*
X582643Y761343D01*
X583108Y761190D01*
X583625Y761152D01*
X584297Y761228D01*
X584658Y761343D01*
X585020Y761535D01*
X585278Y761803D01*
X585330Y762072D01*
X585227Y762340D01*
X584968Y762532D01*
G01X582695Y764137D02*
X582437Y764367D01*
X582282Y764635D01*
X582230Y764980D01*
X582333Y765325D01*
X582540Y765593D01*
X582902Y765785D01*
X583315Y765823D01*
X583728Y765747D01*
X583987Y765555D01*
X584193Y765287D01*
X584245Y765018D01*
X584193Y764750D01*
X583987Y764405D01*
X585330Y764520D01*
Y765555D01*
G01X582230Y768003D02*
X582902Y768080D01*
X583470Y768195D01*
X583987Y768348D01*
X584555Y768540D01*
X585330Y768847D01*
Y767313D01*
G01X578105Y758013D02*
X581205D01*
Y758972D01*
X581050Y759278D01*
X580843Y759470D01*
X580430Y759547D01*
X580017Y759470D01*
X579758Y759240D01*
X579603Y758972D01*
Y758013D01*
G01Y758972D02*
X578105Y759547D01*
G01X578467Y761228D02*
X578208Y761497D01*
X578105Y761803D01*
X578208Y762110D01*
X578518Y762378D01*
X578983Y762570D01*
X579448Y762647D01*
X580017D01*
X580482Y762570D01*
X580895Y762378D01*
X581102Y762148D01*
X581205Y761880D01*
X581102Y761573D01*
X580895Y761343D01*
X580585Y761190D01*
X580172Y761113D01*
X579810Y761190D01*
X579448Y761382D01*
X579242Y761612D01*
X579190Y761880D01*
X579293Y762187D01*
X579552Y762417D01*
X580017Y762647D01*
G01X578570Y764137D02*
X578312Y764367D01*
X578157Y764635D01*
X578105Y764980D01*
X578208Y765325D01*
X578415Y765593D01*
X578777Y765785D01*
X579190Y765823D01*
X579603Y765747D01*
X579862Y765555D01*
X580068Y765287D01*
X580120Y765018D01*
X580068Y764750D01*
X579862Y764405D01*
X581205Y764520D01*
Y765555D01*
G01X578105Y768003D02*
X578777Y768080D01*
X579345Y768195D01*
X579862Y768348D01*
X580430Y768540D01*
X581205Y768847D01*
Y767313D01*
G01X591087Y61980D02*
Y65080D01*
X592505Y62858D01*
X590589D01*
G01X596886Y95299D02*
Y98399D01*
X597346Y97779D01*
G01Y95299D02*
X596426D01*
G01X599269Y173681D02*
Y176781D01*
X599729Y176161D01*
G01Y173681D02*
X598809D01*
G01X591600Y197983D02*
X594700D01*
Y198942D01*
X594545Y199248D01*
X594338Y199440D01*
X593925Y199517D01*
X593512Y199440D01*
X593253Y199210D01*
X593098Y198942D01*
Y197983D01*
G01Y198942D02*
X591600Y199517D01*
G01Y201850D02*
X594700D01*
X594080Y201390D01*
G01X591600D02*
Y202310D01*
G01X594183Y204222D02*
X594493Y204452D01*
X594648Y204720D01*
X594700Y205027D01*
X594597Y205410D01*
X594338Y205678D01*
X594028Y205755D01*
X593718Y205717D01*
X593460Y205563D01*
X592943Y204797D01*
X592582Y204452D01*
X592065Y204222D01*
X591600Y204145D01*
Y205755D01*
G01X592892Y207322D02*
X593253Y207590D01*
X593460Y207820D01*
X593563Y208127D01*
X593460Y208395D01*
X593253Y208587D01*
X592943Y208740D01*
X592582Y208778D01*
X592272Y208740D01*
X591962Y208587D01*
X591703Y208357D01*
X591600Y208088D01*
X591703Y207782D01*
X592013Y207513D01*
X592478Y207360D01*
X592995Y207322D01*
X593667Y207398D01*
X594028Y207513D01*
X594390Y207705D01*
X594648Y207973D01*
X594700Y208242D01*
X594597Y208510D01*
X594338Y208702D01*
G01X591600Y211610D02*
X594700D01*
X592478Y210192D01*
Y212108D01*
G01X600957Y204021D02*
X600880Y204693D01*
X600765Y205261D01*
X600612Y205778D01*
X600420Y206346D01*
X600113Y207121D01*
X601647D01*
G01X598341Y241293D02*
Y247493D01*
G01D02*
X595141D01*
G01D02*
Y241293D01*
G01D02*
X598341D01*
G01X595241Y244393D02*
X598241D01*
G01X606341Y247493D02*
X603141D01*
G01D02*
Y241293D01*
G01D02*
X606341D01*
G01X603241Y244393D02*
X606241D01*
G01X599141Y247493D02*
Y241293D01*
G01D02*
X602341D01*
G01Y247493D02*
X599141D01*
G01X602241Y244393D02*
X599241D01*
G01X602341Y241293D02*
Y247493D01*
G01X591674Y239295D02*
Y242495D01*
G01X598341Y252693D02*
Y258893D01*
G01D02*
X595141D01*
G01D02*
Y252693D01*
G01D02*
X598341D01*
G01X595241Y255793D02*
X598241D01*
G01Y261593D02*
Y267793D01*
G01X595041D02*
Y261593D01*
G01D02*
X598241D01*
G01X598141Y264693D02*
X595141D01*
G01X606341Y258893D02*
X603141D01*
G01D02*
Y252693D01*
G01D02*
X606341D01*
G01X603241Y255793D02*
X606241D01*
G01X599141Y258893D02*
Y252693D01*
G01D02*
X602341D01*
G01Y258893D02*
X599141D01*
G01X602241Y255793D02*
X599241D01*
G01X602341Y252693D02*
Y258893D01*
G01X603041Y267793D02*
Y261593D01*
G01D02*
X606241D01*
G01X606141Y264693D02*
X603141D01*
G01X599041Y267793D02*
Y261593D01*
G01D02*
X602241D01*
G01X599141Y264693D02*
X602141D01*
G01X602241Y261593D02*
Y267793D01*
G01X598241D02*
X595041D01*
G01X606241D02*
X603041D01*
G01X602241D02*
X599041D01*
G01X598988Y299101D02*
Y296001D01*
X597454D01*
G01X595964Y296621D02*
X595734Y296259D01*
X595428Y296053D01*
X595083Y296001D01*
X594776Y296053D01*
X594469Y296311D01*
X594278Y296621D01*
X594239Y296931D01*
X594316Y297293D01*
X594584Y297551D01*
X594853Y297654D01*
X595198D01*
G01X594853D02*
X594623Y297809D01*
X594431Y298068D01*
X594354Y298378D01*
X594431Y298688D01*
X594623Y298946D01*
X594968Y299101D01*
X595313Y299049D01*
X595658Y298843D01*
G01X592021Y296001D02*
Y299101D01*
X592481Y298481D01*
G01Y296001D02*
X591561D01*
G01X601803Y615903D02*
X602033Y616058D01*
X602301Y616161D01*
X602608D01*
X602953Y616006D01*
X603221Y615748D01*
X603413Y615438D01*
X603566Y614921D01*
X603604Y614456D01*
X603528Y613991D01*
X603413Y613681D01*
X603183Y613371D01*
X602914Y613164D01*
X602646Y613061D01*
X602378D01*
X602109Y613164D01*
X601879Y613319D01*
X601688Y613526D01*
G01X599086Y613061D02*
Y616161D01*
X600504Y613939D01*
X598588D01*
G01X597174Y614353D02*
X596906Y614714D01*
X596676Y614921D01*
X596369Y615024D01*
X596101Y614921D01*
X595909Y614714D01*
X595756Y614404D01*
X595718Y614043D01*
X595756Y613733D01*
X595909Y613423D01*
X596139Y613164D01*
X596408Y613061D01*
X596714Y613164D01*
X596983Y613474D01*
X597136Y613939D01*
X597174Y614456D01*
X597098Y615128D01*
X596983Y615489D01*
X596791Y615851D01*
X596523Y616109D01*
X596254Y616161D01*
X595986Y616058D01*
X595794Y615799D01*
G01X593998Y613423D02*
X593729Y613164D01*
X593423Y613061D01*
X593116Y613164D01*
X592848Y613474D01*
X592656Y613939D01*
X592579Y614404D01*
Y614973D01*
X592656Y615438D01*
X592848Y615851D01*
X593078Y616058D01*
X593346Y616161D01*
X593653Y616058D01*
X593883Y615851D01*
X594036Y615541D01*
X594113Y615128D01*
X594036Y614766D01*
X593844Y614404D01*
X593614Y614198D01*
X593346Y614146D01*
X593039Y614249D01*
X592809Y614508D01*
X592579Y614973D01*
G01X601869Y612115D02*
X602099Y612270D01*
X602367Y612373D01*
X602674D01*
X603019Y612218D01*
X603287Y611960D01*
X603479Y611650D01*
X603632Y611133D01*
X603670Y610668D01*
X603594Y610203D01*
X603479Y609893D01*
X603249Y609583D01*
X602980Y609376D01*
X602712Y609273D01*
X602444D01*
X602175Y609376D01*
X601945Y609531D01*
X601754Y609738D01*
G01X599152Y609273D02*
Y612373D01*
X600570Y610151D01*
X598654D01*
G01X596589Y609273D02*
X596512Y609945D01*
X596397Y610513D01*
X596244Y611030D01*
X596052Y611598D01*
X595745Y612373D01*
X597279D01*
G01X593412D02*
X593719Y612270D01*
X593949Y612011D01*
X594102Y611701D01*
X594217Y611288D01*
X594255Y610823D01*
X594217Y610358D01*
X594102Y609945D01*
X593949Y609635D01*
X593719Y609376D01*
X593412Y609273D01*
X593105Y609376D01*
X592875Y609635D01*
X592722Y609945D01*
X592607Y610358D01*
X592569Y610823D01*
X592607Y611288D01*
X592722Y611701D01*
X592875Y612011D01*
X593105Y612270D01*
X593412Y612373D01*
G01X601688Y619768D02*
X601918Y619923D01*
X602186Y620026D01*
X602493D01*
X602838Y619871D01*
X603106Y619613D01*
X603298Y619303D01*
X603451Y618786D01*
X603489Y618321D01*
X603413Y617856D01*
X603298Y617546D01*
X603068Y617236D01*
X602799Y617029D01*
X602531Y616926D01*
X602263D01*
X601994Y617029D01*
X601764Y617184D01*
X601573Y617391D01*
G01X598971Y616926D02*
Y620026D01*
X600389Y617804D01*
X598473D01*
G01X597059Y618218D02*
X596791Y618579D01*
X596561Y618786D01*
X596254Y618889D01*
X595986Y618786D01*
X595794Y618579D01*
X595641Y618269D01*
X595603Y617908D01*
X595641Y617598D01*
X595794Y617288D01*
X596024Y617029D01*
X596293Y616926D01*
X596599Y617029D01*
X596868Y617339D01*
X597021Y617804D01*
X597059Y618321D01*
X596983Y618993D01*
X596868Y619354D01*
X596676Y619716D01*
X596408Y619974D01*
X596139Y620026D01*
X595871Y619923D01*
X595679Y619664D01*
G01X593959Y618218D02*
X593691Y618579D01*
X593461Y618786D01*
X593154Y618889D01*
X592886Y618786D01*
X592694Y618579D01*
X592541Y618269D01*
X592503Y617908D01*
X592541Y617598D01*
X592694Y617288D01*
X592924Y617029D01*
X593193Y616926D01*
X593499Y617029D01*
X593768Y617339D01*
X593921Y617804D01*
X593959Y618321D01*
X593883Y618993D01*
X593768Y619354D01*
X593576Y619716D01*
X593308Y619974D01*
X593039Y620026D01*
X592771Y619923D01*
X592579Y619664D01*
G01X600948Y644642D02*
Y647742D01*
X599989D01*
X599683Y647587D01*
X599491Y647380D01*
X599414Y646967D01*
X599491Y646554D01*
X599721Y646295D01*
X599989Y646140D01*
X600948D01*
G01X599989D02*
X599414Y644642D01*
G01X597158D02*
X597081Y645314D01*
X596966Y645882D01*
X596813Y646399D01*
X596621Y646967D01*
X596314Y647742D01*
X597848D01*
G01X593521Y644642D02*
Y647742D01*
X594939Y645520D01*
X593023D01*
G01X591724Y645107D02*
X591494Y644849D01*
X591226Y644694D01*
X590881Y644642D01*
X590536Y644745D01*
X590268Y644952D01*
X590076Y645314D01*
X590038Y645727D01*
X590114Y646140D01*
X590306Y646399D01*
X590574Y646605D01*
X590843Y646657D01*
X591111Y646605D01*
X591456Y646399D01*
X591341Y647742D01*
X590306D01*
G01X600948Y636642D02*
Y639742D01*
X599989D01*
X599683Y639587D01*
X599491Y639380D01*
X599414Y638967D01*
X599491Y638554D01*
X599721Y638295D01*
X599989Y638140D01*
X600948D01*
G01X599989D02*
X599414Y636642D01*
G01X597158D02*
X597081Y637314D01*
X596966Y637882D01*
X596813Y638399D01*
X596621Y638967D01*
X596314Y639742D01*
X597848D01*
G01X593521Y636642D02*
Y639742D01*
X594939Y637520D01*
X593023D01*
G01X590958Y636642D02*
X590881Y637314D01*
X590766Y637882D01*
X590613Y638399D01*
X590421Y638967D01*
X590114Y639742D01*
X591648D01*
G01X600948Y640642D02*
Y643742D01*
X599989D01*
X599683Y643587D01*
X599491Y643380D01*
X599414Y642967D01*
X599491Y642554D01*
X599721Y642295D01*
X599989Y642140D01*
X600948D01*
G01X599989D02*
X599414Y640642D01*
G01X597158D02*
X597081Y641314D01*
X596966Y641882D01*
X596813Y642399D01*
X596621Y642967D01*
X596314Y643742D01*
X597848D01*
G01X593521Y640642D02*
Y643742D01*
X594939Y641520D01*
X593023D01*
G01X591609Y641934D02*
X591341Y642295D01*
X591111Y642502D01*
X590804Y642605D01*
X590536Y642502D01*
X590344Y642295D01*
X590191Y641985D01*
X590153Y641624D01*
X590191Y641314D01*
X590344Y641004D01*
X590574Y640745D01*
X590843Y640642D01*
X591149Y640745D01*
X591418Y641055D01*
X591571Y641520D01*
X591609Y642037D01*
X591533Y642709D01*
X591418Y643070D01*
X591226Y643432D01*
X590958Y643690D01*
X590689Y643742D01*
X590421Y643639D01*
X590229Y643380D01*
G01X608087Y697638D02*
X598872D01*
Y666477D01*
X604012D01*
Y671868D01*
X612350D01*
Y679829D01*
G01X590840Y667556D02*
Y698756D01*
G01X592095Y662228D02*
Y665428D01*
G01X603440Y673556D02*
X609640D01*
G01X603440Y676756D02*
Y673556D01*
G01Y677556D02*
X609640D01*
G01X603440Y680756D02*
Y677556D01*
G01X609640Y680756D02*
X603440D01*
G01Y681556D02*
X609640D01*
G01X603440Y684756D02*
Y681556D01*
G01X609640Y684756D02*
X603440D01*
G01Y685556D02*
X609640D01*
G01X603440Y688756D02*
Y685556D01*
G01X609640Y688756D02*
X603440D01*
G01Y689556D02*
X609640D01*
G01X603440Y692756D02*
Y689556D01*
G01X609640Y676756D02*
X603440D01*
G01X591008Y705757D02*
X594108D01*
Y706716D01*
X593953Y707022D01*
X593746Y707214D01*
X593333Y707291D01*
X592920Y707214D01*
X592661Y706984D01*
X592506Y706716D01*
Y705757D01*
G01Y706716D02*
X591008Y707291D01*
G01Y709547D02*
X591680Y709624D01*
X592248Y709739D01*
X592765Y709892D01*
X593333Y710084D01*
X594108Y710391D01*
Y708857D01*
G01X591008Y713184D02*
X594108D01*
X591886Y711766D01*
Y713682D01*
G01X593591Y715096D02*
X593901Y715326D01*
X594056Y715594D01*
X594108Y715901D01*
X594005Y716284D01*
X593746Y716552D01*
X593436Y716629D01*
X593126Y716591D01*
X592868Y716437D01*
X592351Y715671D01*
X591990Y715326D01*
X591473Y715096D01*
X591008Y715019D01*
Y716629D01*
G01X595521Y702999D02*
X598621D01*
Y703958D01*
X598466Y704264D01*
X598259Y704456D01*
X597846Y704533D01*
X597433Y704456D01*
X597174Y704226D01*
X597019Y703958D01*
Y702999D01*
G01Y703958D02*
X595521Y704533D01*
G01Y706789D02*
X596193Y706866D01*
X596761Y706981D01*
X597278Y707134D01*
X597846Y707326D01*
X598621Y707633D01*
Y706099D01*
G01X595521Y710426D02*
X598621D01*
X596399Y709008D01*
Y710924D01*
G01X595521Y713066D02*
X598621D01*
X598001Y712606D01*
G01X595521D02*
Y713526D01*
G01X589751Y700776D02*
Y706976D01*
G01X603440Y693556D02*
X609640D01*
G01X603440Y696756D02*
Y693556D01*
G01X609640Y696756D02*
X603440D01*
G01X609640Y692756D02*
X603440D01*
G01X599840Y736556D02*
X603040D01*
G01X599840Y742756D02*
Y736556D01*
G01X603040D02*
Y742756D01*
G01X604340Y736556D02*
X607540D01*
G01X604340Y742756D02*
Y736556D01*
G01X595340D02*
X598540D01*
G01X595340Y742756D02*
Y736556D01*
G01X598540D02*
Y742756D01*
G01X590940Y728156D02*
X593940D01*
G01X590840Y725056D02*
X594040D01*
G01X590840Y731256D02*
Y725056D01*
G01X594040Y731256D02*
X590840D01*
G01X594040Y725056D02*
Y731256D01*
G01X589540Y736556D02*
Y742756D01*
G01X590840Y736556D02*
X594040D01*
G01X590840Y742756D02*
Y736556D01*
G01X594040D02*
Y742756D01*
G01X589540Y725056D02*
Y731256D01*
G01X598540D02*
X595340D01*
G01X598540Y725056D02*
Y731256D01*
G01X595340Y725056D02*
X598540D01*
G01X595340Y731256D02*
Y725056D01*
G01X603040Y731256D02*
X599840D01*
G01X603040Y725056D02*
Y731256D01*
G01X599840Y725056D02*
X603040D01*
G01X599840Y731256D02*
Y725056D01*
G01X607540Y731256D02*
X604340D01*
G01Y725056D02*
X607540D01*
G01X604340Y731256D02*
Y725056D01*
G01X599940Y739656D02*
X602940D01*
G01X603040Y742756D02*
X599840D01*
G01X604440Y739656D02*
X607440D01*
G01X607540Y742756D02*
X604340D01*
G01X595440Y739656D02*
X598440D01*
G01X598540Y742756D02*
X595340D01*
G01X594040D02*
X590840D01*
G01X599122Y745395D02*
X602222D01*
Y746354D01*
X602067Y746660D01*
X601860Y746852D01*
X601447Y746929D01*
X601034Y746852D01*
X600775Y746622D01*
X600620Y746354D01*
Y745395D01*
G01Y746354D02*
X599122Y746929D01*
G01Y749262D02*
X599174Y749530D01*
X599329Y749837D01*
X599587Y750029D01*
X599949Y750105D01*
X600310Y750029D01*
X600620Y749799D01*
X600775Y749454D01*
Y749070D01*
X600879Y748840D01*
X601137Y748649D01*
X601499Y748572D01*
X601860Y748687D01*
X602119Y748955D01*
X602222Y749262D01*
X602119Y749569D01*
X601860Y749837D01*
X601499Y749952D01*
X601137Y749875D01*
X600879Y749684D01*
X600775Y749454D01*
Y749070D01*
X600620Y748725D01*
X600310Y748495D01*
X599949Y748419D01*
X599587Y748495D01*
X599329Y748687D01*
X599174Y748994D01*
X599122Y749262D01*
G01Y752362D02*
X599174Y752630D01*
X599329Y752937D01*
X599587Y753129D01*
X599949Y753205D01*
X600310Y753129D01*
X600620Y752899D01*
X600775Y752554D01*
Y752170D01*
X600879Y751940D01*
X601137Y751749D01*
X601499Y751672D01*
X601860Y751787D01*
X602119Y752055D01*
X602222Y752362D01*
X602119Y752669D01*
X601860Y752937D01*
X601499Y753052D01*
X601137Y752975D01*
X600879Y752784D01*
X600775Y752554D01*
Y752170D01*
X600620Y751825D01*
X600310Y751595D01*
X599949Y751519D01*
X599587Y751595D01*
X599329Y751787D01*
X599174Y752094D01*
X599122Y752362D01*
G01X599587Y754619D02*
X599329Y754849D01*
X599174Y755117D01*
X599122Y755462D01*
X599225Y755807D01*
X599432Y756075D01*
X599794Y756267D01*
X600207Y756305D01*
X600620Y756229D01*
X600879Y756037D01*
X601085Y755769D01*
X601137Y755500D01*
X601085Y755232D01*
X600879Y754887D01*
X602222Y755002D01*
Y756037D01*
G01X590950Y745395D02*
X594050D01*
Y746354D01*
X593895Y746660D01*
X593688Y746852D01*
X593275Y746929D01*
X592862Y746852D01*
X592603Y746622D01*
X592448Y746354D01*
Y745395D01*
G01Y746354D02*
X590950Y746929D01*
G01Y749262D02*
X591002Y749530D01*
X591157Y749837D01*
X591415Y750029D01*
X591777Y750105D01*
X592138Y750029D01*
X592448Y749799D01*
X592603Y749454D01*
Y749070D01*
X592707Y748840D01*
X592965Y748649D01*
X593327Y748572D01*
X593688Y748687D01*
X593947Y748955D01*
X594050Y749262D01*
X593947Y749569D01*
X593688Y749837D01*
X593327Y749952D01*
X592965Y749875D01*
X592707Y749684D01*
X592603Y749454D01*
Y749070D01*
X592448Y748725D01*
X592138Y748495D01*
X591777Y748419D01*
X591415Y748495D01*
X591157Y748687D01*
X591002Y748994D01*
X590950Y749262D01*
G01X591312Y751710D02*
X591053Y751979D01*
X590950Y752285D01*
X591053Y752592D01*
X591363Y752860D01*
X591828Y753052D01*
X592293Y753129D01*
X592862D01*
X593327Y753052D01*
X593740Y752860D01*
X593947Y752630D01*
X594050Y752362D01*
X593947Y752055D01*
X593740Y751825D01*
X593430Y751672D01*
X593017Y751595D01*
X592655Y751672D01*
X592293Y751864D01*
X592087Y752094D01*
X592035Y752362D01*
X592138Y752669D01*
X592397Y752899D01*
X592862Y753129D01*
G01X590950Y755462D02*
X594050D01*
X593430Y755002D01*
G01X590950D02*
Y755922D01*
G01X595082Y745395D02*
X598182D01*
Y746354D01*
X598027Y746660D01*
X597820Y746852D01*
X597407Y746929D01*
X596994Y746852D01*
X596735Y746622D01*
X596580Y746354D01*
Y745395D01*
G01Y746354D02*
X595082Y746929D01*
G01Y749262D02*
X595134Y749530D01*
X595289Y749837D01*
X595547Y750029D01*
X595909Y750105D01*
X596270Y750029D01*
X596580Y749799D01*
X596735Y749454D01*
Y749070D01*
X596839Y748840D01*
X597097Y748649D01*
X597459Y748572D01*
X597820Y748687D01*
X598079Y748955D01*
X598182Y749262D01*
X598079Y749569D01*
X597820Y749837D01*
X597459Y749952D01*
X597097Y749875D01*
X596839Y749684D01*
X596735Y749454D01*
Y749070D01*
X596580Y748725D01*
X596270Y748495D01*
X595909Y748419D01*
X595547Y748495D01*
X595289Y748687D01*
X595134Y748994D01*
X595082Y749262D01*
G01Y752362D02*
X595134Y752630D01*
X595289Y752937D01*
X595547Y753129D01*
X595909Y753205D01*
X596270Y753129D01*
X596580Y752899D01*
X596735Y752554D01*
Y752170D01*
X596839Y751940D01*
X597097Y751749D01*
X597459Y751672D01*
X597820Y751787D01*
X598079Y752055D01*
X598182Y752362D01*
X598079Y752669D01*
X597820Y752937D01*
X597459Y753052D01*
X597097Y752975D01*
X596839Y752784D01*
X596735Y752554D01*
Y752170D01*
X596580Y751825D01*
X596270Y751595D01*
X595909Y751519D01*
X595547Y751595D01*
X595289Y751787D01*
X595134Y752094D01*
X595082Y752362D01*
G01Y755462D02*
X595134Y755730D01*
X595289Y756037D01*
X595547Y756229D01*
X595909Y756305D01*
X596270Y756229D01*
X596580Y755999D01*
X596735Y755654D01*
Y755270D01*
X596839Y755040D01*
X597097Y754849D01*
X597459Y754772D01*
X597820Y754887D01*
X598079Y755155D01*
X598182Y755462D01*
X598079Y755769D01*
X597820Y756037D01*
X597459Y756152D01*
X597097Y756075D01*
X596839Y755884D01*
X596735Y755654D01*
Y755270D01*
X596580Y754925D01*
X596270Y754695D01*
X595909Y754619D01*
X595547Y754695D01*
X595289Y754887D01*
X595134Y755194D01*
X595082Y755462D01*
G01X605685Y759623D02*
X605840Y759393D01*
X605943Y759125D01*
Y758818D01*
X605788Y758473D01*
X605530Y758205D01*
X605220Y758013D01*
X604703Y757860D01*
X604238Y757822D01*
X603773Y757898D01*
X603463Y758013D01*
X603153Y758243D01*
X602946Y758512D01*
X602843Y758780D01*
Y759048D01*
X602946Y759317D01*
X603101Y759547D01*
X603308Y759738D01*
G01Y761037D02*
X603050Y761267D01*
X602895Y761535D01*
X602843Y761880D01*
X602946Y762225D01*
X603153Y762493D01*
X603515Y762685D01*
X603928Y762723D01*
X604341Y762647D01*
X604600Y762455D01*
X604806Y762187D01*
X604858Y761918D01*
X604806Y761650D01*
X604600Y761305D01*
X605943Y761420D01*
Y762455D01*
G01X603205Y764328D02*
X602946Y764597D01*
X602843Y764903D01*
X602946Y765210D01*
X603256Y765478D01*
X603721Y765670D01*
X604186Y765747D01*
X604755D01*
X605220Y765670D01*
X605633Y765478D01*
X605840Y765248D01*
X605943Y764980D01*
X605840Y764673D01*
X605633Y764443D01*
X605323Y764290D01*
X604910Y764213D01*
X604548Y764290D01*
X604186Y764482D01*
X603980Y764712D01*
X603928Y764980D01*
X604031Y765287D01*
X604290Y765517D01*
X604755Y765747D01*
G01X602843Y768003D02*
X603515Y768080D01*
X604083Y768195D01*
X604600Y768348D01*
X605168Y768540D01*
X605943Y768847D01*
Y767313D01*
G01X601600Y759623D02*
X601755Y759393D01*
X601858Y759125D01*
Y758818D01*
X601703Y758473D01*
X601445Y758205D01*
X601135Y758013D01*
X600618Y757860D01*
X600153Y757822D01*
X599688Y757898D01*
X599378Y758013D01*
X599068Y758243D01*
X598861Y758512D01*
X598758Y758780D01*
Y759048D01*
X598861Y759317D01*
X599016Y759547D01*
X599223Y759738D01*
G01Y761037D02*
X598965Y761267D01*
X598810Y761535D01*
X598758Y761880D01*
X598861Y762225D01*
X599068Y762493D01*
X599430Y762685D01*
X599843Y762723D01*
X600256Y762647D01*
X600515Y762455D01*
X600721Y762187D01*
X600773Y761918D01*
X600721Y761650D01*
X600515Y761305D01*
X601858Y761420D01*
Y762455D01*
G01X599120Y764328D02*
X598861Y764597D01*
X598758Y764903D01*
X598861Y765210D01*
X599171Y765478D01*
X599636Y765670D01*
X600101Y765747D01*
X600670D01*
X601135Y765670D01*
X601548Y765478D01*
X601755Y765248D01*
X601858Y764980D01*
X601755Y764673D01*
X601548Y764443D01*
X601238Y764290D01*
X600825Y764213D01*
X600463Y764290D01*
X600101Y764482D01*
X599895Y764712D01*
X599843Y764980D01*
X599946Y765287D01*
X600205Y765517D01*
X600670Y765747D01*
G01X599223Y767237D02*
X598965Y767467D01*
X598810Y767735D01*
X598758Y768080D01*
X598861Y768425D01*
X599068Y768693D01*
X599430Y768885D01*
X599843Y768923D01*
X600256Y768847D01*
X600515Y768655D01*
X600721Y768387D01*
X600773Y768118D01*
X600721Y767850D01*
X600515Y767505D01*
X601858Y767620D01*
Y768655D01*
G01X597514Y759623D02*
X597669Y759393D01*
X597772Y759125D01*
Y758818D01*
X597617Y758473D01*
X597359Y758205D01*
X597049Y758013D01*
X596532Y757860D01*
X596067Y757822D01*
X595602Y757898D01*
X595292Y758013D01*
X594982Y758243D01*
X594775Y758512D01*
X594672Y758780D01*
Y759048D01*
X594775Y759317D01*
X594930Y759547D01*
X595137Y759738D01*
G01X595964Y761152D02*
X596325Y761420D01*
X596532Y761650D01*
X596635Y761957D01*
X596532Y762225D01*
X596325Y762417D01*
X596015Y762570D01*
X595654Y762608D01*
X595344Y762570D01*
X595034Y762417D01*
X594775Y762187D01*
X594672Y761918D01*
X594775Y761612D01*
X595085Y761343D01*
X595550Y761190D01*
X596067Y761152D01*
X596739Y761228D01*
X597100Y761343D01*
X597462Y761535D01*
X597720Y761803D01*
X597772Y762072D01*
X597669Y762340D01*
X597410Y762532D01*
G01X594672Y765440D02*
X597772D01*
X595550Y764022D01*
Y765938D01*
G01X594672Y768080D02*
X594724Y768348D01*
X594879Y768655D01*
X595137Y768847D01*
X595499Y768923D01*
X595860Y768847D01*
X596170Y768617D01*
X596325Y768272D01*
Y767888D01*
X596429Y767658D01*
X596687Y767467D01*
X597049Y767390D01*
X597410Y767505D01*
X597669Y767773D01*
X597772Y768080D01*
X597669Y768387D01*
X597410Y768655D01*
X597049Y768770D01*
X596687Y768693D01*
X596429Y768502D01*
X596325Y768272D01*
Y767888D01*
X596170Y767543D01*
X595860Y767313D01*
X595499Y767237D01*
X595137Y767313D01*
X594879Y767505D01*
X594724Y767812D01*
X594672Y768080D01*
G01X593474Y759623D02*
X593629Y759393D01*
X593732Y759125D01*
Y758818D01*
X593577Y758473D01*
X593319Y758205D01*
X593009Y758013D01*
X592492Y757860D01*
X592027Y757822D01*
X591562Y757898D01*
X591252Y758013D01*
X590942Y758243D01*
X590735Y758512D01*
X590632Y758780D01*
Y759048D01*
X590735Y759317D01*
X590890Y759547D01*
X591097Y759738D01*
G01X591924Y761152D02*
X592285Y761420D01*
X592492Y761650D01*
X592595Y761957D01*
X592492Y762225D01*
X592285Y762417D01*
X591975Y762570D01*
X591614Y762608D01*
X591304Y762570D01*
X590994Y762417D01*
X590735Y762187D01*
X590632Y761918D01*
X590735Y761612D01*
X591045Y761343D01*
X591510Y761190D01*
X592027Y761152D01*
X592699Y761228D01*
X593060Y761343D01*
X593422Y761535D01*
X593680Y761803D01*
X593732Y762072D01*
X593629Y762340D01*
X593370Y762532D01*
G01X591097Y764137D02*
X590839Y764367D01*
X590684Y764635D01*
X590632Y764980D01*
X590735Y765325D01*
X590942Y765593D01*
X591304Y765785D01*
X591717Y765823D01*
X592130Y765747D01*
X592389Y765555D01*
X592595Y765287D01*
X592647Y765018D01*
X592595Y764750D01*
X592389Y764405D01*
X593732Y764520D01*
Y765555D01*
G01X590632Y768080D02*
X593732D01*
X593112Y767620D01*
G01X590632D02*
Y768540D01*
G01X616149Y61584D02*
Y64684D01*
X617567Y62462D01*
X615651D01*
G01X617057Y96672D02*
Y99772D01*
X617517Y99152D01*
G01Y96672D02*
X616597D01*
G01X622454Y235245D02*
X622609Y235015D01*
X622712Y234747D01*
Y234440D01*
X622557Y234095D01*
X622299Y233827D01*
X621989Y233635D01*
X621472Y233482D01*
X621007Y233444D01*
X620542Y233520D01*
X620232Y233635D01*
X619922Y233865D01*
X619715Y234134D01*
X619612Y234402D01*
Y234670D01*
X619715Y234939D01*
X619870Y235169D01*
X620077Y235360D01*
G01X620232Y236659D02*
X619870Y236889D01*
X619664Y237195D01*
X619612Y237540D01*
X619664Y237847D01*
X619922Y238154D01*
X620232Y238345D01*
X620542Y238384D01*
X620904Y238307D01*
X621162Y238039D01*
X621265Y237770D01*
Y237425D01*
G01Y237770D02*
X621420Y238000D01*
X621679Y238192D01*
X621989Y238269D01*
X622299Y238192D01*
X622557Y238000D01*
X622712Y237655D01*
X622660Y237310D01*
X622454Y236965D01*
G01X620077Y239759D02*
X619819Y239989D01*
X619664Y240257D01*
X619612Y240602D01*
X619715Y240947D01*
X619922Y241215D01*
X620284Y241407D01*
X620697Y241445D01*
X621110Y241369D01*
X621369Y241177D01*
X621575Y240909D01*
X621627Y240640D01*
X621575Y240372D01*
X621369Y240027D01*
X622712Y240142D01*
Y241177D01*
G01X619612Y243702D02*
X619664Y243970D01*
X619819Y244277D01*
X620077Y244469D01*
X620439Y244545D01*
X620800Y244469D01*
X621110Y244239D01*
X621265Y243894D01*
Y243510D01*
X621369Y243280D01*
X621627Y243089D01*
X621989Y243012D01*
X622350Y243127D01*
X622609Y243395D01*
X622712Y243702D01*
X622609Y244009D01*
X622350Y244277D01*
X621989Y244392D01*
X621627Y244315D01*
X621369Y244124D01*
X621265Y243894D01*
Y243510D01*
X621110Y243165D01*
X620800Y242935D01*
X620439Y242859D01*
X620077Y242935D01*
X619819Y243127D01*
X619664Y243434D01*
X619612Y243702D01*
G01X621651Y249856D02*
X621806Y249626D01*
X621909Y249358D01*
Y249051D01*
X621754Y248706D01*
X621496Y248438D01*
X621186Y248246D01*
X620669Y248093D01*
X620204Y248055D01*
X619739Y248131D01*
X619429Y248246D01*
X619119Y248476D01*
X618912Y248745D01*
X618809Y249013D01*
Y249281D01*
X618912Y249550D01*
X619067Y249780D01*
X619274Y249971D01*
G01X619429Y251270D02*
X619067Y251500D01*
X618861Y251806D01*
X618809Y252151D01*
X618861Y252458D01*
X619119Y252765D01*
X619429Y252956D01*
X619739Y252995D01*
X620101Y252918D01*
X620359Y252650D01*
X620462Y252381D01*
Y252036D01*
G01Y252381D02*
X620617Y252611D01*
X620876Y252803D01*
X621186Y252880D01*
X621496Y252803D01*
X621754Y252611D01*
X621909Y252266D01*
X621857Y251921D01*
X621651Y251576D01*
G01X618809Y255673D02*
X621909D01*
X619687Y254255D01*
Y256171D01*
G01X620101Y257585D02*
X620462Y257853D01*
X620669Y258083D01*
X620772Y258390D01*
X620669Y258658D01*
X620462Y258850D01*
X620152Y259003D01*
X619791Y259041D01*
X619481Y259003D01*
X619171Y258850D01*
X618912Y258620D01*
X618809Y258351D01*
X618912Y258045D01*
X619222Y257776D01*
X619687Y257623D01*
X620204Y257585D01*
X620876Y257661D01*
X621237Y257776D01*
X621599Y257968D01*
X621857Y258236D01*
X621909Y258505D01*
X621806Y258773D01*
X621547Y258965D01*
G01X606341Y241293D02*
Y247493D01*
G01X610341Y241293D02*
Y247493D01*
G01D02*
X607141D01*
G01D02*
Y241293D01*
G01D02*
X610341D01*
G01X607241Y244393D02*
X610241D01*
G01X611241Y247493D02*
Y241293D01*
G01D02*
X614441D01*
G01D02*
Y247493D01*
G01D02*
X611241D01*
G01X614441Y244743D02*
X611241D01*
G01X614441Y244043D02*
X611241D01*
G01X618394Y266771D02*
X618549Y266541D01*
X618652Y266273D01*
Y265966D01*
X618497Y265621D01*
X618239Y265353D01*
X617929Y265161D01*
X617412Y265008D01*
X616947Y264970D01*
X616482Y265046D01*
X616172Y265161D01*
X615862Y265391D01*
X615655Y265660D01*
X615552Y265928D01*
Y266196D01*
X615655Y266465D01*
X615810Y266695D01*
X616017Y266886D01*
G01X616172Y268185D02*
X615810Y268415D01*
X615604Y268721D01*
X615552Y269066D01*
X615604Y269373D01*
X615862Y269680D01*
X616172Y269871D01*
X616482Y269910D01*
X616844Y269833D01*
X617102Y269565D01*
X617205Y269296D01*
Y268951D01*
G01Y269296D02*
X617360Y269526D01*
X617619Y269718D01*
X617929Y269795D01*
X618239Y269718D01*
X618497Y269526D01*
X618652Y269181D01*
X618600Y268836D01*
X618394Y268491D01*
G01X616844Y271400D02*
X617205Y271668D01*
X617412Y271898D01*
X617515Y272205D01*
X617412Y272473D01*
X617205Y272665D01*
X616895Y272818D01*
X616534Y272856D01*
X616224Y272818D01*
X615914Y272665D01*
X615655Y272435D01*
X615552Y272166D01*
X615655Y271860D01*
X615965Y271591D01*
X616430Y271438D01*
X616947Y271400D01*
X617619Y271476D01*
X617980Y271591D01*
X618342Y271783D01*
X618600Y272051D01*
X618652Y272320D01*
X618549Y272588D01*
X618290Y272780D01*
G01X618135Y274500D02*
X618445Y274730D01*
X618600Y274998D01*
X618652Y275305D01*
X618549Y275688D01*
X618290Y275956D01*
X617980Y276033D01*
X617670Y275995D01*
X617412Y275841D01*
X616895Y275075D01*
X616534Y274730D01*
X616017Y274500D01*
X615552Y274423D01*
Y276033D01*
G01X606341Y252693D02*
Y258893D01*
G01X610341Y252693D02*
Y258893D01*
G01D02*
X607141D01*
G01D02*
Y252693D01*
G01D02*
X610341D01*
G01X607241Y255793D02*
X610241D01*
G01X606241Y261593D02*
Y267793D01*
G01X607041D02*
Y261593D01*
G01D02*
X610241D01*
G01D02*
Y267793D01*
G01X610141Y264693D02*
X607141D01*
G01X622347Y266771D02*
X622502Y266541D01*
X622605Y266273D01*
Y265966D01*
X622450Y265621D01*
X622192Y265353D01*
X621882Y265161D01*
X621365Y265008D01*
X620900Y264970D01*
X620435Y265046D01*
X620125Y265161D01*
X619815Y265391D01*
X619608Y265660D01*
X619505Y265928D01*
Y266196D01*
X619608Y266465D01*
X619763Y266695D01*
X619970Y266886D01*
G01X620125Y268185D02*
X619763Y268415D01*
X619557Y268721D01*
X619505Y269066D01*
X619557Y269373D01*
X619815Y269680D01*
X620125Y269871D01*
X620435Y269910D01*
X620797Y269833D01*
X621055Y269565D01*
X621158Y269296D01*
Y268951D01*
G01Y269296D02*
X621313Y269526D01*
X621572Y269718D01*
X621882Y269795D01*
X622192Y269718D01*
X622450Y269526D01*
X622605Y269181D01*
X622553Y268836D01*
X622347Y268491D01*
G01X620797Y271400D02*
X621158Y271668D01*
X621365Y271898D01*
X621468Y272205D01*
X621365Y272473D01*
X621158Y272665D01*
X620848Y272818D01*
X620487Y272856D01*
X620177Y272818D01*
X619867Y272665D01*
X619608Y272435D01*
X619505Y272166D01*
X619608Y271860D01*
X619918Y271591D01*
X620383Y271438D01*
X620900Y271400D01*
X621572Y271476D01*
X621933Y271591D01*
X622295Y271783D01*
X622553Y272051D01*
X622605Y272320D01*
X622502Y272588D01*
X622243Y272780D01*
G01X619505Y275228D02*
X622605D01*
X621985Y274768D01*
G01X619505D02*
Y275688D01*
G01X614374Y261595D02*
Y267795D01*
G01X611174D02*
Y261595D01*
G01D02*
X614374D01*
G01X611174Y264345D02*
X614374D01*
G01X611174Y265045D02*
X614374D01*
G01X611241Y258893D02*
Y252693D01*
G01D02*
X614441D01*
G01D02*
Y258893D01*
G01D02*
X611241D01*
G01X614441Y256143D02*
X611241D01*
G01X614441Y255443D02*
X611241D01*
G01X610241Y267793D02*
X607041D01*
G01X614374Y267795D02*
X611174D01*
G01X619485Y577617D02*
X619715Y577772D01*
X619983Y577875D01*
X620290D01*
X620635Y577720D01*
X620903Y577462D01*
X621095Y577152D01*
X621248Y576635D01*
X621286Y576170D01*
X621210Y575705D01*
X621095Y575395D01*
X620865Y575085D01*
X620596Y574878D01*
X620328Y574775D01*
X620060D01*
X619791Y574878D01*
X619561Y575033D01*
X619370Y575240D01*
G01X616768Y574775D02*
Y577875D01*
X618186Y575653D01*
X616270D01*
G01X613668Y574775D02*
Y577875D01*
X615086Y575653D01*
X613170D01*
G01X611756Y577358D02*
X611526Y577668D01*
X611258Y577823D01*
X610951Y577875D01*
X610568Y577772D01*
X610300Y577513D01*
X610223Y577203D01*
X610261Y576893D01*
X610415Y576635D01*
X611181Y576118D01*
X611526Y575757D01*
X611756Y575240D01*
X611833Y574775D01*
X610223D01*
G01X619428Y573151D02*
X619658Y573306D01*
X619926Y573409D01*
X620233D01*
X620578Y573254D01*
X620846Y572996D01*
X621038Y572686D01*
X621191Y572169D01*
X621229Y571704D01*
X621153Y571239D01*
X621038Y570929D01*
X620808Y570619D01*
X620539Y570412D01*
X620271Y570309D01*
X620003D01*
X619734Y570412D01*
X619504Y570567D01*
X619313Y570774D01*
G01X616711Y570309D02*
Y573409D01*
X618129Y571187D01*
X616213D01*
G01X613611Y570309D02*
Y573409D01*
X615029Y571187D01*
X613113D01*
G01X610511Y570309D02*
Y573409D01*
X611929Y571187D01*
X610013D01*
G01X620537Y591245D02*
X614337D01*
G01D02*
Y588045D01*
G01X620537D02*
Y591245D01*
G01X617437Y588145D02*
Y591145D01*
G01X614337Y588045D02*
X620537D01*
G01X614370Y583943D02*
X620570D01*
G01Y587143D02*
X614370D01*
G01D02*
Y583943D01*
G01X620570D02*
Y587143D01*
G01X617470Y584043D02*
Y587043D01*
G01X614370Y599543D02*
Y596343D01*
G01D02*
X620570D01*
G01D02*
Y599543D01*
G01X617470Y596443D02*
Y599443D01*
G01X619714Y604559D02*
X619944Y604714D01*
X620212Y604817D01*
X620519D01*
X620864Y604662D01*
X621132Y604404D01*
X621324Y604094D01*
X621477Y603577D01*
X621515Y603112D01*
X621439Y602647D01*
X621324Y602337D01*
X621094Y602027D01*
X620825Y601820D01*
X620557Y601717D01*
X620289D01*
X620020Y601820D01*
X619790Y601975D01*
X619599Y602182D01*
G01X616997Y601717D02*
Y604817D01*
X618415Y602595D01*
X616499D01*
G01X615085Y603009D02*
X614817Y603370D01*
X614587Y603577D01*
X614280Y603680D01*
X614012Y603577D01*
X613820Y603370D01*
X613667Y603060D01*
X613629Y602699D01*
X613667Y602389D01*
X613820Y602079D01*
X614050Y601820D01*
X614319Y601717D01*
X614625Y601820D01*
X614894Y602130D01*
X615047Y602595D01*
X615085Y603112D01*
X615009Y603784D01*
X614894Y604145D01*
X614702Y604507D01*
X614434Y604765D01*
X614165Y604817D01*
X613897Y604714D01*
X613705Y604455D01*
G01X610797Y601717D02*
Y604817D01*
X612215Y602595D01*
X610299D01*
G01X620570Y599543D02*
X614370D01*
G01X614337Y615345D02*
Y612145D01*
G01D02*
X620537D01*
G01D02*
Y615345D01*
G01X617437Y612245D02*
Y615245D01*
G01X620537Y610445D02*
X614337D01*
G01D02*
Y607245D01*
G01D02*
X620537D01*
G01D02*
Y610445D01*
G01X617437Y607345D02*
Y610345D01*
G01X621816Y624403D02*
X621971Y624173D01*
X622074Y623905D01*
Y623598D01*
X621919Y623253D01*
X621661Y622985D01*
X621351Y622793D01*
X620834Y622640D01*
X620369Y622602D01*
X619904Y622678D01*
X619594Y622793D01*
X619284Y623023D01*
X619077Y623292D01*
X618974Y623560D01*
Y623828D01*
X619077Y624097D01*
X619232Y624327D01*
X619439Y624518D01*
G01X618974Y627120D02*
X622074D01*
X619852Y625702D01*
Y627618D01*
G01X620266Y629032D02*
X620627Y629300D01*
X620834Y629530D01*
X620937Y629837D01*
X620834Y630105D01*
X620627Y630297D01*
X620317Y630450D01*
X619956Y630488D01*
X619646Y630450D01*
X619336Y630297D01*
X619077Y630067D01*
X618974Y629798D01*
X619077Y629492D01*
X619387Y629223D01*
X619852Y629070D01*
X620369Y629032D01*
X621041Y629108D01*
X621402Y629223D01*
X621764Y629415D01*
X622022Y629683D01*
X622074Y629952D01*
X621971Y630220D01*
X621712Y630412D01*
G01X621557Y632132D02*
X621867Y632362D01*
X622022Y632630D01*
X622074Y632937D01*
X621971Y633320D01*
X621712Y633588D01*
X621402Y633665D01*
X621092Y633627D01*
X620834Y633473D01*
X620317Y632707D01*
X619956Y632362D01*
X619439Y632132D01*
X618974Y632055D01*
Y633665D01*
G01X614370Y616343D02*
X620570D01*
G01Y619543D02*
X614370D01*
G01D02*
Y616343D01*
G01X620570D02*
Y619543D01*
G01X617470Y616443D02*
Y619443D01*
G01X620537Y615345D02*
X614337D01*
G01X629182Y646945D02*
Y644723D01*
X629029Y644258D01*
X628722Y643948D01*
X628339Y643845D01*
X627956Y643948D01*
X627649Y644258D01*
X627496Y644723D01*
Y646945D01*
G01X625239Y643845D02*
Y646945D01*
X625699Y646325D01*
G01Y643845D02*
X624779D01*
G01X621679D02*
Y646945D01*
X623097Y644723D01*
X621181D01*
G01X619767Y646428D02*
X619537Y646738D01*
X619269Y646893D01*
X618962Y646945D01*
X618579Y646842D01*
X618311Y646583D01*
X618234Y646273D01*
X618272Y645963D01*
X618426Y645705D01*
X619192Y645188D01*
X619537Y644827D01*
X619767Y644310D01*
X619844Y643845D01*
X618234D01*
G01X609343Y654562D02*
X609498Y654332D01*
X609601Y654064D01*
Y653757D01*
X609446Y653412D01*
X609188Y653144D01*
X608878Y652952D01*
X608361Y652799D01*
X607896Y652761D01*
X607431Y652837D01*
X607121Y652952D01*
X606811Y653182D01*
X606604Y653451D01*
X606501Y653719D01*
Y653987D01*
X606604Y654256D01*
X606759Y654486D01*
X606966Y654677D01*
G01X606863Y656167D02*
X606604Y656436D01*
X606501Y656742D01*
X606604Y657049D01*
X606914Y657317D01*
X607379Y657509D01*
X607844Y657586D01*
X608413D01*
X608878Y657509D01*
X609291Y657317D01*
X609498Y657087D01*
X609601Y656819D01*
X609498Y656512D01*
X609291Y656282D01*
X608981Y656129D01*
X608568Y656052D01*
X608206Y656129D01*
X607844Y656321D01*
X607638Y656551D01*
X607586Y656819D01*
X607689Y657126D01*
X607948Y657356D01*
X608413Y657586D01*
G01X606501Y659919D02*
X609601D01*
X608981Y659459D01*
G01X606501D02*
Y660379D01*
G01X606966Y662176D02*
X606708Y662406D01*
X606553Y662674D01*
X606501Y663019D01*
X606604Y663364D01*
X606811Y663632D01*
X607173Y663824D01*
X607586Y663862D01*
X607999Y663786D01*
X608258Y663594D01*
X608464Y663326D01*
X608516Y663057D01*
X608464Y662789D01*
X608258Y662444D01*
X609601Y662559D01*
Y663594D01*
G01X615586Y655200D02*
X615794Y654987D01*
X615919Y654747D01*
Y654533D01*
X615794Y654320D01*
X615586Y654160D01*
X615294Y654080D01*
X615002Y654133D01*
X614752Y654267D01*
X614586Y654507D01*
X614502Y654827D01*
X614336Y655013D01*
X614044Y655093D01*
X613752Y655040D01*
X613544Y654907D01*
X613419Y654720D01*
Y654533D01*
X613502Y654347D01*
X613711Y654187D01*
G01X616702Y648870D02*
X629702D01*
G01X616702Y663870D02*
Y648870D01*
G01X607745Y665262D02*
X610945D01*
G01X607745Y671462D02*
Y665262D01*
G01X610945D02*
Y671462D01*
G01X610845Y668362D02*
X607845D01*
G01X610945Y671462D02*
X607745D01*
G01X609640Y673556D02*
Y676756D01*
G01X620004Y664976D02*
Y667476D01*
X619470D01*
X619257Y667351D01*
X619097Y667184D01*
X618964Y666934D01*
X618857Y666643D01*
X618830Y666226D01*
X618857Y665809D01*
X618964Y665518D01*
X619097Y665268D01*
X619257Y665101D01*
X619470Y664976D01*
X620004D01*
G01X629702Y663870D02*
X616702D01*
G01X612225Y684593D02*
Y686349D01*
G01X612099Y690800D02*
Y694310D01*
G01X622754Y682166D02*
X622909Y681936D01*
X623012Y681668D01*
Y681361D01*
X622857Y681016D01*
X622599Y680748D01*
X622289Y680556D01*
X621772Y680403D01*
X621307Y680365D01*
X620842Y680441D01*
X620532Y680556D01*
X620222Y680786D01*
X620015Y681055D01*
X619912Y681323D01*
Y681591D01*
X620015Y681860D01*
X620170Y682090D01*
X620377Y682281D01*
G01X620274Y683771D02*
X620015Y684040D01*
X619912Y684346D01*
X620015Y684653D01*
X620325Y684921D01*
X620790Y685113D01*
X621255Y685190D01*
X621824D01*
X622289Y685113D01*
X622702Y684921D01*
X622909Y684691D01*
X623012Y684423D01*
X622909Y684116D01*
X622702Y683886D01*
X622392Y683733D01*
X621979Y683656D01*
X621617Y683733D01*
X621255Y683925D01*
X621049Y684155D01*
X620997Y684423D01*
X621100Y684730D01*
X621359Y684960D01*
X621824Y685190D01*
G01X619912Y687523D02*
X623012D01*
X622392Y687063D01*
G01X619912D02*
Y687983D01*
G01Y690546D02*
X620584Y690623D01*
X621152Y690738D01*
X621669Y690891D01*
X622237Y691083D01*
X623012Y691390D01*
Y689856D01*
G01X618835Y687391D02*
X615635D01*
G01X615735Y684291D02*
X618735D01*
G01X618835Y681191D02*
Y687391D01*
G01X615635D02*
Y681191D01*
G01D02*
X618835D01*
G01X609640Y677556D02*
Y680756D01*
G01Y681556D02*
Y684756D01*
G01Y685556D02*
Y688756D01*
G01Y689556D02*
Y692756D01*
G01X622953Y704310D02*
Y707410D01*
X621994D01*
X621688Y707255D01*
X621496Y707048D01*
X621419Y706635D01*
X621496Y706222D01*
X621726Y705963D01*
X621994Y705808D01*
X622953D01*
G01X621994D02*
X621419Y704310D01*
G01X619086D02*
Y707410D01*
X619546Y706790D01*
G01Y704310D02*
X618626D01*
G01X616829Y704930D02*
X616599Y704568D01*
X616293Y704362D01*
X615948Y704310D01*
X615641Y704362D01*
X615334Y704620D01*
X615143Y704930D01*
X615104Y705240D01*
X615181Y705602D01*
X615449Y705860D01*
X615718Y705963D01*
X616063D01*
G01X615718D02*
X615488Y706118D01*
X615296Y706377D01*
X615219Y706687D01*
X615296Y706997D01*
X615488Y707255D01*
X615833Y707410D01*
X616178Y707358D01*
X616523Y707152D01*
G01X612886Y707410D02*
X613193Y707307D01*
X613423Y707048D01*
X613576Y706738D01*
X613691Y706325D01*
X613729Y705860D01*
X613691Y705395D01*
X613576Y704982D01*
X613423Y704672D01*
X613193Y704413D01*
X612886Y704310D01*
X612579Y704413D01*
X612349Y704672D01*
X612196Y704982D01*
X612081Y705395D01*
X612043Y705860D01*
X612081Y706325D01*
X612196Y706738D01*
X612349Y707048D01*
X612579Y707307D01*
X612886Y707410D01*
G01X610514Y705602D02*
X610246Y705963D01*
X610016Y706170D01*
X609709Y706273D01*
X609441Y706170D01*
X609249Y705963D01*
X609096Y705653D01*
X609058Y705292D01*
X609096Y704982D01*
X609249Y704672D01*
X609479Y704413D01*
X609748Y704310D01*
X610054Y704413D01*
X610323Y704723D01*
X610476Y705188D01*
X610514Y705705D01*
X610438Y706377D01*
X610323Y706738D01*
X610131Y707100D01*
X609863Y707358D01*
X609594Y707410D01*
X609326Y707307D01*
X609134Y707048D01*
G01X611561Y698995D02*
Y695795D01*
G01X617761Y698995D02*
X611561D01*
G01X617761Y695795D02*
Y698995D01*
G01X611561Y695795D02*
X617761D01*
G01X609640Y693556D02*
Y696756D01*
G01X617840Y736556D02*
X621040D01*
G01X617840Y742756D02*
Y736556D01*
G01X613340D02*
X616540D01*
G01X613340Y742756D02*
Y736556D01*
G01X616540D02*
Y742756D01*
G01X608840Y736556D02*
X612040D01*
G01X608840Y742756D02*
Y736556D01*
G01X612040D02*
Y742756D01*
G01X607540Y736556D02*
Y742756D01*
G01X621040Y731256D02*
X617840D01*
G01Y725056D02*
X621040D01*
G01X617840Y731256D02*
Y725056D01*
G01X616540Y731256D02*
X613340D01*
G01X616540Y725056D02*
Y731256D01*
G01X613340Y725056D02*
X616540D01*
G01X613340Y731256D02*
Y725056D01*
G01X612040Y731256D02*
X608840D01*
G01X612040Y725056D02*
Y731256D01*
G01X608840Y725056D02*
X612040D01*
G01X608840Y731256D02*
Y725056D01*
G01X607540D02*
Y731256D01*
G01X617940Y739656D02*
X620940D01*
G01X621040Y742756D02*
X617840D01*
G01X613440Y739656D02*
X616440D01*
G01X616540Y742756D02*
X613340D01*
G01X617515Y746805D02*
X617670Y746575D01*
X617773Y746307D01*
Y746000D01*
X617618Y745655D01*
X617360Y745387D01*
X617050Y745195D01*
X616533Y745042D01*
X616068Y745004D01*
X615603Y745080D01*
X615293Y745195D01*
X614983Y745425D01*
X614776Y745694D01*
X614673Y745962D01*
Y746230D01*
X614776Y746499D01*
X614931Y746729D01*
X615138Y746920D01*
G01X615965Y748334D02*
X616326Y748602D01*
X616533Y748832D01*
X616636Y749139D01*
X616533Y749407D01*
X616326Y749599D01*
X616016Y749752D01*
X615655Y749790D01*
X615345Y749752D01*
X615035Y749599D01*
X614776Y749369D01*
X614673Y749100D01*
X614776Y748794D01*
X615086Y748525D01*
X615551Y748372D01*
X616068Y748334D01*
X616740Y748410D01*
X617101Y748525D01*
X617463Y748717D01*
X617721Y748985D01*
X617773Y749254D01*
X617670Y749522D01*
X617411Y749714D01*
G01X615965Y751434D02*
X616326Y751702D01*
X616533Y751932D01*
X616636Y752239D01*
X616533Y752507D01*
X616326Y752699D01*
X616016Y752852D01*
X615655Y752890D01*
X615345Y752852D01*
X615035Y752699D01*
X614776Y752469D01*
X614673Y752200D01*
X614776Y751894D01*
X615086Y751625D01*
X615551Y751472D01*
X616068Y751434D01*
X616740Y751510D01*
X617101Y751625D01*
X617463Y751817D01*
X617721Y752085D01*
X617773Y752354D01*
X617670Y752622D01*
X617411Y752814D01*
G01X615035Y754610D02*
X614776Y754879D01*
X614673Y755185D01*
X614776Y755492D01*
X615086Y755760D01*
X615551Y755952D01*
X616016Y756029D01*
X616585D01*
X617050Y755952D01*
X617463Y755760D01*
X617670Y755530D01*
X617773Y755262D01*
X617670Y754955D01*
X617463Y754725D01*
X617153Y754572D01*
X616740Y754495D01*
X616378Y754572D01*
X616016Y754764D01*
X615810Y754994D01*
X615758Y755262D01*
X615861Y755569D01*
X616120Y755799D01*
X616585Y756029D01*
G01X608940Y739656D02*
X611940D01*
G01X612040Y742756D02*
X608840D01*
G01X618940Y745195D02*
X622040D01*
Y746154D01*
X621885Y746460D01*
X621678Y746652D01*
X621265Y746729D01*
X620852Y746652D01*
X620593Y746422D01*
X620438Y746154D01*
Y745195D01*
G01Y746154D02*
X618940Y746729D01*
G01X619302Y748410D02*
X619043Y748679D01*
X618940Y748985D01*
X619043Y749292D01*
X619353Y749560D01*
X619818Y749752D01*
X620283Y749829D01*
X620852D01*
X621317Y749752D01*
X621730Y749560D01*
X621937Y749330D01*
X622040Y749062D01*
X621937Y748755D01*
X621730Y748525D01*
X621420Y748372D01*
X621007Y748295D01*
X620645Y748372D01*
X620283Y748564D01*
X620077Y748794D01*
X620025Y749062D01*
X620128Y749369D01*
X620387Y749599D01*
X620852Y749829D01*
G01X622040Y752162D02*
X621937Y751855D01*
X621678Y751625D01*
X621368Y751472D01*
X620955Y751357D01*
X620490Y751319D01*
X620025Y751357D01*
X619612Y751472D01*
X619302Y751625D01*
X619043Y751855D01*
X618940Y752162D01*
X619043Y752469D01*
X619302Y752699D01*
X619612Y752852D01*
X620025Y752967D01*
X620490Y753005D01*
X620955Y752967D01*
X621368Y752852D01*
X621678Y752699D01*
X621937Y752469D01*
X622040Y752162D01*
G01X620232Y754534D02*
X620593Y754802D01*
X620800Y755032D01*
X620903Y755339D01*
X620800Y755607D01*
X620593Y755799D01*
X620283Y755952D01*
X619922Y755990D01*
X619612Y755952D01*
X619302Y755799D01*
X619043Y755569D01*
X618940Y755300D01*
X619043Y754994D01*
X619353Y754725D01*
X619818Y754572D01*
X620335Y754534D01*
X621007Y754610D01*
X621368Y754725D01*
X621730Y754917D01*
X621988Y755185D01*
X622040Y755454D01*
X621937Y755722D01*
X621678Y755914D01*
G01X610393Y745195D02*
X613493D01*
Y746154D01*
X613338Y746460D01*
X613131Y746652D01*
X612718Y746729D01*
X612305Y746652D01*
X612046Y746422D01*
X611891Y746154D01*
Y745195D01*
G01Y746154D02*
X610393Y746729D01*
G01Y749062D02*
X610445Y749330D01*
X610600Y749637D01*
X610858Y749829D01*
X611220Y749905D01*
X611581Y749829D01*
X611891Y749599D01*
X612046Y749254D01*
Y748870D01*
X612150Y748640D01*
X612408Y748449D01*
X612770Y748372D01*
X613131Y748487D01*
X613390Y748755D01*
X613493Y749062D01*
X613390Y749369D01*
X613131Y749637D01*
X612770Y749752D01*
X612408Y749675D01*
X612150Y749484D01*
X612046Y749254D01*
Y748870D01*
X611891Y748525D01*
X611581Y748295D01*
X611220Y748219D01*
X610858Y748295D01*
X610600Y748487D01*
X610445Y748794D01*
X610393Y749062D01*
G01X612976Y751434D02*
X613286Y751664D01*
X613441Y751932D01*
X613493Y752239D01*
X613390Y752622D01*
X613131Y752890D01*
X612821Y752967D01*
X612511Y752929D01*
X612253Y752775D01*
X611736Y752009D01*
X611375Y751664D01*
X610858Y751434D01*
X610393Y751357D01*
Y752967D01*
G01Y755262D02*
X610445Y755530D01*
X610600Y755837D01*
X610858Y756029D01*
X611220Y756105D01*
X611581Y756029D01*
X611891Y755799D01*
X612046Y755454D01*
Y755070D01*
X612150Y754840D01*
X612408Y754649D01*
X612770Y754572D01*
X613131Y754687D01*
X613390Y754955D01*
X613493Y755262D01*
X613390Y755569D01*
X613131Y755837D01*
X612770Y755952D01*
X612408Y755875D01*
X612150Y755684D01*
X612046Y755454D01*
Y755070D01*
X611891Y754725D01*
X611581Y754495D01*
X611220Y754419D01*
X610858Y754495D01*
X610600Y754687D01*
X610445Y754994D01*
X610393Y755262D01*
G01X606308Y745195D02*
X609408D01*
Y746154D01*
X609253Y746460D01*
X609046Y746652D01*
X608633Y746729D01*
X608220Y746652D01*
X607961Y746422D01*
X607806Y746154D01*
Y745195D01*
G01Y746154D02*
X606308Y746729D01*
G01Y749062D02*
X606360Y749330D01*
X606515Y749637D01*
X606773Y749829D01*
X607135Y749905D01*
X607496Y749829D01*
X607806Y749599D01*
X607961Y749254D01*
Y748870D01*
X608065Y748640D01*
X608323Y748449D01*
X608685Y748372D01*
X609046Y748487D01*
X609305Y748755D01*
X609408Y749062D01*
X609305Y749369D01*
X609046Y749637D01*
X608685Y749752D01*
X608323Y749675D01*
X608065Y749484D01*
X607961Y749254D01*
Y748870D01*
X607806Y748525D01*
X607496Y748295D01*
X607135Y748219D01*
X606773Y748295D01*
X606515Y748487D01*
X606360Y748794D01*
X606308Y749062D01*
G01X608891Y751434D02*
X609201Y751664D01*
X609356Y751932D01*
X609408Y752239D01*
X609305Y752622D01*
X609046Y752890D01*
X608736Y752967D01*
X608426Y752929D01*
X608168Y752775D01*
X607651Y752009D01*
X607290Y751664D01*
X606773Y751434D01*
X606308Y751357D01*
Y752967D01*
G01X607600Y754534D02*
X607961Y754802D01*
X608168Y755032D01*
X608271Y755339D01*
X608168Y755607D01*
X607961Y755799D01*
X607651Y755952D01*
X607290Y755990D01*
X606980Y755952D01*
X606670Y755799D01*
X606411Y755569D01*
X606308Y755300D01*
X606411Y754994D01*
X606721Y754725D01*
X607186Y754572D01*
X607703Y754534D01*
X608375Y754610D01*
X608736Y754725D01*
X609098Y754917D01*
X609356Y755185D01*
X609408Y755454D01*
X609305Y755722D01*
X609046Y755914D01*
G01X606714Y758013D02*
X609814D01*
Y758972D01*
X609659Y759278D01*
X609452Y759470D01*
X609039Y759547D01*
X608626Y759470D01*
X608367Y759240D01*
X608212Y758972D01*
Y758013D01*
G01Y758972D02*
X606714Y759547D01*
G01Y761880D02*
X609814D01*
X609194Y761420D01*
G01X606714D02*
Y762340D01*
G01X609297Y764252D02*
X609607Y764482D01*
X609762Y764750D01*
X609814Y765057D01*
X609711Y765440D01*
X609452Y765708D01*
X609142Y765785D01*
X608832Y765747D01*
X608574Y765593D01*
X608057Y764827D01*
X607696Y764482D01*
X607179Y764252D01*
X606714Y764175D01*
Y765785D01*
G01X609297Y767352D02*
X609607Y767582D01*
X609762Y767850D01*
X609814Y768157D01*
X609711Y768540D01*
X609452Y768808D01*
X609142Y768885D01*
X608832Y768847D01*
X608574Y768693D01*
X608057Y767927D01*
X607696Y767582D01*
X607179Y767352D01*
X606714Y767275D01*
Y768885D01*
G01Y771640D02*
X609814D01*
X607592Y770222D01*
Y772138D01*
G01X611031Y758013D02*
X614131D01*
Y758972D01*
X613976Y759278D01*
X613769Y759470D01*
X613356Y759547D01*
X612943Y759470D01*
X612684Y759240D01*
X612529Y758972D01*
Y758013D01*
G01Y758972D02*
X611031Y759547D01*
G01Y761880D02*
X611083Y762148D01*
X611238Y762455D01*
X611496Y762647D01*
X611858Y762723D01*
X612219Y762647D01*
X612529Y762417D01*
X612684Y762072D01*
Y761688D01*
X612788Y761458D01*
X613046Y761267D01*
X613408Y761190D01*
X613769Y761305D01*
X614028Y761573D01*
X614131Y761880D01*
X614028Y762187D01*
X613769Y762455D01*
X613408Y762570D01*
X613046Y762493D01*
X612788Y762302D01*
X612684Y762072D01*
Y761688D01*
X612529Y761343D01*
X612219Y761113D01*
X611858Y761037D01*
X611496Y761113D01*
X611238Y761305D01*
X611083Y761612D01*
X611031Y761880D01*
G01X611651Y764137D02*
X611289Y764367D01*
X611083Y764673D01*
X611031Y765018D01*
X611083Y765325D01*
X611341Y765632D01*
X611651Y765823D01*
X611961Y765862D01*
X612323Y765785D01*
X612581Y765517D01*
X612684Y765248D01*
Y764903D01*
G01Y765248D02*
X612839Y765478D01*
X613098Y765670D01*
X613408Y765747D01*
X613718Y765670D01*
X613976Y765478D01*
X614131Y765133D01*
X614079Y764788D01*
X613873Y764443D01*
G01X614131Y768080D02*
X614028Y767773D01*
X613769Y767543D01*
X613459Y767390D01*
X613046Y767275D01*
X612581Y767237D01*
X612116Y767275D01*
X611703Y767390D01*
X611393Y767543D01*
X611134Y767773D01*
X611031Y768080D01*
X611134Y768387D01*
X611393Y768617D01*
X611703Y768770D01*
X612116Y768885D01*
X612581Y768923D01*
X613046Y768885D01*
X613459Y768770D01*
X613769Y768617D01*
X614028Y768387D01*
X614131Y768080D01*
G01X618592Y758013D02*
X621692D01*
Y758972D01*
X621537Y759278D01*
X621330Y759470D01*
X620917Y759547D01*
X620504Y759470D01*
X620245Y759240D01*
X620090Y758972D01*
Y758013D01*
G01Y758972D02*
X618592Y759547D01*
G01Y761880D02*
X618644Y762148D01*
X618799Y762455D01*
X619057Y762647D01*
X619419Y762723D01*
X619780Y762647D01*
X620090Y762417D01*
X620245Y762072D01*
Y761688D01*
X620349Y761458D01*
X620607Y761267D01*
X620969Y761190D01*
X621330Y761305D01*
X621589Y761573D01*
X621692Y761880D01*
X621589Y762187D01*
X621330Y762455D01*
X620969Y762570D01*
X620607Y762493D01*
X620349Y762302D01*
X620245Y762072D01*
Y761688D01*
X620090Y761343D01*
X619780Y761113D01*
X619419Y761037D01*
X619057Y761113D01*
X618799Y761305D01*
X618644Y761612D01*
X618592Y761880D01*
G01X621175Y764252D02*
X621485Y764482D01*
X621640Y764750D01*
X621692Y765057D01*
X621589Y765440D01*
X621330Y765708D01*
X621020Y765785D01*
X620710Y765747D01*
X620452Y765593D01*
X619935Y764827D01*
X619574Y764482D01*
X619057Y764252D01*
X618592Y764175D01*
Y765785D01*
G01Y768003D02*
X619264Y768080D01*
X619832Y768195D01*
X620349Y768348D01*
X620917Y768540D01*
X621692Y768847D01*
Y767313D01*
G01X614900Y758013D02*
X618000D01*
Y758972D01*
X617845Y759278D01*
X617638Y759470D01*
X617225Y759547D01*
X616812Y759470D01*
X616553Y759240D01*
X616398Y758972D01*
Y758013D01*
G01Y758972D02*
X614900Y759547D01*
G01Y761880D02*
X614952Y762148D01*
X615107Y762455D01*
X615365Y762647D01*
X615727Y762723D01*
X616088Y762647D01*
X616398Y762417D01*
X616553Y762072D01*
Y761688D01*
X616657Y761458D01*
X616915Y761267D01*
X617277Y761190D01*
X617638Y761305D01*
X617897Y761573D01*
X618000Y761880D01*
X617897Y762187D01*
X617638Y762455D01*
X617277Y762570D01*
X616915Y762493D01*
X616657Y762302D01*
X616553Y762072D01*
Y761688D01*
X616398Y761343D01*
X616088Y761113D01*
X615727Y761037D01*
X615365Y761113D01*
X615107Y761305D01*
X614952Y761612D01*
X614900Y761880D01*
G01X617483Y764252D02*
X617793Y764482D01*
X617948Y764750D01*
X618000Y765057D01*
X617897Y765440D01*
X617638Y765708D01*
X617328Y765785D01*
X617018Y765747D01*
X616760Y765593D01*
X616243Y764827D01*
X615882Y764482D01*
X615365Y764252D01*
X614900Y764175D01*
Y765785D01*
G01X615262Y767428D02*
X615003Y767697D01*
X614900Y768003D01*
X615003Y768310D01*
X615313Y768578D01*
X615778Y768770D01*
X616243Y768847D01*
X616812D01*
X617277Y768770D01*
X617690Y768578D01*
X617897Y768348D01*
X618000Y768080D01*
X617897Y767773D01*
X617690Y767543D01*
X617380Y767390D01*
X616967Y767313D01*
X616605Y767390D01*
X616243Y767582D01*
X616037Y767812D01*
X615985Y768080D01*
X616088Y768387D01*
X616347Y768617D01*
X616812Y768847D01*
G01X629500Y782281D02*
X614200D01*
G01X634692Y27129D02*
Y30229D01*
X635152Y29609D01*
G01Y27129D02*
X634232D01*
G01X631592Y30229D02*
X631899Y30126D01*
X632129Y29867D01*
X632282Y29557D01*
X632397Y29144D01*
X632435Y28679D01*
X632397Y28214D01*
X632282Y27801D01*
X632129Y27491D01*
X631899Y27232D01*
X631592Y27129D01*
X631285Y27232D01*
X631055Y27491D01*
X630902Y27801D01*
X630787Y28214D01*
X630749Y28679D01*
X630787Y29144D01*
X630902Y29557D01*
X631055Y29867D01*
X631285Y30126D01*
X631592Y30229D01*
G01X623246Y29968D02*
X623016Y30278D01*
X622748Y30433D01*
X622441Y30485D01*
X622058Y30382D01*
X621790Y30123D01*
X621713Y29813D01*
X621751Y29503D01*
X621905Y29245D01*
X622671Y28728D01*
X623016Y28367D01*
X623246Y27850D01*
X623323Y27385D01*
X621713D01*
G01X634834Y36972D02*
X634565Y36713D01*
X634259Y36610D01*
X633952Y36713D01*
X633684Y37023D01*
X633492Y37488D01*
X633415Y37953D01*
Y38522D01*
X633492Y38987D01*
X633684Y39400D01*
X633914Y39607D01*
X634182Y39710D01*
X634489Y39607D01*
X634719Y39400D01*
X634872Y39090D01*
X634949Y38677D01*
X634872Y38315D01*
X634680Y37953D01*
X634450Y37747D01*
X634182Y37695D01*
X633875Y37798D01*
X633645Y38057D01*
X633415Y38522D01*
G01X622518Y36739D02*
Y39839D01*
X622978Y39219D01*
G01Y36739D02*
X622058D01*
G01X626041Y196907D02*
Y193707D01*
G01D02*
X632241D01*
G01D02*
Y196907D01*
G01X629141Y193807D02*
Y196807D01*
G01X632241Y196907D02*
X626041D01*
G01X632241Y200907D02*
X626041D01*
G01D02*
Y197707D01*
G01D02*
X632241D01*
G01D02*
Y200907D01*
G01X629141Y197807D02*
Y200807D01*
G01X632800Y207514D02*
X633030Y207669D01*
X633298Y207772D01*
X633605D01*
X633950Y207617D01*
X634218Y207359D01*
X634410Y207049D01*
X634563Y206532D01*
X634601Y206067D01*
X634525Y205602D01*
X634410Y205292D01*
X634180Y204982D01*
X633911Y204775D01*
X633643Y204672D01*
X633375D01*
X633106Y204775D01*
X632876Y204930D01*
X632685Y205137D01*
G01X630083Y204672D02*
Y207772D01*
X631501Y205550D01*
X629585D01*
G01X628095Y205034D02*
X627826Y204775D01*
X627520Y204672D01*
X627213Y204775D01*
X626945Y205085D01*
X626753Y205550D01*
X626676Y206015D01*
Y206584D01*
X626753Y207049D01*
X626945Y207462D01*
X627175Y207669D01*
X627443Y207772D01*
X627750Y207669D01*
X627980Y207462D01*
X628133Y207152D01*
X628210Y206739D01*
X628133Y206377D01*
X627941Y206015D01*
X627711Y205809D01*
X627443Y205757D01*
X627136Y205860D01*
X626906Y206119D01*
X626676Y206584D01*
G01X623883Y204672D02*
Y207772D01*
X625301Y205550D01*
X623385D01*
G01X632800Y211514D02*
X633030Y211669D01*
X633298Y211772D01*
X633605D01*
X633950Y211617D01*
X634218Y211359D01*
X634410Y211049D01*
X634563Y210532D01*
X634601Y210067D01*
X634525Y209602D01*
X634410Y209292D01*
X634180Y208982D01*
X633911Y208775D01*
X633643Y208672D01*
X633375D01*
X633106Y208775D01*
X632876Y208930D01*
X632685Y209137D01*
G01X630083Y208672D02*
Y211772D01*
X631501Y209550D01*
X629585D01*
G01X628095Y209034D02*
X627826Y208775D01*
X627520Y208672D01*
X627213Y208775D01*
X626945Y209085D01*
X626753Y209550D01*
X626676Y210015D01*
Y210584D01*
X626753Y211049D01*
X626945Y211462D01*
X627175Y211669D01*
X627443Y211772D01*
X627750Y211669D01*
X627980Y211462D01*
X628133Y211152D01*
X628210Y210739D01*
X628133Y210377D01*
X627941Y210015D01*
X627711Y209809D01*
X627443Y209757D01*
X627136Y209860D01*
X626906Y210119D01*
X626676Y210584D01*
G01X625071Y211255D02*
X624841Y211565D01*
X624573Y211720D01*
X624266Y211772D01*
X623883Y211669D01*
X623615Y211410D01*
X623538Y211100D01*
X623576Y210790D01*
X623730Y210532D01*
X624496Y210015D01*
X624841Y209654D01*
X625071Y209137D01*
X625148Y208672D01*
X623538D01*
G01X630269Y235245D02*
X630424Y235015D01*
X630527Y234747D01*
Y234440D01*
X630372Y234095D01*
X630114Y233827D01*
X629804Y233635D01*
X629287Y233482D01*
X628822Y233444D01*
X628357Y233520D01*
X628047Y233635D01*
X627737Y233865D01*
X627530Y234134D01*
X627427Y234402D01*
Y234670D01*
X627530Y234939D01*
X627685Y235169D01*
X627892Y235360D01*
G01X628047Y236659D02*
X627685Y236889D01*
X627479Y237195D01*
X627427Y237540D01*
X627479Y237847D01*
X627737Y238154D01*
X628047Y238345D01*
X628357Y238384D01*
X628719Y238307D01*
X628977Y238039D01*
X629080Y237770D01*
Y237425D01*
G01Y237770D02*
X629235Y238000D01*
X629494Y238192D01*
X629804Y238269D01*
X630114Y238192D01*
X630372Y238000D01*
X630527Y237655D01*
X630475Y237310D01*
X630269Y236965D01*
G01X627892Y239759D02*
X627634Y239989D01*
X627479Y240257D01*
X627427Y240602D01*
X627530Y240947D01*
X627737Y241215D01*
X628099Y241407D01*
X628512Y241445D01*
X628925Y241369D01*
X629184Y241177D01*
X629390Y240909D01*
X629442Y240640D01*
X629390Y240372D01*
X629184Y240027D01*
X630527Y240142D01*
Y241177D01*
G01X628719Y242974D02*
X629080Y243242D01*
X629287Y243472D01*
X629390Y243779D01*
X629287Y244047D01*
X629080Y244239D01*
X628770Y244392D01*
X628409Y244430D01*
X628099Y244392D01*
X627789Y244239D01*
X627530Y244009D01*
X627427Y243740D01*
X627530Y243434D01*
X627840Y243165D01*
X628305Y243012D01*
X628822Y242974D01*
X629494Y243050D01*
X629855Y243165D01*
X630217Y243357D01*
X630475Y243625D01*
X630527Y243894D01*
X630424Y244162D01*
X630165Y244354D01*
G01X634130Y235245D02*
X634285Y235015D01*
X634388Y234747D01*
Y234440D01*
X634233Y234095D01*
X633975Y233827D01*
X633665Y233635D01*
X633148Y233482D01*
X632683Y233444D01*
X632218Y233520D01*
X631908Y233635D01*
X631598Y233865D01*
X631391Y234134D01*
X631288Y234402D01*
Y234670D01*
X631391Y234939D01*
X631546Y235169D01*
X631753Y235360D01*
G01X631908Y236659D02*
X631546Y236889D01*
X631340Y237195D01*
X631288Y237540D01*
X631340Y237847D01*
X631598Y238154D01*
X631908Y238345D01*
X632218Y238384D01*
X632580Y238307D01*
X632838Y238039D01*
X632941Y237770D01*
Y237425D01*
G01Y237770D02*
X633096Y238000D01*
X633355Y238192D01*
X633665Y238269D01*
X633975Y238192D01*
X634233Y238000D01*
X634388Y237655D01*
X634336Y237310D01*
X634130Y236965D01*
G01X631753Y239759D02*
X631495Y239989D01*
X631340Y240257D01*
X631288Y240602D01*
X631391Y240947D01*
X631598Y241215D01*
X631960Y241407D01*
X632373Y241445D01*
X632786Y241369D01*
X633045Y241177D01*
X633251Y240909D01*
X633303Y240640D01*
X633251Y240372D01*
X633045Y240027D01*
X634388Y240142D01*
Y241177D01*
G01X631753Y242859D02*
X631495Y243089D01*
X631340Y243357D01*
X631288Y243702D01*
X631391Y244047D01*
X631598Y244315D01*
X631960Y244507D01*
X632373Y244545D01*
X632786Y244469D01*
X633045Y244277D01*
X633251Y244009D01*
X633303Y243740D01*
X633251Y243472D01*
X633045Y243127D01*
X634388Y243242D01*
Y244277D01*
G01X626316Y235245D02*
X626471Y235015D01*
X626574Y234747D01*
Y234440D01*
X626419Y234095D01*
X626161Y233827D01*
X625851Y233635D01*
X625334Y233482D01*
X624869Y233444D01*
X624404Y233520D01*
X624094Y233635D01*
X623784Y233865D01*
X623577Y234134D01*
X623474Y234402D01*
Y234670D01*
X623577Y234939D01*
X623732Y235169D01*
X623939Y235360D01*
G01X624094Y236659D02*
X623732Y236889D01*
X623526Y237195D01*
X623474Y237540D01*
X623526Y237847D01*
X623784Y238154D01*
X624094Y238345D01*
X624404Y238384D01*
X624766Y238307D01*
X625024Y238039D01*
X625127Y237770D01*
Y237425D01*
G01Y237770D02*
X625282Y238000D01*
X625541Y238192D01*
X625851Y238269D01*
X626161Y238192D01*
X626419Y238000D01*
X626574Y237655D01*
X626522Y237310D01*
X626316Y236965D01*
G01X623939Y239759D02*
X623681Y239989D01*
X623526Y240257D01*
X623474Y240602D01*
X623577Y240947D01*
X623784Y241215D01*
X624146Y241407D01*
X624559Y241445D01*
X624972Y241369D01*
X625231Y241177D01*
X625437Y240909D01*
X625489Y240640D01*
X625437Y240372D01*
X625231Y240027D01*
X626574Y240142D01*
Y241177D01*
G01X623474Y243625D02*
X624146Y243702D01*
X624714Y243817D01*
X625231Y243970D01*
X625799Y244162D01*
X626574Y244469D01*
Y242935D01*
G01X638713Y233635D02*
X635613D01*
Y235169D01*
G01X636233Y236659D02*
X635871Y236889D01*
X635665Y237195D01*
X635613Y237540D01*
X635665Y237847D01*
X635923Y238154D01*
X636233Y238345D01*
X636543Y238384D01*
X636905Y238307D01*
X637163Y238039D01*
X637266Y237770D01*
Y237425D01*
G01Y237770D02*
X637421Y238000D01*
X637680Y238192D01*
X637990Y238269D01*
X638300Y238192D01*
X638558Y238000D01*
X638713Y237655D01*
X638661Y237310D01*
X638455Y236965D01*
G01X638196Y239874D02*
X638506Y240104D01*
X638661Y240372D01*
X638713Y240679D01*
X638610Y241062D01*
X638351Y241330D01*
X638041Y241407D01*
X637731Y241369D01*
X637473Y241215D01*
X636956Y240449D01*
X636595Y240104D01*
X636078Y239874D01*
X635613Y239797D01*
Y241407D01*
G01X629507Y249856D02*
X629662Y249626D01*
X629765Y249358D01*
Y249051D01*
X629610Y248706D01*
X629352Y248438D01*
X629042Y248246D01*
X628525Y248093D01*
X628060Y248055D01*
X627595Y248131D01*
X627285Y248246D01*
X626975Y248476D01*
X626768Y248745D01*
X626665Y249013D01*
Y249281D01*
X626768Y249550D01*
X626923Y249780D01*
X627130Y249971D01*
G01X627285Y251270D02*
X626923Y251500D01*
X626717Y251806D01*
X626665Y252151D01*
X626717Y252458D01*
X626975Y252765D01*
X627285Y252956D01*
X627595Y252995D01*
X627957Y252918D01*
X628215Y252650D01*
X628318Y252381D01*
Y252036D01*
G01Y252381D02*
X628473Y252611D01*
X628732Y252803D01*
X629042Y252880D01*
X629352Y252803D01*
X629610Y252611D01*
X629765Y252266D01*
X629713Y251921D01*
X629507Y251576D01*
G01X626665Y255673D02*
X629765D01*
X627543Y254255D01*
Y256171D01*
G01X626665Y258773D02*
X629765D01*
X627543Y257355D01*
Y259271D01*
G01X633179Y249856D02*
X633334Y249626D01*
X633437Y249358D01*
Y249051D01*
X633282Y248706D01*
X633024Y248438D01*
X632714Y248246D01*
X632197Y248093D01*
X631732Y248055D01*
X631267Y248131D01*
X630957Y248246D01*
X630647Y248476D01*
X630440Y248745D01*
X630337Y249013D01*
Y249281D01*
X630440Y249550D01*
X630595Y249780D01*
X630802Y249971D01*
G01X630957Y251270D02*
X630595Y251500D01*
X630389Y251806D01*
X630337Y252151D01*
X630389Y252458D01*
X630647Y252765D01*
X630957Y252956D01*
X631267Y252995D01*
X631629Y252918D01*
X631887Y252650D01*
X631990Y252381D01*
Y252036D01*
G01Y252381D02*
X632145Y252611D01*
X632404Y252803D01*
X632714Y252880D01*
X633024Y252803D01*
X633282Y252611D01*
X633437Y252266D01*
X633385Y251921D01*
X633179Y251576D01*
G01X630337Y255673D02*
X633437D01*
X631215Y254255D01*
Y256171D01*
G01X630957Y257470D02*
X630595Y257700D01*
X630389Y258006D01*
X630337Y258351D01*
X630389Y258658D01*
X630647Y258965D01*
X630957Y259156D01*
X631267Y259195D01*
X631629Y259118D01*
X631887Y258850D01*
X631990Y258581D01*
Y258236D01*
G01Y258581D02*
X632145Y258811D01*
X632404Y259003D01*
X632714Y259080D01*
X633024Y259003D01*
X633282Y258811D01*
X633437Y258466D01*
X633385Y258121D01*
X633179Y257776D01*
G01X625467Y249856D02*
X625622Y249626D01*
X625725Y249358D01*
Y249051D01*
X625570Y248706D01*
X625312Y248438D01*
X625002Y248246D01*
X624485Y248093D01*
X624020Y248055D01*
X623555Y248131D01*
X623245Y248246D01*
X622935Y248476D01*
X622728Y248745D01*
X622625Y249013D01*
Y249281D01*
X622728Y249550D01*
X622883Y249780D01*
X623090Y249971D01*
G01X623245Y251270D02*
X622883Y251500D01*
X622677Y251806D01*
X622625Y252151D01*
X622677Y252458D01*
X622935Y252765D01*
X623245Y252956D01*
X623555Y252995D01*
X623917Y252918D01*
X624175Y252650D01*
X624278Y252381D01*
Y252036D01*
G01Y252381D02*
X624433Y252611D01*
X624692Y252803D01*
X625002Y252880D01*
X625312Y252803D01*
X625570Y252611D01*
X625725Y252266D01*
X625673Y251921D01*
X625467Y251576D01*
G01X622625Y255673D02*
X625725D01*
X623503Y254255D01*
Y256171D01*
G01X623090Y257470D02*
X622832Y257700D01*
X622677Y257968D01*
X622625Y258313D01*
X622728Y258658D01*
X622935Y258926D01*
X623297Y259118D01*
X623710Y259156D01*
X624123Y259080D01*
X624382Y258888D01*
X624588Y258620D01*
X624640Y258351D01*
X624588Y258083D01*
X624382Y257738D01*
X625725Y257853D01*
Y258888D01*
G01X638438Y248131D02*
X635338D01*
Y249665D01*
G01X635958Y251155D02*
X635596Y251385D01*
X635390Y251691D01*
X635338Y252036D01*
X635390Y252343D01*
X635648Y252650D01*
X635958Y252841D01*
X636268Y252880D01*
X636630Y252803D01*
X636888Y252535D01*
X636991Y252266D01*
Y251921D01*
G01Y252266D02*
X637146Y252496D01*
X637405Y252688D01*
X637715Y252765D01*
X638025Y252688D01*
X638283Y252496D01*
X638438Y252151D01*
X638386Y251806D01*
X638180Y251461D01*
G01X638438Y255098D02*
X638335Y254791D01*
X638076Y254561D01*
X637766Y254408D01*
X637353Y254293D01*
X636888Y254255D01*
X636423Y254293D01*
X636010Y254408D01*
X635700Y254561D01*
X635441Y254791D01*
X635338Y255098D01*
X635441Y255405D01*
X635700Y255635D01*
X636010Y255788D01*
X636423Y255903D01*
X636888Y255941D01*
X637353Y255903D01*
X637766Y255788D01*
X638076Y255635D01*
X638335Y255405D01*
X638438Y255098D01*
G01X626316Y266771D02*
X626471Y266541D01*
X626574Y266273D01*
Y265966D01*
X626419Y265621D01*
X626161Y265353D01*
X625851Y265161D01*
X625334Y265008D01*
X624869Y264970D01*
X624404Y265046D01*
X624094Y265161D01*
X623784Y265391D01*
X623577Y265660D01*
X623474Y265928D01*
Y266196D01*
X623577Y266465D01*
X623732Y266695D01*
X623939Y266886D01*
G01X624094Y268185D02*
X623732Y268415D01*
X623526Y268721D01*
X623474Y269066D01*
X623526Y269373D01*
X623784Y269680D01*
X624094Y269871D01*
X624404Y269910D01*
X624766Y269833D01*
X625024Y269565D01*
X625127Y269296D01*
Y268951D01*
G01Y269296D02*
X625282Y269526D01*
X625541Y269718D01*
X625851Y269795D01*
X626161Y269718D01*
X626419Y269526D01*
X626574Y269181D01*
X626522Y268836D01*
X626316Y268491D01*
G01X624766Y271400D02*
X625127Y271668D01*
X625334Y271898D01*
X625437Y272205D01*
X625334Y272473D01*
X625127Y272665D01*
X624817Y272818D01*
X624456Y272856D01*
X624146Y272818D01*
X623836Y272665D01*
X623577Y272435D01*
X623474Y272166D01*
X623577Y271860D01*
X623887Y271591D01*
X624352Y271438D01*
X624869Y271400D01*
X625541Y271476D01*
X625902Y271591D01*
X626264Y271783D01*
X626522Y272051D01*
X626574Y272320D01*
X626471Y272588D01*
X626212Y272780D01*
G01X626574Y275228D02*
X626471Y274921D01*
X626212Y274691D01*
X625902Y274538D01*
X625489Y274423D01*
X625024Y274385D01*
X624559Y274423D01*
X624146Y274538D01*
X623836Y274691D01*
X623577Y274921D01*
X623474Y275228D01*
X623577Y275535D01*
X623836Y275765D01*
X624146Y275918D01*
X624559Y276033D01*
X625024Y276071D01*
X625489Y276033D01*
X625902Y275918D01*
X626212Y275765D01*
X626471Y275535D01*
X626574Y275228D01*
G01X630316Y266771D02*
X630471Y266541D01*
X630574Y266273D01*
Y265966D01*
X630419Y265621D01*
X630161Y265353D01*
X629851Y265161D01*
X629334Y265008D01*
X628869Y264970D01*
X628404Y265046D01*
X628094Y265161D01*
X627784Y265391D01*
X627577Y265660D01*
X627474Y265928D01*
Y266196D01*
X627577Y266465D01*
X627732Y266695D01*
X627939Y266886D01*
G01X628094Y268185D02*
X627732Y268415D01*
X627526Y268721D01*
X627474Y269066D01*
X627526Y269373D01*
X627784Y269680D01*
X628094Y269871D01*
X628404Y269910D01*
X628766Y269833D01*
X629024Y269565D01*
X629127Y269296D01*
Y268951D01*
G01Y269296D02*
X629282Y269526D01*
X629541Y269718D01*
X629851Y269795D01*
X630161Y269718D01*
X630419Y269526D01*
X630574Y269181D01*
X630522Y268836D01*
X630316Y268491D01*
G01X627939Y271285D02*
X627681Y271515D01*
X627526Y271783D01*
X627474Y272128D01*
X627577Y272473D01*
X627784Y272741D01*
X628146Y272933D01*
X628559Y272971D01*
X628972Y272895D01*
X629231Y272703D01*
X629437Y272435D01*
X629489Y272166D01*
X629437Y271898D01*
X629231Y271553D01*
X630574Y271668D01*
Y272703D01*
G01X627836Y274576D02*
X627577Y274845D01*
X627474Y275151D01*
X627577Y275458D01*
X627887Y275726D01*
X628352Y275918D01*
X628817Y275995D01*
X629386D01*
X629851Y275918D01*
X630264Y275726D01*
X630471Y275496D01*
X630574Y275228D01*
X630471Y274921D01*
X630264Y274691D01*
X629954Y274538D01*
X629541Y274461D01*
X629179Y274538D01*
X628817Y274730D01*
X628611Y274960D01*
X628559Y275228D01*
X628662Y275535D01*
X628921Y275765D01*
X629386Y275995D01*
G01X634744Y265161D02*
X631644D01*
Y266695D01*
G01X632264Y268185D02*
X631902Y268415D01*
X631696Y268721D01*
X631644Y269066D01*
X631696Y269373D01*
X631954Y269680D01*
X632264Y269871D01*
X632574Y269910D01*
X632936Y269833D01*
X633194Y269565D01*
X633297Y269296D01*
Y268951D01*
G01Y269296D02*
X633452Y269526D01*
X633711Y269718D01*
X634021Y269795D01*
X634331Y269718D01*
X634589Y269526D01*
X634744Y269181D01*
X634692Y268836D01*
X634486Y268491D01*
G01X632264Y271285D02*
X631902Y271515D01*
X631696Y271821D01*
X631644Y272166D01*
X631696Y272473D01*
X631954Y272780D01*
X632264Y272971D01*
X632574Y273010D01*
X632936Y272933D01*
X633194Y272665D01*
X633297Y272396D01*
Y272051D01*
G01Y272396D02*
X633452Y272626D01*
X633711Y272818D01*
X634021Y272895D01*
X634331Y272818D01*
X634589Y272626D01*
X634744Y272281D01*
X634692Y271936D01*
X634486Y271591D01*
G01X635392Y422060D02*
X640904D01*
G01Y423377D02*
X635392D01*
G01Y428577D02*
Y417160D01*
G01D02*
X640904D01*
G01Y428577D02*
X635392D01*
G01X628174Y554493D02*
X628329Y554263D01*
X628432Y553995D01*
Y553688D01*
X628277Y553343D01*
X628019Y553075D01*
X627709Y552883D01*
X627192Y552730D01*
X626727Y552692D01*
X626262Y552768D01*
X625952Y552883D01*
X625642Y553113D01*
X625435Y553382D01*
X625332Y553650D01*
Y553918D01*
X625435Y554187D01*
X625590Y554417D01*
X625797Y554608D01*
G01X625332Y557210D02*
X628432D01*
X626210Y555792D01*
Y557708D01*
G01X626624Y559122D02*
X626985Y559390D01*
X627192Y559620D01*
X627295Y559927D01*
X627192Y560195D01*
X626985Y560387D01*
X626675Y560540D01*
X626314Y560578D01*
X626004Y560540D01*
X625694Y560387D01*
X625435Y560157D01*
X625332Y559888D01*
X625435Y559582D01*
X625745Y559313D01*
X626210Y559160D01*
X626727Y559122D01*
X627399Y559198D01*
X627760Y559313D01*
X628122Y559505D01*
X628380Y559773D01*
X628432Y560042D01*
X628329Y560310D01*
X628070Y560502D01*
G01X625332Y562950D02*
X628432D01*
X627812Y562490D01*
G01X625332D02*
Y563410D01*
G01X632036Y554493D02*
X632191Y554263D01*
X632294Y553995D01*
Y553688D01*
X632139Y553343D01*
X631881Y553075D01*
X631571Y552883D01*
X631054Y552730D01*
X630589Y552692D01*
X630124Y552768D01*
X629814Y552883D01*
X629504Y553113D01*
X629297Y553382D01*
X629194Y553650D01*
Y553918D01*
X629297Y554187D01*
X629452Y554417D01*
X629659Y554608D01*
G01X629194Y557210D02*
X632294D01*
X630072Y555792D01*
Y557708D01*
G01X630486Y559122D02*
X630847Y559390D01*
X631054Y559620D01*
X631157Y559927D01*
X631054Y560195D01*
X630847Y560387D01*
X630537Y560540D01*
X630176Y560578D01*
X629866Y560540D01*
X629556Y560387D01*
X629297Y560157D01*
X629194Y559888D01*
X629297Y559582D01*
X629607Y559313D01*
X630072Y559160D01*
X630589Y559122D01*
X631261Y559198D01*
X631622Y559313D01*
X631984Y559505D01*
X632242Y559773D01*
X632294Y560042D01*
X632191Y560310D01*
X631932Y560502D01*
G01X629814Y562107D02*
X629452Y562337D01*
X629246Y562643D01*
X629194Y562988D01*
X629246Y563295D01*
X629504Y563602D01*
X629814Y563793D01*
X630124Y563832D01*
X630486Y563755D01*
X630744Y563487D01*
X630847Y563218D01*
Y562873D01*
G01Y563218D02*
X631002Y563448D01*
X631261Y563640D01*
X631571Y563717D01*
X631881Y563640D01*
X632139Y563448D01*
X632294Y563103D01*
X632242Y562758D01*
X632036Y562413D01*
G01X636128Y554493D02*
X636283Y554263D01*
X636386Y553995D01*
Y553688D01*
X636231Y553343D01*
X635973Y553075D01*
X635663Y552883D01*
X635146Y552730D01*
X634681Y552692D01*
X634216Y552768D01*
X633906Y552883D01*
X633596Y553113D01*
X633389Y553382D01*
X633286Y553650D01*
Y553918D01*
X633389Y554187D01*
X633544Y554417D01*
X633751Y554608D01*
G01X633286Y557210D02*
X636386D01*
X634164Y555792D01*
Y557708D01*
G01X633751Y559007D02*
X633493Y559237D01*
X633338Y559505D01*
X633286Y559850D01*
X633389Y560195D01*
X633596Y560463D01*
X633958Y560655D01*
X634371Y560693D01*
X634784Y560617D01*
X635043Y560425D01*
X635249Y560157D01*
X635301Y559888D01*
X635249Y559620D01*
X635043Y559275D01*
X636386Y559390D01*
Y560425D01*
G01X633286Y563410D02*
X636386D01*
X634164Y561992D01*
Y563908D01*
G01X643891Y593890D02*
X644121Y594045D01*
X644389Y594148D01*
X644696D01*
X645041Y593993D01*
X645309Y593735D01*
X645501Y593425D01*
X645654Y592908D01*
X645692Y592443D01*
X645616Y591978D01*
X645501Y591668D01*
X645271Y591358D01*
X645002Y591151D01*
X644734Y591048D01*
X644466D01*
X644197Y591151D01*
X643967Y591306D01*
X643776Y591513D01*
G01X641174Y591048D02*
Y594148D01*
X642592Y591926D01*
X640676D01*
G01X639377Y591513D02*
X639147Y591255D01*
X638879Y591100D01*
X638534Y591048D01*
X638189Y591151D01*
X637921Y591358D01*
X637729Y591720D01*
X637691Y592133D01*
X637767Y592546D01*
X637959Y592805D01*
X638227Y593011D01*
X638496Y593063D01*
X638764Y593011D01*
X639109Y592805D01*
X638994Y594148D01*
X637959D01*
G01X636277Y591513D02*
X636047Y591255D01*
X635779Y591100D01*
X635434Y591048D01*
X635089Y591151D01*
X634821Y591358D01*
X634629Y591720D01*
X634591Y592133D01*
X634667Y592546D01*
X634859Y592805D01*
X635127Y593011D01*
X635396Y593063D01*
X635664Y593011D01*
X636009Y592805D01*
X635894Y594148D01*
X634859D01*
G01X644211Y598142D02*
X644441Y598297D01*
X644709Y598400D01*
X645016D01*
X645361Y598245D01*
X645629Y597987D01*
X645821Y597677D01*
X645974Y597160D01*
X646012Y596695D01*
X645936Y596230D01*
X645821Y595920D01*
X645591Y595610D01*
X645322Y595403D01*
X645054Y595300D01*
X644786D01*
X644517Y595403D01*
X644287Y595558D01*
X644096Y595765D01*
G01X641494Y595300D02*
Y598400D01*
X642912Y596178D01*
X640996D01*
G01X639697Y595765D02*
X639467Y595507D01*
X639199Y595352D01*
X638854Y595300D01*
X638509Y595403D01*
X638241Y595610D01*
X638049Y595972D01*
X638011Y596385D01*
X638087Y596798D01*
X638279Y597057D01*
X638547Y597263D01*
X638816Y597315D01*
X639084Y597263D01*
X639429Y597057D01*
X639314Y598400D01*
X638279D01*
G01X636482Y596592D02*
X636214Y596953D01*
X635984Y597160D01*
X635677Y597263D01*
X635409Y597160D01*
X635217Y596953D01*
X635064Y596643D01*
X635026Y596282D01*
X635064Y595972D01*
X635217Y595662D01*
X635447Y595403D01*
X635716Y595300D01*
X636022Y595403D01*
X636291Y595713D01*
X636444Y596178D01*
X636482Y596695D01*
X636406Y597367D01*
X636291Y597728D01*
X636099Y598090D01*
X635831Y598348D01*
X635562Y598400D01*
X635294Y598297D01*
X635102Y598038D01*
G01X625370Y588943D02*
Y582743D01*
G01X628570D02*
Y588943D01*
G01D02*
X625370D01*
G01X628470Y585843D02*
X625470D01*
G01X625370Y582743D02*
X628570D01*
G01X630970Y589143D02*
Y582943D01*
G01X634170D02*
Y589143D01*
G01D02*
X630970D01*
G01Y582943D02*
X634170D01*
G01X634070Y586043D02*
X631070D01*
G01X635270Y589143D02*
Y582943D01*
G01X638470Y589143D02*
X635270D01*
G01Y582943D02*
X638470D01*
G01X638370Y586043D02*
X635370D01*
G01X644211Y610715D02*
X644441Y610870D01*
X644709Y610973D01*
X645016D01*
X645361Y610818D01*
X645629Y610560D01*
X645821Y610250D01*
X645974Y609733D01*
X646012Y609268D01*
X645936Y608803D01*
X645821Y608493D01*
X645591Y608183D01*
X645322Y607976D01*
X645054Y607873D01*
X644786D01*
X644517Y607976D01*
X644287Y608131D01*
X644096Y608338D01*
G01X641494Y607873D02*
Y610973D01*
X642912Y608751D01*
X640996D01*
G01X638931Y607873D02*
X638854Y608545D01*
X638739Y609113D01*
X638586Y609630D01*
X638394Y610198D01*
X638087Y610973D01*
X639621D01*
G01X636482Y610456D02*
X636252Y610766D01*
X635984Y610921D01*
X635677Y610973D01*
X635294Y610870D01*
X635026Y610611D01*
X634949Y610301D01*
X634987Y609991D01*
X635141Y609733D01*
X635907Y609216D01*
X636252Y608855D01*
X636482Y608338D01*
X636559Y607873D01*
X634949D01*
G01X644211Y616005D02*
X644441Y616160D01*
X644709Y616263D01*
X645016D01*
X645361Y616108D01*
X645629Y615850D01*
X645821Y615540D01*
X645974Y615023D01*
X646012Y614558D01*
X645936Y614093D01*
X645821Y613783D01*
X645591Y613473D01*
X645322Y613266D01*
X645054Y613163D01*
X644786D01*
X644517Y613266D01*
X644287Y613421D01*
X644096Y613628D01*
G01X641494Y613163D02*
Y616263D01*
X642912Y614041D01*
X640996D01*
G01X638931Y613163D02*
X638854Y613835D01*
X638739Y614403D01*
X638586Y614920D01*
X638394Y615488D01*
X638087Y616263D01*
X639621D01*
G01X635754Y613163D02*
Y616263D01*
X636214Y615643D01*
G01Y613163D02*
X635294D01*
G01X644211Y606532D02*
X644441Y606687D01*
X644709Y606790D01*
X645016D01*
X645361Y606635D01*
X645629Y606377D01*
X645821Y606067D01*
X645974Y605550D01*
X646012Y605085D01*
X645936Y604620D01*
X645821Y604310D01*
X645591Y604000D01*
X645322Y603793D01*
X645054Y603690D01*
X644786D01*
X644517Y603793D01*
X644287Y603948D01*
X644096Y604155D01*
G01X641494Y603690D02*
Y606790D01*
X642912Y604568D01*
X640996D01*
G01X639582Y604982D02*
X639314Y605343D01*
X639084Y605550D01*
X638777Y605653D01*
X638509Y605550D01*
X638317Y605343D01*
X638164Y605033D01*
X638126Y604672D01*
X638164Y604362D01*
X638317Y604052D01*
X638547Y603793D01*
X638816Y603690D01*
X639122Y603793D01*
X639391Y604103D01*
X639544Y604568D01*
X639582Y605085D01*
X639506Y605757D01*
X639391Y606118D01*
X639199Y606480D01*
X638931Y606738D01*
X638662Y606790D01*
X638394Y606687D01*
X638202Y606428D01*
G01X635831Y603690D02*
X635754Y604362D01*
X635639Y604930D01*
X635486Y605447D01*
X635294Y606015D01*
X634987Y606790D01*
X636521D01*
G01X644211Y602371D02*
X644441Y602526D01*
X644709Y602629D01*
X645016D01*
X645361Y602474D01*
X645629Y602216D01*
X645821Y601906D01*
X645974Y601389D01*
X646012Y600924D01*
X645936Y600459D01*
X645821Y600149D01*
X645591Y599839D01*
X645322Y599632D01*
X645054Y599529D01*
X644786D01*
X644517Y599632D01*
X644287Y599787D01*
X644096Y599994D01*
G01X641494Y599529D02*
Y602629D01*
X642912Y600407D01*
X640996D01*
G01X639697Y599994D02*
X639467Y599736D01*
X639199Y599581D01*
X638854Y599529D01*
X638509Y599632D01*
X638241Y599839D01*
X638049Y600201D01*
X638011Y600614D01*
X638087Y601027D01*
X638279Y601286D01*
X638547Y601492D01*
X638816Y601544D01*
X639084Y601492D01*
X639429Y601286D01*
X639314Y602629D01*
X638279D01*
G01X636597Y600149D02*
X636367Y599787D01*
X636061Y599581D01*
X635716Y599529D01*
X635409Y599581D01*
X635102Y599839D01*
X634911Y600149D01*
X634872Y600459D01*
X634949Y600821D01*
X635217Y601079D01*
X635486Y601182D01*
X635831D01*
G01X635486D02*
X635256Y601337D01*
X635064Y601596D01*
X634987Y601906D01*
X635064Y602216D01*
X635256Y602474D01*
X635601Y602629D01*
X635946Y602577D01*
X636291Y602371D01*
G01X627670Y617943D02*
Y624143D01*
G01D02*
X624470D01*
G01D02*
Y617943D01*
G01X624570Y621043D02*
X627570D01*
G01X624470Y617943D02*
X627670D01*
G01X634737Y618045D02*
Y624245D01*
G01D02*
X631537D01*
G01D02*
Y618045D01*
G01X631637Y621145D02*
X634637D01*
G01X631537Y618045D02*
X634737D01*
G01X639073Y632348D02*
X639228Y632118D01*
X639331Y631850D01*
Y631543D01*
X639176Y631198D01*
X638918Y630930D01*
X638608Y630738D01*
X638091Y630585D01*
X637626Y630547D01*
X637161Y630623D01*
X636851Y630738D01*
X636541Y630968D01*
X636334Y631237D01*
X636231Y631505D01*
Y631773D01*
X636334Y632042D01*
X636489Y632272D01*
X636696Y632463D01*
G01X636231Y635065D02*
X639331D01*
X637109Y633647D01*
Y635563D01*
G01X637523Y636977D02*
X637884Y637245D01*
X638091Y637475D01*
X638194Y637782D01*
X638091Y638050D01*
X637884Y638242D01*
X637574Y638395D01*
X637213Y638433D01*
X636903Y638395D01*
X636593Y638242D01*
X636334Y638012D01*
X636231Y637743D01*
X636334Y637437D01*
X636644Y637168D01*
X637109Y637015D01*
X637626Y636977D01*
X638298Y637053D01*
X638659Y637168D01*
X639021Y637360D01*
X639279Y637628D01*
X639331Y637897D01*
X639228Y638165D01*
X638969Y638357D01*
G01X636696Y639962D02*
X636438Y640192D01*
X636283Y640460D01*
X636231Y640805D01*
X636334Y641150D01*
X636541Y641418D01*
X636903Y641610D01*
X637316Y641648D01*
X637729Y641572D01*
X637988Y641380D01*
X638194Y641112D01*
X638246Y640843D01*
X638194Y640575D01*
X637988Y640230D01*
X639331Y640345D01*
Y641380D01*
G01X631471Y632434D02*
X631626Y632204D01*
X631729Y631936D01*
Y631629D01*
X631574Y631284D01*
X631316Y631016D01*
X631006Y630824D01*
X630489Y630671D01*
X630024Y630633D01*
X629559Y630709D01*
X629249Y630824D01*
X628939Y631054D01*
X628732Y631323D01*
X628629Y631591D01*
Y631859D01*
X628732Y632128D01*
X628887Y632358D01*
X629094Y632549D01*
G01X628629Y635151D02*
X631729D01*
X629507Y633733D01*
Y635649D01*
G01X628629Y638251D02*
X631729D01*
X629507Y636833D01*
Y638749D01*
G01X631729Y640891D02*
X631626Y640584D01*
X631367Y640354D01*
X631057Y640201D01*
X630644Y640086D01*
X630179Y640048D01*
X629714Y640086D01*
X629301Y640201D01*
X628991Y640354D01*
X628732Y640584D01*
X628629Y640891D01*
X628732Y641198D01*
X628991Y641428D01*
X629301Y641581D01*
X629714Y641696D01*
X630179Y641734D01*
X630644Y641696D01*
X631057Y641581D01*
X631367Y641428D01*
X631626Y641198D01*
X631729Y640891D01*
G01X643613Y649415D02*
Y647193D01*
X643460Y646728D01*
X643153Y646418D01*
X642770Y646315D01*
X642387Y646418D01*
X642080Y646728D01*
X641927Y647193D01*
Y649415D01*
G01X639670Y646315D02*
Y649415D01*
X640130Y648795D01*
G01Y646315D02*
X639210D01*
G01X636110D02*
Y649415D01*
X637528Y647193D01*
X635612D01*
G01X633470Y646315D02*
Y649415D01*
X633930Y648795D01*
G01Y646315D02*
X633010D01*
G01X630438Y665537D02*
Y650537D01*
G01D02*
X643438D01*
G01X630791Y648628D02*
X630258D01*
Y647878D01*
X630418Y647628D01*
X630604Y647461D01*
X630871Y647378D01*
X631138Y647461D01*
X631324Y647628D01*
X631484Y647878D01*
X631591Y648170D01*
X631644Y648503D01*
Y648795D01*
X631591Y649045D01*
X631484Y649336D01*
X631324Y649586D01*
X631164Y649753D01*
X630951Y649878D01*
X630764D01*
X630551Y649795D01*
X630391Y649628D01*
G01X629702Y648870D02*
Y663870D01*
G01X636542Y671114D02*
Y668892D01*
X636389Y668427D01*
X636082Y668117D01*
X635699Y668014D01*
X635316Y668117D01*
X635009Y668427D01*
X634856Y668892D01*
Y671114D01*
G01X633442Y668479D02*
X633212Y668221D01*
X632944Y668066D01*
X632599Y668014D01*
X632254Y668117D01*
X631986Y668324D01*
X631794Y668686D01*
X631756Y669099D01*
X631832Y669512D01*
X632024Y669771D01*
X632292Y669977D01*
X632561Y670029D01*
X632829Y669977D01*
X633174Y669771D01*
X633059Y671114D01*
X632024D01*
G01X630151Y668376D02*
X629882Y668117D01*
X629576Y668014D01*
X629269Y668117D01*
X629001Y668427D01*
X628809Y668892D01*
X628732Y669357D01*
Y669926D01*
X628809Y670391D01*
X629001Y670804D01*
X629231Y671011D01*
X629499Y671114D01*
X629806Y671011D01*
X630036Y670804D01*
X630189Y670494D01*
X630266Y670081D01*
X630189Y669719D01*
X629997Y669357D01*
X629767Y669151D01*
X629499Y669099D01*
X629192Y669202D01*
X628962Y669461D01*
X628732Y669926D01*
G01X633963Y675234D02*
G02I-1000J0D01*
G01X636663Y672934D02*
X638963Y675234D01*
G01X631063Y672934D02*
X636663D01*
G01X631063Y711534D02*
Y672934D01*
G01X643438Y665537D02*
X630438D01*
G01X646863Y711534D02*
X631063D01*
G01X635150Y713273D02*
X638250D01*
Y714232D01*
X638095Y714538D01*
X637888Y714730D01*
X637475Y714807D01*
X637062Y714730D01*
X636803Y714500D01*
X636648Y714232D01*
Y713273D01*
G01Y714232D02*
X635150Y714807D01*
G01Y717140D02*
X638250D01*
X637630Y716680D01*
G01X635150D02*
Y717600D01*
G01Y720240D02*
X638250D01*
X637630Y719780D01*
G01X635150D02*
Y720700D01*
G01Y723263D02*
X635822Y723340D01*
X636390Y723455D01*
X636907Y723608D01*
X637475Y723800D01*
X638250Y724107D01*
Y722573D01*
G01X635615Y725597D02*
X635357Y725827D01*
X635202Y726095D01*
X635150Y726440D01*
X635253Y726785D01*
X635460Y727053D01*
X635822Y727245D01*
X636235Y727283D01*
X636648Y727207D01*
X636907Y727015D01*
X637113Y726747D01*
X637165Y726478D01*
X637113Y726210D01*
X636907Y725865D01*
X638250Y725980D01*
Y727015D01*
G01X625557Y719617D02*
X622357D01*
G01X625557Y713417D02*
Y719617D01*
G01X622357Y713417D02*
X625557D01*
G01X622357Y719617D02*
Y713417D01*
G01X626357Y719617D02*
Y713417D01*
G01D02*
X629557D01*
G01D02*
Y719617D01*
G01D02*
X626357D01*
G01X621040Y736556D02*
Y742756D01*
G01X622440Y728156D02*
X625440D01*
G01X622340Y725056D02*
X625540D01*
G01X622340Y731256D02*
Y725056D01*
G01X625540Y731256D02*
X622340D01*
G01X625540Y725056D02*
Y731256D01*
G01X622340Y736556D02*
X625540D01*
G01X622340Y742756D02*
Y736556D01*
G01X625540D02*
Y742756D01*
G01X630040Y736556D02*
Y742756D01*
G01X626840Y736556D02*
X630040D01*
G01X626840Y742756D02*
Y736556D01*
G01X634840D02*
X638040D01*
G01X634840Y742756D02*
Y736556D01*
G01X634039D02*
Y742756D01*
G01X630841Y736556D02*
X634039D01*
G01X630841Y742756D02*
Y736556D01*
G01X630040Y731247D02*
X626840D01*
G01X630040Y725047D02*
Y731247D01*
G01X626840Y725047D02*
X630040D01*
G01X626840Y731247D02*
Y725047D01*
G01X621040Y725056D02*
Y731256D01*
G01X625540Y742756D02*
X622340D01*
G01X630040D02*
X626840D01*
G01X638040D02*
X634840D01*
G01X634039D02*
X630841D01*
G01X649900Y782281D02*
X633400D01*
G01X658123Y390623D02*
X658353Y390778D01*
X658621Y390881D01*
X658928D01*
X659273Y390726D01*
X659541Y390468D01*
X659733Y390158D01*
X659886Y389641D01*
X659924Y389176D01*
X659848Y388711D01*
X659733Y388401D01*
X659503Y388091D01*
X659234Y387884D01*
X658966Y387781D01*
X658698D01*
X658429Y387884D01*
X658199Y388039D01*
X658008Y388246D01*
G01X656709Y388401D02*
X656479Y388039D01*
X656173Y387833D01*
X655828Y387781D01*
X655521Y387833D01*
X655214Y388091D01*
X655023Y388401D01*
X654984Y388711D01*
X655061Y389073D01*
X655329Y389331D01*
X655598Y389434D01*
X655943D01*
G01X655598D02*
X655368Y389589D01*
X655176Y389848D01*
X655099Y390158D01*
X655176Y390468D01*
X655368Y390726D01*
X655713Y390881D01*
X656058Y390829D01*
X656403Y390623D01*
G01X652766Y387781D02*
X652498Y387833D01*
X652191Y387988D01*
X651999Y388246D01*
X651923Y388608D01*
X651999Y388969D01*
X652229Y389279D01*
X652574Y389434D01*
X652958D01*
X653188Y389538D01*
X653379Y389796D01*
X653456Y390158D01*
X653341Y390519D01*
X653073Y390778D01*
X652766Y390881D01*
X652459Y390778D01*
X652191Y390519D01*
X652076Y390158D01*
X652153Y389796D01*
X652344Y389538D01*
X652574Y389434D01*
X652958D01*
X653303Y389279D01*
X653533Y388969D01*
X653609Y388608D01*
X653533Y388246D01*
X653341Y387988D01*
X653034Y387833D01*
X652766Y387781D01*
G01X650394Y390364D02*
X650164Y390674D01*
X649896Y390829D01*
X649589Y390881D01*
X649206Y390778D01*
X648938Y390519D01*
X648861Y390209D01*
X648899Y389899D01*
X649053Y389641D01*
X649819Y389124D01*
X650164Y388763D01*
X650394Y388246D01*
X650471Y387781D01*
X648861D01*
G01X642238Y388785D02*
Y385785D01*
G01X639138Y388885D02*
Y385685D01*
G01D02*
X645338D01*
G01Y388885D02*
X639138D01*
G01X645338Y385685D02*
Y388885D01*
G01X658123Y394577D02*
X658353Y394732D01*
X658621Y394835D01*
X658928D01*
X659273Y394680D01*
X659541Y394422D01*
X659733Y394112D01*
X659886Y393595D01*
X659924Y393130D01*
X659848Y392665D01*
X659733Y392355D01*
X659503Y392045D01*
X659234Y391838D01*
X658966Y391735D01*
X658698D01*
X658429Y391838D01*
X658199Y391993D01*
X658008Y392200D01*
G01X656709Y392355D02*
X656479Y391993D01*
X656173Y391787D01*
X655828Y391735D01*
X655521Y391787D01*
X655214Y392045D01*
X655023Y392355D01*
X654984Y392665D01*
X655061Y393027D01*
X655329Y393285D01*
X655598Y393388D01*
X655943D01*
G01X655598D02*
X655368Y393543D01*
X655176Y393802D01*
X655099Y394112D01*
X655176Y394422D01*
X655368Y394680D01*
X655713Y394835D01*
X656058Y394783D01*
X656403Y394577D01*
G01X652843Y391735D02*
X652766Y392407D01*
X652651Y392975D01*
X652498Y393492D01*
X652306Y394060D01*
X651999Y394835D01*
X653533D01*
G01X650394Y393027D02*
X650126Y393388D01*
X649896Y393595D01*
X649589Y393698D01*
X649321Y393595D01*
X649129Y393388D01*
X648976Y393078D01*
X648938Y392717D01*
X648976Y392407D01*
X649129Y392097D01*
X649359Y391838D01*
X649628Y391735D01*
X649934Y391838D01*
X650203Y392148D01*
X650356Y392613D01*
X650394Y393130D01*
X650318Y393802D01*
X650203Y394163D01*
X650011Y394525D01*
X649743Y394783D01*
X649474Y394835D01*
X649206Y394732D01*
X649014Y394473D01*
G01X642238Y393585D02*
Y390585D01*
G01X639138Y393685D02*
Y390485D01*
G01D02*
X645338D01*
G01D02*
Y393685D01*
G01X658123Y398808D02*
X658353Y398963D01*
X658621Y399066D01*
X658928D01*
X659273Y398911D01*
X659541Y398653D01*
X659733Y398343D01*
X659886Y397826D01*
X659924Y397361D01*
X659848Y396896D01*
X659733Y396586D01*
X659503Y396276D01*
X659234Y396069D01*
X658966Y395966D01*
X658698D01*
X658429Y396069D01*
X658199Y396224D01*
X658008Y396431D01*
G01X656709Y396586D02*
X656479Y396224D01*
X656173Y396018D01*
X655828Y395966D01*
X655521Y396018D01*
X655214Y396276D01*
X655023Y396586D01*
X654984Y396896D01*
X655061Y397258D01*
X655329Y397516D01*
X655598Y397619D01*
X655943D01*
G01X655598D02*
X655368Y397774D01*
X655176Y398033D01*
X655099Y398343D01*
X655176Y398653D01*
X655368Y398911D01*
X655713Y399066D01*
X656058Y399014D01*
X656403Y398808D01*
G01X652843Y395966D02*
X652766Y396638D01*
X652651Y397206D01*
X652498Y397723D01*
X652306Y398291D01*
X651999Y399066D01*
X653533D01*
G01X649206Y395966D02*
Y399066D01*
X650624Y396844D01*
X648708D01*
G01X642238Y398485D02*
Y395485D01*
G01X639138Y398585D02*
Y395385D01*
G01X645338Y398585D02*
X639138D01*
G01Y395385D02*
X645338D01*
G01D02*
Y398585D01*
G01X658123Y402901D02*
X658353Y403056D01*
X658621Y403159D01*
X658928D01*
X659273Y403004D01*
X659541Y402746D01*
X659733Y402436D01*
X659886Y401919D01*
X659924Y401454D01*
X659848Y400989D01*
X659733Y400679D01*
X659503Y400369D01*
X659234Y400162D01*
X658966Y400059D01*
X658698D01*
X658429Y400162D01*
X658199Y400317D01*
X658008Y400524D01*
G01X656709Y400679D02*
X656479Y400317D01*
X656173Y400111D01*
X655828Y400059D01*
X655521Y400111D01*
X655214Y400369D01*
X655023Y400679D01*
X654984Y400989D01*
X655061Y401351D01*
X655329Y401609D01*
X655598Y401712D01*
X655943D01*
G01X655598D02*
X655368Y401867D01*
X655176Y402126D01*
X655099Y402436D01*
X655176Y402746D01*
X655368Y403004D01*
X655713Y403159D01*
X656058Y403107D01*
X656403Y402901D01*
G01X652766Y400059D02*
X652498Y400111D01*
X652191Y400266D01*
X651999Y400524D01*
X651923Y400886D01*
X651999Y401247D01*
X652229Y401557D01*
X652574Y401712D01*
X652958D01*
X653188Y401816D01*
X653379Y402074D01*
X653456Y402436D01*
X653341Y402797D01*
X653073Y403056D01*
X652766Y403159D01*
X652459Y403056D01*
X652191Y402797D01*
X652076Y402436D01*
X652153Y402074D01*
X652344Y401816D01*
X652574Y401712D01*
X652958D01*
X653303Y401557D01*
X653533Y401247D01*
X653609Y400886D01*
X653533Y400524D01*
X653341Y400266D01*
X653034Y400111D01*
X652766Y400059D01*
G01X650509Y400524D02*
X650279Y400266D01*
X650011Y400111D01*
X649666Y400059D01*
X649321Y400162D01*
X649053Y400369D01*
X648861Y400731D01*
X648823Y401144D01*
X648899Y401557D01*
X649091Y401816D01*
X649359Y402022D01*
X649628Y402074D01*
X649896Y402022D01*
X650241Y401816D01*
X650126Y403159D01*
X649091D01*
G01X642238Y400083D02*
Y403083D01*
G01X639138Y399983D02*
X645338D01*
G01X639138Y403183D02*
Y399983D01*
G01X645338Y403183D02*
X639138D01*
G01X645338Y399983D02*
Y403183D01*
G01X658123Y407040D02*
X658353Y407195D01*
X658621Y407298D01*
X658928D01*
X659273Y407143D01*
X659541Y406885D01*
X659733Y406575D01*
X659886Y406058D01*
X659924Y405593D01*
X659848Y405128D01*
X659733Y404818D01*
X659503Y404508D01*
X659234Y404301D01*
X658966Y404198D01*
X658698D01*
X658429Y404301D01*
X658199Y404456D01*
X658008Y404663D01*
G01X656709Y404818D02*
X656479Y404456D01*
X656173Y404250D01*
X655828Y404198D01*
X655521Y404250D01*
X655214Y404508D01*
X655023Y404818D01*
X654984Y405128D01*
X655061Y405490D01*
X655329Y405748D01*
X655598Y405851D01*
X655943D01*
G01X655598D02*
X655368Y406006D01*
X655176Y406265D01*
X655099Y406575D01*
X655176Y406885D01*
X655368Y407143D01*
X655713Y407298D01*
X656058Y407246D01*
X656403Y407040D01*
G01X652766Y404198D02*
X652498Y404250D01*
X652191Y404405D01*
X651999Y404663D01*
X651923Y405025D01*
X651999Y405386D01*
X652229Y405696D01*
X652574Y405851D01*
X652958D01*
X653188Y405955D01*
X653379Y406213D01*
X653456Y406575D01*
X653341Y406936D01*
X653073Y407195D01*
X652766Y407298D01*
X652459Y407195D01*
X652191Y406936D01*
X652076Y406575D01*
X652153Y406213D01*
X652344Y405955D01*
X652574Y405851D01*
X652958D01*
X653303Y405696D01*
X653533Y405386D01*
X653609Y405025D01*
X653533Y404663D01*
X653341Y404405D01*
X653034Y404250D01*
X652766Y404198D01*
G01X650394Y405490D02*
X650126Y405851D01*
X649896Y406058D01*
X649589Y406161D01*
X649321Y406058D01*
X649129Y405851D01*
X648976Y405541D01*
X648938Y405180D01*
X648976Y404870D01*
X649129Y404560D01*
X649359Y404301D01*
X649628Y404198D01*
X649934Y404301D01*
X650203Y404611D01*
X650356Y405076D01*
X650394Y405593D01*
X650318Y406265D01*
X650203Y406626D01*
X650011Y406988D01*
X649743Y407246D01*
X649474Y407298D01*
X649206Y407195D01*
X649014Y406936D01*
G01X642238Y407383D02*
Y404383D01*
G01X639138Y407483D02*
Y404283D01*
G01X645338Y407483D02*
X639138D01*
G01Y404283D02*
X645338D01*
G01D02*
Y407483D01*
G01Y393685D02*
X639138D01*
G01X645076Y418553D02*
X641976D01*
Y420087D01*
G01X642596Y421577D02*
X642234Y421807D01*
X642028Y422113D01*
X641976Y422458D01*
X642028Y422765D01*
X642286Y423072D01*
X642596Y423263D01*
X642906Y423302D01*
X643268Y423225D01*
X643526Y422957D01*
X643629Y422688D01*
Y422343D01*
G01Y422688D02*
X643784Y422918D01*
X644043Y423110D01*
X644353Y423187D01*
X644663Y423110D01*
X644921Y422918D01*
X645076Y422573D01*
X645024Y422228D01*
X644818Y421883D01*
G01X641976Y425980D02*
X645076D01*
X642854Y424562D01*
Y426478D01*
G01X640904Y417160D02*
Y428577D01*
G01X652038Y412885D02*
X655038D01*
G01X651938Y409785D02*
X655138D01*
G01X651938Y415985D02*
Y409785D01*
G01X655138Y415985D02*
X651938D01*
G01X650338Y412785D02*
X647338D01*
G01X650438Y415885D02*
X647238D01*
G01X650438Y409685D02*
Y415885D01*
G01X647238Y409685D02*
X650438D01*
G01X647238Y415885D02*
Y409685D01*
G01X647634Y554619D02*
X647789Y554389D01*
X647892Y554121D01*
Y553814D01*
X647737Y553469D01*
X647479Y553201D01*
X647169Y553009D01*
X646652Y552856D01*
X646187Y552818D01*
X645722Y552894D01*
X645412Y553009D01*
X645102Y553239D01*
X644895Y553508D01*
X644792Y553776D01*
Y554044D01*
X644895Y554313D01*
X645050Y554543D01*
X645257Y554734D01*
G01X644792Y557336D02*
X647892D01*
X645670Y555918D01*
Y557834D01*
G01X645257Y559133D02*
X644999Y559363D01*
X644844Y559631D01*
X644792Y559976D01*
X644895Y560321D01*
X645102Y560589D01*
X645464Y560781D01*
X645877Y560819D01*
X646290Y560743D01*
X646549Y560551D01*
X646755Y560283D01*
X646807Y560014D01*
X646755Y559746D01*
X646549Y559401D01*
X647892Y559516D01*
Y560551D01*
G01X645154Y562424D02*
X644895Y562693D01*
X644792Y562999D01*
X644895Y563306D01*
X645205Y563574D01*
X645670Y563766D01*
X646135Y563843D01*
X646704D01*
X647169Y563766D01*
X647582Y563574D01*
X647789Y563344D01*
X647892Y563076D01*
X647789Y562769D01*
X647582Y562539D01*
X647272Y562386D01*
X646859Y562309D01*
X646497Y562386D01*
X646135Y562578D01*
X645929Y562808D01*
X645877Y563076D01*
X645980Y563383D01*
X646239Y563613D01*
X646704Y563843D01*
G01X643670Y554619D02*
X643825Y554389D01*
X643928Y554121D01*
Y553814D01*
X643773Y553469D01*
X643515Y553201D01*
X643205Y553009D01*
X642688Y552856D01*
X642223Y552818D01*
X641758Y552894D01*
X641448Y553009D01*
X641138Y553239D01*
X640931Y553508D01*
X640828Y553776D01*
Y554044D01*
X640931Y554313D01*
X641086Y554543D01*
X641293Y554734D01*
G01X640828Y557336D02*
X643928D01*
X641706Y555918D01*
Y557834D01*
G01X641293Y559133D02*
X641035Y559363D01*
X640880Y559631D01*
X640828Y559976D01*
X640931Y560321D01*
X641138Y560589D01*
X641500Y560781D01*
X641913Y560819D01*
X642326Y560743D01*
X642585Y560551D01*
X642791Y560283D01*
X642843Y560014D01*
X642791Y559746D01*
X642585Y559401D01*
X643928Y559516D01*
Y560551D01*
G01X643411Y562348D02*
X643721Y562578D01*
X643876Y562846D01*
X643928Y563153D01*
X643825Y563536D01*
X643566Y563804D01*
X643256Y563881D01*
X642946Y563843D01*
X642688Y563689D01*
X642171Y562923D01*
X641810Y562578D01*
X641293Y562348D01*
X640828Y562271D01*
Y563881D01*
G01X647337Y590145D02*
X653537D01*
G01Y593345D02*
X647337D01*
G01D02*
Y590145D01*
G01X650437Y593245D02*
Y590245D01*
G01X646837Y582945D02*
Y589145D01*
G01D02*
X643637D01*
G01Y582945D02*
X646837D01*
G01X646737Y586045D02*
X643737D01*
G01X643637Y589145D02*
Y582945D01*
G01X639370Y589243D02*
Y583043D01*
G01X642570D02*
Y589243D01*
G01D02*
X639370D01*
G01Y583043D02*
X642570D01*
G01X642470Y586143D02*
X639470D01*
G01X647270Y594343D02*
X653470D01*
G01X647270Y597543D02*
Y594343D01*
G01X650370Y597443D02*
Y594443D01*
G01X638470Y582943D02*
Y589143D01*
G01X653470Y597543D02*
X647270D01*
G01X647337Y610145D02*
X653537D01*
G01X647337Y613345D02*
Y610145D01*
G01X650437Y613245D02*
Y610245D01*
G01X647370Y605943D02*
X653570D01*
G01Y609143D02*
X647370D01*
G01D02*
Y605943D01*
G01X650470Y609043D02*
Y606043D01*
G01X647337Y600145D02*
X653537D01*
G01X650437Y603245D02*
Y600245D01*
G01X653537Y603345D02*
X647337D01*
G01D02*
Y600145D01*
G01X647670Y618143D02*
Y624343D01*
G01D02*
X644470D01*
G01X644570Y621243D02*
X647570D01*
G01X644470Y618143D02*
X647670D01*
G01X644470Y624343D02*
Y618143D01*
G01X656170Y626043D02*
X649970D01*
G01D02*
Y622843D01*
G01D02*
X656170D01*
G01X641670Y618143D02*
Y624343D01*
G01D02*
X638470D01*
G01D02*
Y618143D01*
G01X638570Y621243D02*
X641570D01*
G01X638470Y618143D02*
X641670D01*
G01X653537Y613345D02*
X647337D01*
G01Y614145D02*
X653537D01*
G01Y617345D02*
X647337D01*
G01D02*
Y614145D01*
G01X650437Y617245D02*
Y614245D01*
G01X646335Y631665D02*
X646490Y631435D01*
X646593Y631167D01*
Y630860D01*
X646438Y630515D01*
X646180Y630247D01*
X645870Y630055D01*
X645353Y629902D01*
X644888Y629864D01*
X644423Y629940D01*
X644113Y630055D01*
X643803Y630285D01*
X643596Y630554D01*
X643493Y630822D01*
Y631090D01*
X643596Y631359D01*
X643751Y631589D01*
X643958Y631780D01*
G01X643493Y634382D02*
X646593D01*
X644371Y632964D01*
Y634880D01*
G01X643493Y637482D02*
X646593D01*
X644371Y636064D01*
Y637980D01*
G01X643493Y640122D02*
X646593D01*
X645973Y639662D01*
G01X643493D02*
Y640582D01*
G01X652986Y643040D02*
X656086D01*
Y643999D01*
X655931Y644305D01*
X655724Y644497D01*
X655311Y644574D01*
X654898Y644497D01*
X654639Y644267D01*
X654484Y643999D01*
Y643040D01*
G01Y643999D02*
X652986Y644574D01*
G01Y646907D02*
X656086D01*
X655466Y646447D01*
G01X652986D02*
Y647367D01*
G01X656086Y650007D02*
X655983Y649700D01*
X655724Y649470D01*
X655414Y649317D01*
X655001Y649202D01*
X654536Y649164D01*
X654071Y649202D01*
X653658Y649317D01*
X653348Y649470D01*
X653089Y649700D01*
X652986Y650007D01*
X653089Y650314D01*
X653348Y650544D01*
X653658Y650697D01*
X654071Y650812D01*
X654536Y650850D01*
X655001Y650812D01*
X655414Y650697D01*
X655724Y650544D01*
X655983Y650314D01*
X656086Y650007D01*
G01X654278Y652379D02*
X654639Y652647D01*
X654846Y652877D01*
X654949Y653184D01*
X654846Y653452D01*
X654639Y653644D01*
X654329Y653797D01*
X653968Y653835D01*
X653658Y653797D01*
X653348Y653644D01*
X653089Y653414D01*
X652986Y653145D01*
X653089Y652839D01*
X653399Y652570D01*
X653864Y652417D01*
X654381Y652379D01*
X655053Y652455D01*
X655414Y652570D01*
X655776Y652762D01*
X656034Y653030D01*
X656086Y653299D01*
X655983Y653567D01*
X655724Y653759D01*
G01X652986Y656667D02*
X656086D01*
X653864Y655249D01*
Y657165D01*
G01X649260Y643024D02*
X652360D01*
Y643983D01*
X652205Y644289D01*
X651998Y644481D01*
X651585Y644558D01*
X651172Y644481D01*
X650913Y644251D01*
X650758Y643983D01*
Y643024D01*
G01Y643983D02*
X649260Y644558D01*
G01Y646891D02*
X652360D01*
X651740Y646431D01*
G01X649260D02*
Y647351D01*
G01X652360Y649991D02*
X652257Y649684D01*
X651998Y649454D01*
X651688Y649301D01*
X651275Y649186D01*
X650810Y649148D01*
X650345Y649186D01*
X649932Y649301D01*
X649622Y649454D01*
X649363Y649684D01*
X649260Y649991D01*
X649363Y650298D01*
X649622Y650528D01*
X649932Y650681D01*
X650345Y650796D01*
X650810Y650834D01*
X651275Y650796D01*
X651688Y650681D01*
X651998Y650528D01*
X652257Y650298D01*
X652360Y649991D01*
G01X650552Y652363D02*
X650913Y652631D01*
X651120Y652861D01*
X651223Y653168D01*
X651120Y653436D01*
X650913Y653628D01*
X650603Y653781D01*
X650242Y653819D01*
X649932Y653781D01*
X649622Y653628D01*
X649363Y653398D01*
X649260Y653129D01*
X649363Y652823D01*
X649673Y652554D01*
X650138Y652401D01*
X650655Y652363D01*
X651327Y652439D01*
X651688Y652554D01*
X652050Y652746D01*
X652308Y653014D01*
X652360Y653283D01*
X652257Y653551D01*
X651998Y653743D01*
G01X649260Y656191D02*
X652360D01*
X651740Y655731D01*
G01X649260D02*
Y656651D01*
G01X648739Y658893D02*
X651939D01*
G01X648739Y665093D02*
Y658893D01*
G01X651939D02*
Y665093D01*
G01X644152Y658906D02*
X647352D01*
G01D02*
Y665106D01*
G01X644152D02*
Y658906D01*
G01X645437Y651212D02*
X645224Y651004D01*
X644984Y650879D01*
X644770D01*
X644557Y651004D01*
X644397Y651212D01*
X644317Y651504D01*
X644370Y651796D01*
X644504Y652046D01*
X644744Y652212D01*
X645064Y652296D01*
X645250Y652462D01*
X645330Y652754D01*
X645277Y653046D01*
X645144Y653254D01*
X644957Y653379D01*
X644770D01*
X644584Y653296D01*
X644424Y653087D01*
G01X643438Y650537D02*
Y665537D01*
G01X641263Y672934D02*
X646863D01*
G01X638963Y675234D02*
X641263Y672934D01*
G01X646863D02*
Y711534D01*
G01X651939Y665093D02*
X648739D01*
G01X647352Y665106D02*
X644152D01*
G01X638480Y667936D02*
X637947D01*
Y667186D01*
X638107Y666936D01*
X638293Y666769D01*
X638560Y666686D01*
X638827Y666769D01*
X639013Y666936D01*
X639173Y667186D01*
X639280Y667478D01*
X639333Y667811D01*
Y668103D01*
X639280Y668353D01*
X639173Y668644D01*
X639013Y668894D01*
X638853Y669061D01*
X638640Y669186D01*
X638453D01*
X638240Y669103D01*
X638080Y668936D01*
G01X644780Y667198D02*
Y669698D01*
X644246D01*
X644033Y669573D01*
X643873Y669406D01*
X643740Y669156D01*
X643633Y668865D01*
X643606Y668448D01*
X643633Y668031D01*
X643740Y667740D01*
X643873Y667490D01*
X644033Y667323D01*
X644246Y667198D01*
X644780D01*
G01X647000Y730900D02*
X660700D01*
Y768700D01*
X681100D01*
Y743100D01*
X664800D01*
Y714500D01*
X645800D01*
Y730900D01*
X647000D01*
G01X639180Y713274D02*
X642280D01*
Y714233D01*
X642125Y714539D01*
X641918Y714731D01*
X641505Y714808D01*
X641092Y714731D01*
X640833Y714501D01*
X640678Y714233D01*
Y713274D01*
G01Y714233D02*
X639180Y714808D01*
G01Y717141D02*
X642280D01*
X641660Y716681D01*
G01X639180D02*
Y717601D01*
G01Y720241D02*
X642280D01*
X641660Y719781D01*
G01X639180D02*
Y720701D01*
G01Y723264D02*
X639852Y723341D01*
X640420Y723456D01*
X640937Y723609D01*
X641505Y723801D01*
X642280Y724108D01*
Y722574D01*
G01X640472Y725713D02*
X640833Y725981D01*
X641040Y726211D01*
X641143Y726518D01*
X641040Y726786D01*
X640833Y726978D01*
X640523Y727131D01*
X640162Y727169D01*
X639852Y727131D01*
X639542Y726978D01*
X639283Y726748D01*
X639180Y726479D01*
X639283Y726173D01*
X639593Y725904D01*
X640058Y725751D01*
X640575Y725713D01*
X641247Y725789D01*
X641608Y725904D01*
X641970Y726096D01*
X642228Y726364D01*
X642280Y726633D01*
X642177Y726901D01*
X641918Y727093D01*
G01X652752Y722273D02*
X646552D01*
G01D02*
Y719075D01*
G01D02*
X652752D01*
G01X646552Y715074D02*
X652752D01*
G01Y718274D02*
X646552D01*
G01D02*
Y715074D01*
G01X651060Y737835D02*
X654260D01*
G01X651060Y744035D02*
Y737835D01*
G01X647502Y730274D02*
Y727074D01*
G01X653702Y730274D02*
X647502D01*
G01Y727074D02*
X653702D01*
G01X646552Y726274D02*
Y723074D01*
G01X652752Y726274D02*
X646552D01*
G01Y723074D02*
X652752D01*
G01X638040Y736556D02*
Y742756D01*
G01X640300Y732983D02*
X643400D01*
Y733942D01*
X643245Y734248D01*
X643038Y734440D01*
X642625Y734517D01*
X642212Y734440D01*
X641953Y734210D01*
X641798Y733942D01*
Y732983D01*
G01Y733942D02*
X640300Y734517D01*
G01Y736850D02*
X643400D01*
X642780Y736390D01*
G01X640300D02*
Y737310D01*
G01X640920Y739107D02*
X640558Y739337D01*
X640352Y739643D01*
X640300Y739988D01*
X640352Y740295D01*
X640610Y740602D01*
X640920Y740793D01*
X641230Y740832D01*
X641592Y740755D01*
X641850Y740487D01*
X641953Y740218D01*
Y739873D01*
G01Y740218D02*
X642108Y740448D01*
X642367Y740640D01*
X642677Y740717D01*
X642987Y740640D01*
X643245Y740448D01*
X643400Y740103D01*
X643348Y739758D01*
X643142Y739413D01*
G01X640920Y742207D02*
X640558Y742437D01*
X640352Y742743D01*
X640300Y743088D01*
X640352Y743395D01*
X640610Y743702D01*
X640920Y743893D01*
X641230Y743932D01*
X641592Y743855D01*
X641850Y743587D01*
X641953Y743318D01*
Y742973D01*
G01Y743318D02*
X642108Y743548D01*
X642367Y743740D01*
X642677Y743817D01*
X642987Y743740D01*
X643245Y743548D01*
X643400Y743203D01*
X643348Y742858D01*
X643142Y742513D01*
G01X640920Y745307D02*
X640558Y745537D01*
X640352Y745843D01*
X640300Y746188D01*
X640352Y746495D01*
X640610Y746802D01*
X640920Y746993D01*
X641230Y747032D01*
X641592Y746955D01*
X641850Y746687D01*
X641953Y746418D01*
Y746073D01*
G01Y746418D02*
X642108Y746648D01*
X642367Y746840D01*
X642677Y746917D01*
X642987Y746840D01*
X643245Y746648D01*
X643400Y746303D01*
X643348Y745958D01*
X643142Y745613D01*
G01X649600Y737400D02*
Y743600D01*
X646400D01*
Y737400D01*
X649600D01*
G01X653442Y751393D02*
X653597Y751163D01*
X653700Y750895D01*
Y750588D01*
X653545Y750243D01*
X653287Y749975D01*
X652977Y749783D01*
X652460Y749630D01*
X651995Y749592D01*
X651530Y749668D01*
X651220Y749783D01*
X650910Y750013D01*
X650703Y750282D01*
X650600Y750550D01*
Y750818D01*
X650703Y751087D01*
X650858Y751317D01*
X651065Y751508D01*
G01X651892Y752922D02*
X652253Y753190D01*
X652460Y753420D01*
X652563Y753727D01*
X652460Y753995D01*
X652253Y754187D01*
X651943Y754340D01*
X651582Y754378D01*
X651272Y754340D01*
X650962Y754187D01*
X650703Y753957D01*
X650600Y753688D01*
X650703Y753382D01*
X651013Y753113D01*
X651478Y752960D01*
X651995Y752922D01*
X652667Y752998D01*
X653028Y753113D01*
X653390Y753305D01*
X653648Y753573D01*
X653700Y753842D01*
X653597Y754110D01*
X653338Y754302D01*
G01X650600Y756750D02*
X653700D01*
X653080Y756290D01*
G01X650600D02*
Y757210D01*
G01X651220Y759007D02*
X650858Y759237D01*
X650652Y759543D01*
X650600Y759888D01*
X650652Y760195D01*
X650910Y760502D01*
X651220Y760693D01*
X651530Y760732D01*
X651892Y760655D01*
X652150Y760387D01*
X652253Y760118D01*
Y759773D01*
G01Y760118D02*
X652408Y760348D01*
X652667Y760540D01*
X652977Y760617D01*
X653287Y760540D01*
X653545Y760348D01*
X653700Y760003D01*
X653648Y759658D01*
X653442Y759313D01*
G01X654260Y744035D02*
X651060D01*
G01X651160Y740935D02*
X654160D01*
G01X657019Y375638D02*
X657174Y375408D01*
X657277Y375140D01*
Y374833D01*
X657122Y374488D01*
X656864Y374220D01*
X656554Y374028D01*
X656037Y373875D01*
X655572Y373837D01*
X655107Y373913D01*
X654797Y374028D01*
X654487Y374258D01*
X654280Y374527D01*
X654177Y374795D01*
Y375063D01*
X654280Y375332D01*
X654435Y375562D01*
X654642Y375753D01*
G01X654797Y377052D02*
X654435Y377282D01*
X654229Y377588D01*
X654177Y377933D01*
X654229Y378240D01*
X654487Y378547D01*
X654797Y378738D01*
X655107Y378777D01*
X655469Y378700D01*
X655727Y378432D01*
X655830Y378163D01*
Y377818D01*
G01Y378163D02*
X655985Y378393D01*
X656244Y378585D01*
X656554Y378662D01*
X656864Y378585D01*
X657122Y378393D01*
X657277Y378048D01*
X657225Y377703D01*
X657019Y377358D01*
G01X654177Y380918D02*
X654849Y380995D01*
X655417Y381110D01*
X655934Y381263D01*
X656502Y381455D01*
X657277Y381762D01*
Y380228D01*
G01Y384095D02*
X657174Y383788D01*
X656915Y383558D01*
X656605Y383405D01*
X656192Y383290D01*
X655727Y383252D01*
X655262Y383290D01*
X654849Y383405D01*
X654539Y383558D01*
X654280Y383788D01*
X654177Y384095D01*
X654280Y384402D01*
X654539Y384632D01*
X654849Y384785D01*
X655262Y384900D01*
X655727Y384938D01*
X656192Y384900D01*
X656605Y384785D01*
X656915Y384632D01*
X657174Y384402D01*
X657277Y384095D01*
G01X669922Y371510D02*
X666922D01*
G01X666822Y368410D02*
X670022D01*
G01X666822Y374610D02*
Y368410D01*
G01X670022Y374610D02*
X666822D01*
G01X661438Y382085D02*
X658438D01*
G01X661538Y385185D02*
X658338D01*
G01Y378985D02*
X661538D01*
G01X658338Y385185D02*
Y378985D01*
G01X661538D02*
Y385185D01*
G01X667132Y387653D02*
X667287Y387423D01*
X667390Y387155D01*
Y386848D01*
X667235Y386503D01*
X666977Y386235D01*
X666667Y386043D01*
X666150Y385890D01*
X665685Y385852D01*
X665220Y385928D01*
X664910Y386043D01*
X664600Y386273D01*
X664393Y386542D01*
X664290Y386810D01*
Y387078D01*
X664393Y387347D01*
X664548Y387577D01*
X664755Y387768D01*
G01X664910Y389067D02*
X664548Y389297D01*
X664342Y389603D01*
X664290Y389948D01*
X664342Y390255D01*
X664600Y390562D01*
X664910Y390753D01*
X665220Y390792D01*
X665582Y390715D01*
X665840Y390447D01*
X665943Y390178D01*
Y389833D01*
G01Y390178D02*
X666098Y390408D01*
X666357Y390600D01*
X666667Y390677D01*
X666977Y390600D01*
X667235Y390408D01*
X667390Y390063D01*
X667338Y389718D01*
X667132Y389373D01*
G01X664290Y393010D02*
X664342Y393278D01*
X664497Y393585D01*
X664755Y393777D01*
X665117Y393853D01*
X665478Y393777D01*
X665788Y393547D01*
X665943Y393202D01*
Y392818D01*
X666047Y392588D01*
X666305Y392397D01*
X666667Y392320D01*
X667028Y392435D01*
X667287Y392703D01*
X667390Y393010D01*
X667287Y393317D01*
X667028Y393585D01*
X666667Y393700D01*
X666305Y393623D01*
X666047Y393432D01*
X665943Y393202D01*
Y392818D01*
X665788Y392473D01*
X665478Y392243D01*
X665117Y392167D01*
X664755Y392243D01*
X664497Y392435D01*
X664342Y392742D01*
X664290Y393010D01*
G01X667390Y396110D02*
X667287Y395803D01*
X667028Y395573D01*
X666718Y395420D01*
X666305Y395305D01*
X665840Y395267D01*
X665375Y395305D01*
X664962Y395420D01*
X664652Y395573D01*
X664393Y395803D01*
X664290Y396110D01*
X664393Y396417D01*
X664652Y396647D01*
X664962Y396800D01*
X665375Y396915D01*
X665840Y396953D01*
X666305Y396915D01*
X666718Y396800D01*
X667028Y396647D01*
X667287Y396417D01*
X667390Y396110D01*
G01X662438Y382085D02*
X665438D01*
G01X662338Y378985D02*
X665538D01*
G01X662338Y385185D02*
Y378985D01*
G01X665538Y385185D02*
X662338D01*
G01X665538Y378985D02*
Y385185D01*
G01X659838Y412785D02*
X656838D01*
G01X659938Y415885D02*
X656738D01*
G01Y409685D02*
X659938D01*
G01X656738Y415885D02*
Y409685D01*
G01X659938D02*
Y415885D01*
G01X655138Y409785D02*
Y415985D01*
G01X664738Y412885D02*
X661738D01*
G01X664838Y415985D02*
X661638D01*
G01X664838Y409785D02*
Y415985D01*
G01X661638Y409785D02*
X664838D01*
G01X661638Y415985D02*
Y409785D01*
G01X669038Y412785D02*
X666038D01*
G01X669138Y415885D02*
X665938D01*
G01Y409685D02*
X669138D01*
G01X665938Y415885D02*
Y409685D01*
G01X674445Y461970D02*
X674675Y462125D01*
X674943Y462228D01*
X675250D01*
X675595Y462073D01*
X675863Y461815D01*
X676055Y461505D01*
X676208Y460988D01*
X676246Y460523D01*
X676170Y460058D01*
X676055Y459748D01*
X675825Y459438D01*
X675556Y459231D01*
X675288Y459128D01*
X675020D01*
X674751Y459231D01*
X674521Y459386D01*
X674330Y459593D01*
G01X672265Y459128D02*
X672188Y459800D01*
X672073Y460368D01*
X671920Y460885D01*
X671728Y461453D01*
X671421Y462228D01*
X672955D01*
G01X669740Y459490D02*
X669471Y459231D01*
X669165Y459128D01*
X668858Y459231D01*
X668590Y459541D01*
X668398Y460006D01*
X668321Y460471D01*
Y461040D01*
X668398Y461505D01*
X668590Y461918D01*
X668820Y462125D01*
X669088Y462228D01*
X669395Y462125D01*
X669625Y461918D01*
X669778Y461608D01*
X669855Y461195D01*
X669778Y460833D01*
X669586Y460471D01*
X669356Y460265D01*
X669088Y460213D01*
X668781Y460316D01*
X668551Y460575D01*
X668321Y461040D01*
G01X666716Y461711D02*
X666486Y462021D01*
X666218Y462176D01*
X665911Y462228D01*
X665528Y462125D01*
X665260Y461866D01*
X665183Y461556D01*
X665221Y461246D01*
X665375Y460988D01*
X666141Y460471D01*
X666486Y460110D01*
X666716Y459593D01*
X666793Y459128D01*
X665183D01*
G01X675118Y500875D02*
X675348Y501030D01*
X675616Y501133D01*
X675923D01*
X676268Y500978D01*
X676536Y500720D01*
X676728Y500410D01*
X676881Y499893D01*
X676919Y499428D01*
X676843Y498963D01*
X676728Y498653D01*
X676498Y498343D01*
X676229Y498136D01*
X675961Y498033D01*
X675693D01*
X675424Y498136D01*
X675194Y498291D01*
X675003Y498498D01*
G01X672938Y498033D02*
X672861Y498705D01*
X672746Y499273D01*
X672593Y499790D01*
X672401Y500358D01*
X672094Y501133D01*
X673628D01*
G01X669761Y498033D02*
X669493Y498085D01*
X669186Y498240D01*
X668994Y498498D01*
X668918Y498860D01*
X668994Y499221D01*
X669224Y499531D01*
X669569Y499686D01*
X669953D01*
X670183Y499790D01*
X670374Y500048D01*
X670451Y500410D01*
X670336Y500771D01*
X670068Y501030D01*
X669761Y501133D01*
X669454Y501030D01*
X669186Y500771D01*
X669071Y500410D01*
X669148Y500048D01*
X669339Y499790D01*
X669569Y499686D01*
X669953D01*
X670298Y499531D01*
X670528Y499221D01*
X670604Y498860D01*
X670528Y498498D01*
X670336Y498240D01*
X670029Y498085D01*
X669761Y498033D01*
G01X666201D02*
Y501133D01*
X667619Y498911D01*
X665703D01*
G01X675062Y496743D02*
X675292Y496898D01*
X675560Y497001D01*
X675867D01*
X676212Y496846D01*
X676480Y496588D01*
X676672Y496278D01*
X676825Y495761D01*
X676863Y495296D01*
X676787Y494831D01*
X676672Y494521D01*
X676442Y494211D01*
X676173Y494004D01*
X675905Y493901D01*
X675637D01*
X675368Y494004D01*
X675138Y494159D01*
X674947Y494366D01*
G01X672882Y493901D02*
X672805Y494573D01*
X672690Y495141D01*
X672537Y495658D01*
X672345Y496226D01*
X672038Y497001D01*
X673572D01*
G01X669705Y493901D02*
X669437Y493953D01*
X669130Y494108D01*
X668938Y494366D01*
X668862Y494728D01*
X668938Y495089D01*
X669168Y495399D01*
X669513Y495554D01*
X669897D01*
X670127Y495658D01*
X670318Y495916D01*
X670395Y496278D01*
X670280Y496639D01*
X670012Y496898D01*
X669705Y497001D01*
X669398Y496898D01*
X669130Y496639D01*
X669015Y496278D01*
X669092Y495916D01*
X669283Y495658D01*
X669513Y495554D01*
X669897D01*
X670242Y495399D01*
X670472Y495089D01*
X670548Y494728D01*
X670472Y494366D01*
X670280Y494108D01*
X669973Y493953D01*
X669705Y493901D01*
G01X667448Y494366D02*
X667218Y494108D01*
X666950Y493953D01*
X666605Y493901D01*
X666260Y494004D01*
X665992Y494211D01*
X665800Y494573D01*
X665762Y494986D01*
X665838Y495399D01*
X666030Y495658D01*
X666298Y495864D01*
X666567Y495916D01*
X666835Y495864D01*
X667180Y495658D01*
X667065Y497001D01*
X666030D01*
G01X674805Y492592D02*
X675035Y492747D01*
X675303Y492850D01*
X675610D01*
X675955Y492695D01*
X676223Y492437D01*
X676415Y492127D01*
X676568Y491610D01*
X676606Y491145D01*
X676530Y490680D01*
X676415Y490370D01*
X676185Y490060D01*
X675916Y489853D01*
X675648Y489750D01*
X675380D01*
X675111Y489853D01*
X674881Y490008D01*
X674690Y490215D01*
G01X672625Y489750D02*
X672548Y490422D01*
X672433Y490990D01*
X672280Y491507D01*
X672088Y492075D01*
X671781Y492850D01*
X673315D01*
G01X670100Y490112D02*
X669831Y489853D01*
X669525Y489750D01*
X669218Y489853D01*
X668950Y490163D01*
X668758Y490628D01*
X668681Y491093D01*
Y491662D01*
X668758Y492127D01*
X668950Y492540D01*
X669180Y492747D01*
X669448Y492850D01*
X669755Y492747D01*
X669985Y492540D01*
X670138Y492230D01*
X670215Y491817D01*
X670138Y491455D01*
X669946Y491093D01*
X669716Y490887D01*
X669448Y490835D01*
X669141Y490938D01*
X668911Y491197D01*
X668681Y491662D01*
G01X666348Y492850D02*
X666655Y492747D01*
X666885Y492488D01*
X667038Y492178D01*
X667153Y491765D01*
X667191Y491300D01*
X667153Y490835D01*
X667038Y490422D01*
X666885Y490112D01*
X666655Y489853D01*
X666348Y489750D01*
X666041Y489853D01*
X665811Y490112D01*
X665658Y490422D01*
X665543Y490835D01*
X665505Y491300D01*
X665543Y491765D01*
X665658Y492178D01*
X665811Y492488D01*
X666041Y492747D01*
X666348Y492850D01*
G01X676409Y597805D02*
X676639Y597960D01*
X676907Y598063D01*
X677214D01*
X677559Y597908D01*
X677827Y597650D01*
X678019Y597340D01*
X678172Y596823D01*
X678210Y596358D01*
X678134Y595893D01*
X678019Y595583D01*
X677789Y595273D01*
X677520Y595066D01*
X677252Y594963D01*
X676984D01*
X676715Y595066D01*
X676485Y595221D01*
X676294Y595428D01*
G01X673692Y594963D02*
Y598063D01*
X675110Y595841D01*
X673194D01*
G01X671895Y595428D02*
X671665Y595170D01*
X671397Y595015D01*
X671052Y594963D01*
X670707Y595066D01*
X670439Y595273D01*
X670247Y595635D01*
X670209Y596048D01*
X670285Y596461D01*
X670477Y596720D01*
X670745Y596926D01*
X671014Y596978D01*
X671282Y596926D01*
X671627Y596720D01*
X671512Y598063D01*
X670477D01*
G01X667952Y594963D02*
Y598063D01*
X668412Y597443D01*
G01Y594963D02*
X667492D01*
G01X656870Y594843D02*
X663070D01*
G01D02*
Y598043D01*
G01X656870D02*
Y594843D01*
G01X659970Y594943D02*
Y597943D01*
G01X676409Y593536D02*
X676639Y593691D01*
X676907Y593794D01*
X677214D01*
X677559Y593639D01*
X677827Y593381D01*
X678019Y593071D01*
X678172Y592554D01*
X678210Y592089D01*
X678134Y591624D01*
X678019Y591314D01*
X677789Y591004D01*
X677520Y590797D01*
X677252Y590694D01*
X676984D01*
X676715Y590797D01*
X676485Y590952D01*
X676294Y591159D01*
G01X673692Y590694D02*
Y593794D01*
X675110Y591572D01*
X673194D01*
G01X670592Y590694D02*
Y593794D01*
X672010Y591572D01*
X670094D01*
G01X668604Y591056D02*
X668335Y590797D01*
X668029Y590694D01*
X667722Y590797D01*
X667454Y591107D01*
X667262Y591572D01*
X667185Y592037D01*
Y592606D01*
X667262Y593071D01*
X667454Y593484D01*
X667684Y593691D01*
X667952Y593794D01*
X668259Y593691D01*
X668489Y593484D01*
X668642Y593174D01*
X668719Y592761D01*
X668642Y592399D01*
X668450Y592037D01*
X668220Y591831D01*
X667952Y591779D01*
X667645Y591882D01*
X667415Y592141D01*
X667185Y592606D01*
G01X663070Y593743D02*
X656870D01*
G01Y590543D02*
X663070D01*
G01D02*
Y593743D01*
G01X656870D02*
Y590543D01*
G01X659970Y590643D02*
Y593643D01*
G01X653537Y590145D02*
Y593345D01*
G01X653470Y594343D02*
Y597543D01*
G01X663070Y598043D02*
X656870D01*
G01X676409Y602082D02*
X676639Y602237D01*
X676907Y602340D01*
X677214D01*
X677559Y602185D01*
X677827Y601927D01*
X678019Y601617D01*
X678172Y601100D01*
X678210Y600635D01*
X678134Y600170D01*
X678019Y599860D01*
X677789Y599550D01*
X677520Y599343D01*
X677252Y599240D01*
X676984D01*
X676715Y599343D01*
X676485Y599498D01*
X676294Y599705D01*
G01X673692Y599240D02*
Y602340D01*
X675110Y600118D01*
X673194D01*
G01X671895Y599705D02*
X671665Y599447D01*
X671397Y599292D01*
X671052Y599240D01*
X670707Y599343D01*
X670439Y599550D01*
X670247Y599912D01*
X670209Y600325D01*
X670285Y600738D01*
X670477Y600997D01*
X670745Y601203D01*
X671014Y601255D01*
X671282Y601203D01*
X671627Y600997D01*
X671512Y602340D01*
X670477D01*
G01X667952D02*
X668259Y602237D01*
X668489Y601978D01*
X668642Y601668D01*
X668757Y601255D01*
X668795Y600790D01*
X668757Y600325D01*
X668642Y599912D01*
X668489Y599602D01*
X668259Y599343D01*
X667952Y599240D01*
X667645Y599343D01*
X667415Y599602D01*
X667262Y599912D01*
X667147Y600325D01*
X667109Y600790D01*
X667147Y601255D01*
X667262Y601668D01*
X667415Y601978D01*
X667645Y602237D01*
X667952Y602340D01*
G01X656972Y600376D02*
X663172D01*
G01Y603576D02*
X656972D01*
G01X663172Y600376D02*
Y603576D01*
G01X656972D02*
Y600376D01*
G01X660072Y600476D02*
Y603476D01*
G01X653537Y610145D02*
Y613345D01*
G01X653570Y605943D02*
Y609143D01*
G01X653537Y600145D02*
Y603345D01*
G01X662782Y607868D02*
X668982D01*
G01Y611068D02*
X662782D01*
G01D02*
Y607868D01*
G01X657037Y616941D02*
X663237D01*
G01Y620141D02*
X657037D01*
G01X663237Y616941D02*
Y620141D01*
G01X657037D02*
Y616941D01*
G01X660137Y617041D02*
Y620041D01*
G01X665250Y630189D02*
X665480Y630344D01*
X665748Y630447D01*
X666055D01*
X666400Y630292D01*
X666668Y630034D01*
X666860Y629724D01*
X667013Y629207D01*
X667051Y628742D01*
X666975Y628277D01*
X666860Y627967D01*
X666630Y627657D01*
X666361Y627450D01*
X666093Y627347D01*
X665825D01*
X665556Y627450D01*
X665326Y627605D01*
X665135Y627812D01*
G01X662533Y627347D02*
Y630447D01*
X663951Y628225D01*
X662035D01*
G01X659433Y627347D02*
Y630447D01*
X660851Y628225D01*
X658935D01*
G01X657636Y627967D02*
X657406Y627605D01*
X657100Y627399D01*
X656755Y627347D01*
X656448Y627399D01*
X656141Y627657D01*
X655950Y627967D01*
X655911Y628277D01*
X655988Y628639D01*
X656256Y628897D01*
X656525Y629000D01*
X656870D01*
G01X656525D02*
X656295Y629155D01*
X656103Y629414D01*
X656026Y629724D01*
X656103Y630034D01*
X656295Y630292D01*
X656640Y630447D01*
X656985Y630395D01*
X657330Y630189D01*
G01X656170Y622843D02*
Y626043D01*
G01X653070Y622943D02*
Y625943D01*
G01X663270Y616143D02*
X657070D01*
G01Y612943D02*
X663270D01*
G01D02*
Y616143D01*
G01X657070D02*
Y612943D01*
G01X660170Y613043D02*
Y616043D01*
G01X653537Y614145D02*
Y617345D01*
G01X666156Y656013D02*
X666311Y655783D01*
X666414Y655515D01*
Y655208D01*
X666259Y654863D01*
X666001Y654595D01*
X665691Y654403D01*
X665174Y654250D01*
X664709Y654212D01*
X664244Y654288D01*
X663934Y654403D01*
X663624Y654633D01*
X663417Y654902D01*
X663314Y655170D01*
Y655438D01*
X663417Y655707D01*
X663572Y655937D01*
X663779Y656128D01*
G01X663676Y657618D02*
X663417Y657887D01*
X663314Y658193D01*
X663417Y658500D01*
X663727Y658768D01*
X664192Y658960D01*
X664657Y659037D01*
X665226D01*
X665691Y658960D01*
X666104Y658768D01*
X666311Y658538D01*
X666414Y658270D01*
X666311Y657963D01*
X666104Y657733D01*
X665794Y657580D01*
X665381Y657503D01*
X665019Y657580D01*
X664657Y657772D01*
X664451Y658002D01*
X664399Y658270D01*
X664502Y658577D01*
X664761Y658807D01*
X665226Y659037D01*
G01X663314Y661370D02*
X666414D01*
X665794Y660910D01*
G01X663314D02*
Y661830D01*
G01X664606Y663742D02*
X664967Y664010D01*
X665174Y664240D01*
X665277Y664547D01*
X665174Y664815D01*
X664967Y665007D01*
X664657Y665160D01*
X664296Y665198D01*
X663986Y665160D01*
X663676Y665007D01*
X663417Y664777D01*
X663314Y664508D01*
X663417Y664202D01*
X663727Y663933D01*
X664192Y663780D01*
X664709Y663742D01*
X665381Y663818D01*
X665742Y663933D01*
X666104Y664125D01*
X666362Y664393D01*
X666414Y664662D01*
X666311Y664930D01*
X666052Y665122D01*
G01X662464Y678095D02*
Y675095D01*
G01X659364Y674995D02*
X665564D01*
G01D02*
Y678195D01*
G01X659364D02*
Y674995D01*
G01X662904Y673654D02*
Y667454D01*
G01X666003Y670554D02*
X663003D01*
G01X662904Y667454D02*
X666102D01*
G01D02*
Y673654D01*
G01D02*
X662904D01*
G01X665564Y678195D02*
X659364D01*
G01X661552Y687870D02*
X661707Y687640D01*
X661810Y687372D01*
Y687065D01*
X661655Y686720D01*
X661397Y686452D01*
X661087Y686260D01*
X660570Y686107D01*
X660105Y686069D01*
X659640Y686145D01*
X659330Y686260D01*
X659020Y686490D01*
X658813Y686759D01*
X658710Y687027D01*
Y687295D01*
X658813Y687564D01*
X658968Y687794D01*
X659175Y687985D01*
G01X659072Y689475D02*
X658813Y689744D01*
X658710Y690050D01*
X658813Y690357D01*
X659123Y690625D01*
X659588Y690817D01*
X660053Y690894D01*
X660622D01*
X661087Y690817D01*
X661500Y690625D01*
X661707Y690395D01*
X661810Y690127D01*
X661707Y689820D01*
X661500Y689590D01*
X661190Y689437D01*
X660777Y689360D01*
X660415Y689437D01*
X660053Y689629D01*
X659847Y689859D01*
X659795Y690127D01*
X659898Y690434D01*
X660157Y690664D01*
X660622Y690894D01*
G01X658710Y693227D02*
X661810D01*
X661190Y692767D01*
G01X658710D02*
Y693687D01*
G01Y696327D02*
X658762Y696595D01*
X658917Y696902D01*
X659175Y697094D01*
X659537Y697170D01*
X659898Y697094D01*
X660208Y696864D01*
X660363Y696519D01*
Y696135D01*
X660467Y695905D01*
X660725Y695714D01*
X661087Y695637D01*
X661448Y695752D01*
X661707Y696020D01*
X661810Y696327D01*
X661707Y696634D01*
X661448Y696902D01*
X661087Y697017D01*
X660725Y696940D01*
X660467Y696749D01*
X660363Y696519D01*
Y696135D01*
X660208Y695790D01*
X659898Y695560D01*
X659537Y695484D01*
X659175Y695560D01*
X658917Y695752D01*
X658762Y696059D01*
X658710Y696327D01*
G01X662534Y682223D02*
X659534D01*
G01X659434Y685323D02*
Y679123D01*
G01D02*
X662634D01*
G01D02*
Y685323D01*
G01D02*
X659434D01*
G01X652752Y719075D02*
Y722273D01*
G01Y715074D02*
Y718274D01*
G01X655060Y737835D02*
X658260D01*
G01X655060Y744035D02*
Y737835D01*
G01X658260D02*
Y744035D01*
G01X654260Y737835D02*
Y744035D01*
G01X653702Y727074D02*
Y730274D01*
G01X652752Y723074D02*
Y726274D01*
G01X658242Y746793D02*
X658397Y746563D01*
X658500Y746295D01*
Y745988D01*
X658345Y745643D01*
X658087Y745375D01*
X657777Y745183D01*
X657260Y745030D01*
X656795Y744992D01*
X656330Y745068D01*
X656020Y745183D01*
X655710Y745413D01*
X655503Y745682D01*
X655400Y745950D01*
Y746218D01*
X655503Y746487D01*
X655658Y746717D01*
X655865Y746908D01*
G01X656692Y748322D02*
X657053Y748590D01*
X657260Y748820D01*
X657363Y749127D01*
X657260Y749395D01*
X657053Y749587D01*
X656743Y749740D01*
X656382Y749778D01*
X656072Y749740D01*
X655762Y749587D01*
X655503Y749357D01*
X655400Y749088D01*
X655503Y748782D01*
X655813Y748513D01*
X656278Y748360D01*
X656795Y748322D01*
X657467Y748398D01*
X657828Y748513D01*
X658190Y748705D01*
X658448Y748973D01*
X658500Y749242D01*
X658397Y749510D01*
X658138Y749702D01*
G01X655400Y752150D02*
X658500D01*
X657880Y751690D01*
G01X655400D02*
Y752610D01*
G01X658500Y755250D02*
X658397Y754943D01*
X658138Y754713D01*
X657828Y754560D01*
X657415Y754445D01*
X656950Y754407D01*
X656485Y754445D01*
X656072Y754560D01*
X655762Y754713D01*
X655503Y754943D01*
X655400Y755250D01*
X655503Y755557D01*
X655762Y755787D01*
X656072Y755940D01*
X656485Y756055D01*
X656950Y756093D01*
X657415Y756055D01*
X657828Y755940D01*
X658138Y755787D01*
X658397Y755557D01*
X658500Y755250D01*
G01X658260Y744035D02*
X655060D01*
G01X655160Y740935D02*
X658160D01*
G01X675745Y754801D02*
Y757901D01*
X674786D01*
X674480Y757746D01*
X674288Y757539D01*
X674211Y757126D01*
X674288Y756713D01*
X674518Y756454D01*
X674786Y756299D01*
X675745D01*
G01X674786D02*
X674211Y754801D01*
G01X671878D02*
Y757901D01*
X672338Y757281D01*
G01Y754801D02*
X671418D01*
G01X668778D02*
Y757901D01*
X669238Y757281D01*
G01Y754801D02*
X668318D01*
G01X665755D02*
X665678Y755473D01*
X665563Y756041D01*
X665410Y756558D01*
X665218Y757126D01*
X664911Y757901D01*
X666445D01*
G01X663421Y755421D02*
X663191Y755059D01*
X662885Y754853D01*
X662540Y754801D01*
X662233Y754853D01*
X661926Y755111D01*
X661735Y755421D01*
X661696Y755731D01*
X661773Y756093D01*
X662041Y756351D01*
X662310Y756454D01*
X662655D01*
G01X662310D02*
X662080Y756609D01*
X661888Y756868D01*
X661811Y757178D01*
X661888Y757488D01*
X662080Y757746D01*
X662425Y757901D01*
X662770Y757849D01*
X663115Y757643D01*
G01X675745Y750835D02*
Y753935D01*
X674786D01*
X674480Y753780D01*
X674288Y753573D01*
X674211Y753160D01*
X674288Y752747D01*
X674518Y752488D01*
X674786Y752333D01*
X675745D01*
G01X674786D02*
X674211Y750835D01*
G01X671878D02*
Y753935D01*
X672338Y753315D01*
G01Y750835D02*
X671418D01*
G01X668778D02*
Y753935D01*
X669238Y753315D01*
G01Y750835D02*
X668318D01*
G01X665755D02*
X665678Y751507D01*
X665563Y752075D01*
X665410Y752592D01*
X665218Y753160D01*
X664911Y753935D01*
X666445D01*
G01X662118Y750835D02*
Y753935D01*
X663536Y751713D01*
X661620D01*
G01X675745Y758462D02*
Y761562D01*
X674786D01*
X674480Y761407D01*
X674288Y761200D01*
X674211Y760787D01*
X674288Y760374D01*
X674518Y760115D01*
X674786Y759960D01*
X675745D01*
G01X674786D02*
X674211Y758462D01*
G01X671878D02*
Y761562D01*
X672338Y760942D01*
G01Y758462D02*
X671418D01*
G01X669621Y759082D02*
X669391Y758720D01*
X669085Y758514D01*
X668740Y758462D01*
X668433Y758514D01*
X668126Y758772D01*
X667935Y759082D01*
X667896Y759392D01*
X667973Y759754D01*
X668241Y760012D01*
X668510Y760115D01*
X668855D01*
G01X668510D02*
X668280Y760270D01*
X668088Y760529D01*
X668011Y760839D01*
X668088Y761149D01*
X668280Y761407D01*
X668625Y761562D01*
X668970Y761510D01*
X669315Y761304D01*
G01X665678Y761562D02*
X665985Y761459D01*
X666215Y761200D01*
X666368Y760890D01*
X666483Y760477D01*
X666521Y760012D01*
X666483Y759547D01*
X666368Y759134D01*
X666215Y758824D01*
X665985Y758565D01*
X665678Y758462D01*
X665371Y758565D01*
X665141Y758824D01*
X664988Y759134D01*
X664873Y759547D01*
X664835Y760012D01*
X664873Y760477D01*
X664988Y760890D01*
X665141Y761200D01*
X665371Y761459D01*
X665678Y761562D01*
G01X662578Y758462D02*
X662310Y758514D01*
X662003Y758669D01*
X661811Y758927D01*
X661735Y759289D01*
X661811Y759650D01*
X662041Y759960D01*
X662386Y760115D01*
X662770D01*
X663000Y760219D01*
X663191Y760477D01*
X663268Y760839D01*
X663153Y761200D01*
X662885Y761459D01*
X662578Y761562D01*
X662271Y761459D01*
X662003Y761200D01*
X661888Y760839D01*
X661965Y760477D01*
X662156Y760219D01*
X662386Y760115D01*
X662770D01*
X663115Y759960D01*
X663345Y759650D01*
X663421Y759289D01*
X663345Y758927D01*
X663153Y758669D01*
X662846Y758514D01*
X662578Y758462D01*
G01X678817Y762600D02*
Y765700D01*
X677858D01*
X677552Y765545D01*
X677360Y765338D01*
X677283Y764925D01*
X677360Y764512D01*
X677590Y764253D01*
X677858Y764098D01*
X678817D01*
G01X677858D02*
X677283Y762600D01*
G01X674950D02*
Y765700D01*
X675410Y765080D01*
G01Y762600D02*
X674490D01*
G01X672693Y763220D02*
X672463Y762858D01*
X672157Y762652D01*
X671812Y762600D01*
X671505Y762652D01*
X671198Y762910D01*
X671007Y763220D01*
X670968Y763530D01*
X671045Y763892D01*
X671313Y764150D01*
X671582Y764253D01*
X671927D01*
G01X671582D02*
X671352Y764408D01*
X671160Y764667D01*
X671083Y764977D01*
X671160Y765287D01*
X671352Y765545D01*
X671697Y765700D01*
X672042Y765648D01*
X672387Y765442D01*
G01X668750Y765700D02*
X669057Y765597D01*
X669287Y765338D01*
X669440Y765028D01*
X669555Y764615D01*
X669593Y764150D01*
X669555Y763685D01*
X669440Y763272D01*
X669287Y762962D01*
X669057Y762703D01*
X668750Y762600D01*
X668443Y762703D01*
X668213Y762962D01*
X668060Y763272D01*
X667945Y763685D01*
X667907Y764150D01*
X667945Y764615D01*
X668060Y765028D01*
X668213Y765338D01*
X668443Y765597D01*
X668750Y765700D01*
G01X665727Y762600D02*
X665650Y763272D01*
X665535Y763840D01*
X665382Y764357D01*
X665190Y764925D01*
X664883Y765700D01*
X666417D01*
G01X679700Y782281D02*
X659800D01*
G01X682158Y362475D02*
X682313Y362245D01*
X682416Y361977D01*
Y361670D01*
X682261Y361325D01*
X682003Y361057D01*
X681693Y360865D01*
X681176Y360712D01*
X680711Y360674D01*
X680246Y360750D01*
X679936Y360865D01*
X679626Y361095D01*
X679419Y361364D01*
X679316Y361632D01*
Y361900D01*
X679419Y362169D01*
X679574Y362399D01*
X679781Y362590D01*
G01X679936Y363889D02*
X679574Y364119D01*
X679368Y364425D01*
X679316Y364770D01*
X679368Y365077D01*
X679626Y365384D01*
X679936Y365575D01*
X680246Y365614D01*
X680608Y365537D01*
X680866Y365269D01*
X680969Y365000D01*
Y364655D01*
G01Y365000D02*
X681124Y365230D01*
X681383Y365422D01*
X681693Y365499D01*
X682003Y365422D01*
X682261Y365230D01*
X682416Y364885D01*
X682364Y364540D01*
X682158Y364195D01*
G01X679316Y367832D02*
X679368Y368100D01*
X679523Y368407D01*
X679781Y368599D01*
X680143Y368675D01*
X680504Y368599D01*
X680814Y368369D01*
X680969Y368024D01*
Y367640D01*
X681073Y367410D01*
X681331Y367219D01*
X681693Y367142D01*
X682054Y367257D01*
X682313Y367525D01*
X682416Y367832D01*
X682313Y368139D01*
X682054Y368407D01*
X681693Y368522D01*
X681331Y368445D01*
X681073Y368254D01*
X680969Y368024D01*
Y367640D01*
X680814Y367295D01*
X680504Y367065D01*
X680143Y366989D01*
X679781Y367065D01*
X679523Y367257D01*
X679368Y367564D01*
X679316Y367832D01*
G01X679936Y370089D02*
X679574Y370319D01*
X679368Y370625D01*
X679316Y370970D01*
X679368Y371277D01*
X679626Y371584D01*
X679936Y371775D01*
X680246Y371814D01*
X680608Y371737D01*
X680866Y371469D01*
X680969Y371200D01*
Y370855D01*
G01Y371200D02*
X681124Y371430D01*
X681383Y371622D01*
X681693Y371699D01*
X682003Y371622D01*
X682261Y371430D01*
X682416Y371085D01*
X682364Y370740D01*
X682158Y370395D01*
G01X671022Y371510D02*
X674022D01*
G01X670922Y368410D02*
X674122D01*
G01X670922Y374610D02*
Y368410D01*
G01X674122D02*
Y374610D01*
G01D02*
X670922D01*
G01X678144Y362552D02*
X678299Y362322D01*
X678402Y362054D01*
Y361747D01*
X678247Y361402D01*
X677989Y361134D01*
X677679Y360942D01*
X677162Y360789D01*
X676697Y360751D01*
X676232Y360827D01*
X675922Y360942D01*
X675612Y361172D01*
X675405Y361441D01*
X675302Y361709D01*
Y361977D01*
X675405Y362246D01*
X675560Y362476D01*
X675767Y362667D01*
G01X675922Y363966D02*
X675560Y364196D01*
X675354Y364502D01*
X675302Y364847D01*
X675354Y365154D01*
X675612Y365461D01*
X675922Y365652D01*
X676232Y365691D01*
X676594Y365614D01*
X676852Y365346D01*
X676955Y365077D01*
Y364732D01*
G01Y365077D02*
X677110Y365307D01*
X677369Y365499D01*
X677679Y365576D01*
X677989Y365499D01*
X678247Y365307D01*
X678402Y364962D01*
X678350Y364617D01*
X678144Y364272D01*
G01X675302Y367909D02*
X675354Y368177D01*
X675509Y368484D01*
X675767Y368676D01*
X676129Y368752D01*
X676490Y368676D01*
X676800Y368446D01*
X676955Y368101D01*
Y367717D01*
X677059Y367487D01*
X677317Y367296D01*
X677679Y367219D01*
X678040Y367334D01*
X678299Y367602D01*
X678402Y367909D01*
X678299Y368216D01*
X678040Y368484D01*
X677679Y368599D01*
X677317Y368522D01*
X677059Y368331D01*
X676955Y368101D01*
Y367717D01*
X676800Y367372D01*
X676490Y367142D01*
X676129Y367066D01*
X675767Y367142D01*
X675509Y367334D01*
X675354Y367641D01*
X675302Y367909D01*
G01Y371469D02*
X678402D01*
X676180Y370051D01*
Y371967D01*
G01X670022Y368410D02*
Y374610D01*
G01X673938Y389685D02*
Y386685D01*
G01X670838Y389785D02*
Y386585D01*
G01D02*
X677038D01*
G01Y389785D02*
X670838D01*
G01X677038Y386585D02*
Y389785D01*
G01X673938Y390885D02*
Y393885D01*
G01X670838Y390785D02*
X677038D01*
G01X670838Y393985D02*
Y390785D01*
G01X677038D02*
Y393985D01*
G01X673938Y400285D02*
Y403285D01*
G01X670838Y400185D02*
X677038D01*
G01X670838Y403385D02*
Y400185D01*
G01X677038Y403385D02*
X670838D01*
G01X677038Y400185D02*
Y403385D01*
G01X673938Y408285D02*
Y405285D01*
G01X670838Y408385D02*
Y405185D01*
G01D02*
X677038D01*
G01D02*
Y408385D01*
G01X673938Y396085D02*
Y399085D01*
G01X670838Y395985D02*
X677038D01*
G01X670838Y399185D02*
Y395985D01*
G01X677038Y399185D02*
X670838D01*
G01X677038Y395985D02*
Y399185D01*
G01Y393985D02*
X670838D01*
G01X677038Y408385D02*
X670838D01*
G01X684542Y420382D02*
X684697Y420152D01*
X684800Y419884D01*
Y419577D01*
X684645Y419232D01*
X684387Y418964D01*
X684077Y418772D01*
X683560Y418619D01*
X683095Y418581D01*
X682630Y418657D01*
X682320Y418772D01*
X682010Y419002D01*
X681803Y419271D01*
X681700Y419539D01*
Y419807D01*
X681803Y420076D01*
X681958Y420306D01*
X682165Y420497D01*
G01X682320Y421796D02*
X681958Y422026D01*
X681752Y422332D01*
X681700Y422677D01*
X681752Y422984D01*
X682010Y423291D01*
X682320Y423482D01*
X682630Y423521D01*
X682992Y423444D01*
X683250Y423176D01*
X683353Y422907D01*
Y422562D01*
G01Y422907D02*
X683508Y423137D01*
X683767Y423329D01*
X684077Y423406D01*
X684387Y423329D01*
X684645Y423137D01*
X684800Y422792D01*
X684748Y422447D01*
X684542Y422102D01*
G01X681700Y425662D02*
X682372Y425739D01*
X682940Y425854D01*
X683457Y426007D01*
X684025Y426199D01*
X684800Y426506D01*
Y424972D01*
G01X684283Y428111D02*
X684593Y428341D01*
X684748Y428609D01*
X684800Y428916D01*
X684697Y429299D01*
X684438Y429567D01*
X684128Y429644D01*
X683818Y429606D01*
X683560Y429452D01*
X683043Y428686D01*
X682682Y428341D01*
X682165Y428111D01*
X681700Y428034D01*
Y429644D01*
G01X680358Y420382D02*
X680513Y420152D01*
X680616Y419884D01*
Y419577D01*
X680461Y419232D01*
X680203Y418964D01*
X679893Y418772D01*
X679376Y418619D01*
X678911Y418581D01*
X678446Y418657D01*
X678136Y418772D01*
X677826Y419002D01*
X677619Y419271D01*
X677516Y419539D01*
Y419807D01*
X677619Y420076D01*
X677774Y420306D01*
X677981Y420497D01*
G01X678136Y421796D02*
X677774Y422026D01*
X677568Y422332D01*
X677516Y422677D01*
X677568Y422984D01*
X677826Y423291D01*
X678136Y423482D01*
X678446Y423521D01*
X678808Y423444D01*
X679066Y423176D01*
X679169Y422907D01*
Y422562D01*
G01Y422907D02*
X679324Y423137D01*
X679583Y423329D01*
X679893Y423406D01*
X680203Y423329D01*
X680461Y423137D01*
X680616Y422792D01*
X680564Y422447D01*
X680358Y422102D01*
G01X678808Y425011D02*
X679169Y425279D01*
X679376Y425509D01*
X679479Y425816D01*
X679376Y426084D01*
X679169Y426276D01*
X678859Y426429D01*
X678498Y426467D01*
X678188Y426429D01*
X677878Y426276D01*
X677619Y426046D01*
X677516Y425777D01*
X677619Y425471D01*
X677929Y425202D01*
X678394Y425049D01*
X678911Y425011D01*
X679583Y425087D01*
X679944Y425202D01*
X680306Y425394D01*
X680564Y425662D01*
X680616Y425931D01*
X680513Y426199D01*
X680254Y426391D01*
G01X677878Y428187D02*
X677619Y428456D01*
X677516Y428762D01*
X677619Y429069D01*
X677929Y429337D01*
X678394Y429529D01*
X678859Y429606D01*
X679428D01*
X679893Y429529D01*
X680306Y429337D01*
X680513Y429107D01*
X680616Y428839D01*
X680513Y428532D01*
X680306Y428302D01*
X679996Y428149D01*
X679583Y428072D01*
X679221Y428149D01*
X678859Y428341D01*
X678653Y428571D01*
X678601Y428839D01*
X678704Y429146D01*
X678963Y429376D01*
X679428Y429606D01*
G01X669138Y409685D02*
Y415885D01*
G01X675944Y420382D02*
X676099Y420152D01*
X676202Y419884D01*
Y419577D01*
X676047Y419232D01*
X675789Y418964D01*
X675479Y418772D01*
X674962Y418619D01*
X674497Y418581D01*
X674032Y418657D01*
X673722Y418772D01*
X673412Y419002D01*
X673205Y419271D01*
X673102Y419539D01*
Y419807D01*
X673205Y420076D01*
X673360Y420306D01*
X673567Y420497D01*
G01X673722Y421796D02*
X673360Y422026D01*
X673154Y422332D01*
X673102Y422677D01*
X673154Y422984D01*
X673412Y423291D01*
X673722Y423482D01*
X674032Y423521D01*
X674394Y423444D01*
X674652Y423176D01*
X674755Y422907D01*
Y422562D01*
G01Y422907D02*
X674910Y423137D01*
X675169Y423329D01*
X675479Y423406D01*
X675789Y423329D01*
X676047Y423137D01*
X676202Y422792D01*
X676150Y422447D01*
X675944Y422102D01*
G01X673102Y425739D02*
X673154Y426007D01*
X673309Y426314D01*
X673567Y426506D01*
X673929Y426582D01*
X674290Y426506D01*
X674600Y426276D01*
X674755Y425931D01*
Y425547D01*
X674859Y425317D01*
X675117Y425126D01*
X675479Y425049D01*
X675840Y425164D01*
X676099Y425432D01*
X676202Y425739D01*
X676099Y426046D01*
X675840Y426314D01*
X675479Y426429D01*
X675117Y426352D01*
X674859Y426161D01*
X674755Y425931D01*
Y425547D01*
X674600Y425202D01*
X674290Y424972D01*
X673929Y424896D01*
X673567Y424972D01*
X673309Y425164D01*
X673154Y425471D01*
X673102Y425739D01*
G01Y428839D02*
X676202D01*
X675582Y428379D01*
G01X673102D02*
Y429299D01*
G01X687716Y441940D02*
X687871Y441710D01*
X687974Y441442D01*
Y441135D01*
X687819Y440790D01*
X687561Y440522D01*
X687251Y440330D01*
X686734Y440177D01*
X686269Y440139D01*
X685804Y440215D01*
X685494Y440330D01*
X685184Y440560D01*
X684977Y440829D01*
X684874Y441097D01*
Y441365D01*
X684977Y441634D01*
X685132Y441864D01*
X685339Y442055D01*
G01X684874Y444120D02*
X685546Y444197D01*
X686114Y444312D01*
X686631Y444465D01*
X687199Y444657D01*
X687974Y444964D01*
Y443430D01*
G01X685236Y446645D02*
X684977Y446914D01*
X684874Y447220D01*
X684977Y447527D01*
X685287Y447795D01*
X685752Y447987D01*
X686217Y448064D01*
X686786D01*
X687251Y447987D01*
X687664Y447795D01*
X687871Y447565D01*
X687974Y447297D01*
X687871Y446990D01*
X687664Y446760D01*
X687354Y446607D01*
X686941Y446530D01*
X686579Y446607D01*
X686217Y446799D01*
X686011Y447029D01*
X685959Y447297D01*
X686062Y447604D01*
X686321Y447834D01*
X686786Y448064D01*
G01X685494Y449554D02*
X685132Y449784D01*
X684926Y450090D01*
X684874Y450435D01*
X684926Y450742D01*
X685184Y451049D01*
X685494Y451240D01*
X685804Y451279D01*
X686166Y451202D01*
X686424Y450934D01*
X686527Y450665D01*
Y450320D01*
G01Y450665D02*
X686682Y450895D01*
X686941Y451087D01*
X687251Y451164D01*
X687561Y451087D01*
X687819Y450895D01*
X687974Y450550D01*
X687922Y450205D01*
X687716Y449860D01*
G01X680930Y452699D02*
X685530D01*
G01X680930Y462899D02*
Y452699D01*
G01X675395Y470330D02*
Y465730D01*
G01X685595Y470330D02*
X675395D01*
G01Y465730D02*
X685595D01*
G01X680495D02*
Y470330D01*
G01X685530Y457799D02*
X680930D01*
G01X685530Y462899D02*
X680930D01*
G01X671461Y488134D02*
Y483534D01*
G01D02*
X681661D01*
G01X676561D02*
Y488134D01*
G01X681661Y483534D02*
Y488134D01*
G01X671461Y482634D02*
Y478034D01*
G01X681661Y482634D02*
X671461D01*
G01Y478034D02*
X681661D01*
G01X676561D02*
Y482634D01*
G01X681661Y478034D02*
Y482634D01*
G01X671461Y477134D02*
Y472534D01*
G01D02*
X681661D01*
G01X676561D02*
Y477134D01*
G01X681661D02*
X671461D01*
G01X681661Y472534D02*
Y477134D01*
G01Y488134D02*
X671461D01*
G01X681754Y616198D02*
X681984Y616353D01*
X682252Y616456D01*
X682559D01*
X682904Y616301D01*
X683172Y616043D01*
X683364Y615733D01*
X683517Y615216D01*
X683555Y614751D01*
X683479Y614286D01*
X683364Y613976D01*
X683134Y613666D01*
X682865Y613459D01*
X682597Y613356D01*
X682329D01*
X682060Y613459D01*
X681830Y613614D01*
X681639Y613821D01*
G01X679037Y613356D02*
Y616456D01*
X680455Y614234D01*
X678539D01*
G01X677240Y613821D02*
X677010Y613563D01*
X676742Y613408D01*
X676397Y613356D01*
X676052Y613459D01*
X675784Y613666D01*
X675592Y614028D01*
X675554Y614441D01*
X675630Y614854D01*
X675822Y615113D01*
X676090Y615319D01*
X676359Y615371D01*
X676627Y615319D01*
X676972Y615113D01*
X676857Y616456D01*
X675822D01*
G01X673297Y613356D02*
X673029Y613408D01*
X672722Y613563D01*
X672530Y613821D01*
X672454Y614183D01*
X672530Y614544D01*
X672760Y614854D01*
X673105Y615009D01*
X673489D01*
X673719Y615113D01*
X673910Y615371D01*
X673987Y615733D01*
X673872Y616094D01*
X673604Y616353D01*
X673297Y616456D01*
X672990Y616353D01*
X672722Y616094D01*
X672607Y615733D01*
X672684Y615371D01*
X672875Y615113D01*
X673105Y615009D01*
X673489D01*
X673834Y614854D01*
X674064Y614544D01*
X674140Y614183D01*
X674064Y613821D01*
X673872Y613563D01*
X673565Y613408D01*
X673297Y613356D01*
G01X682747Y607619D02*
Y610719D01*
X681788D01*
X681482Y610564D01*
X681290Y610357D01*
X681213Y609944D01*
X681290Y609531D01*
X681520Y609272D01*
X681788Y609117D01*
X682747D01*
G01X681788D02*
X681213Y607619D01*
G01X679723Y608084D02*
X679493Y607826D01*
X679225Y607671D01*
X678880Y607619D01*
X678535Y607722D01*
X678267Y607929D01*
X678075Y608291D01*
X678037Y608704D01*
X678113Y609117D01*
X678305Y609376D01*
X678573Y609582D01*
X678842Y609634D01*
X679110Y609582D01*
X679455Y609376D01*
X679340Y610719D01*
X678305D01*
G01X675780Y607619D02*
X675512Y607671D01*
X675205Y607826D01*
X675013Y608084D01*
X674937Y608446D01*
X675013Y608807D01*
X675243Y609117D01*
X675588Y609272D01*
X675972D01*
X676202Y609376D01*
X676393Y609634D01*
X676470Y609996D01*
X676355Y610357D01*
X676087Y610616D01*
X675780Y610719D01*
X675473Y610616D01*
X675205Y610357D01*
X675090Y609996D01*
X675167Y609634D01*
X675358Y609376D01*
X675588Y609272D01*
X675972D01*
X676317Y609117D01*
X676547Y608807D01*
X676623Y608446D01*
X676547Y608084D01*
X676355Y607826D01*
X676048Y607671D01*
X675780Y607619D01*
G01X672680D02*
Y610719D01*
X673140Y610099D01*
G01Y607619D02*
X672220D01*
G01X668982Y607868D02*
Y611068D01*
G01X681914Y620337D02*
X682144Y620492D01*
X682412Y620595D01*
X682719D01*
X683064Y620440D01*
X683332Y620182D01*
X683524Y619872D01*
X683677Y619355D01*
X683715Y618890D01*
X683639Y618425D01*
X683524Y618115D01*
X683294Y617805D01*
X683025Y617598D01*
X682757Y617495D01*
X682489D01*
X682220Y617598D01*
X681990Y617753D01*
X681799Y617960D01*
G01X679197Y617495D02*
Y620595D01*
X680615Y618373D01*
X678699D01*
G01X677400Y617960D02*
X677170Y617702D01*
X676902Y617547D01*
X676557Y617495D01*
X676212Y617598D01*
X675944Y617805D01*
X675752Y618167D01*
X675714Y618580D01*
X675790Y618993D01*
X675982Y619252D01*
X676250Y619458D01*
X676519Y619510D01*
X676787Y619458D01*
X677132Y619252D01*
X677017Y620595D01*
X675982D01*
G01X673534Y617495D02*
X673457Y618167D01*
X673342Y618735D01*
X673189Y619252D01*
X672997Y619820D01*
X672690Y620595D01*
X674224D01*
G01X681968Y627347D02*
X684968D01*
G01X681868Y630447D02*
Y624247D01*
G01D02*
X685068D01*
G01X684414Y639377D02*
X684569Y639147D01*
X684672Y638879D01*
Y638572D01*
X684517Y638227D01*
X684259Y637959D01*
X683949Y637767D01*
X683432Y637614D01*
X682967Y637576D01*
X682502Y637652D01*
X682192Y637767D01*
X681882Y637997D01*
X681675Y638266D01*
X681572Y638534D01*
Y638802D01*
X681675Y639071D01*
X681830Y639301D01*
X682037Y639492D01*
G01Y640791D02*
X681779Y641021D01*
X681624Y641289D01*
X681572Y641634D01*
X681675Y641979D01*
X681882Y642247D01*
X682244Y642439D01*
X682657Y642477D01*
X683070Y642401D01*
X683329Y642209D01*
X683535Y641941D01*
X683587Y641672D01*
X683535Y641404D01*
X683329Y641059D01*
X684672Y641174D01*
Y642209D01*
G01X684155Y644006D02*
X684465Y644236D01*
X684620Y644504D01*
X684672Y644811D01*
X684569Y645194D01*
X684310Y645462D01*
X684000Y645539D01*
X683690Y645501D01*
X683432Y645347D01*
X682915Y644581D01*
X682554Y644236D01*
X682037Y644006D01*
X681572Y643929D01*
Y645539D01*
G01Y647834D02*
X684672D01*
X684052Y647374D01*
G01X681572D02*
Y648294D01*
G01X685068Y630447D02*
X681868D01*
G01X679285Y677125D02*
X679515Y677280D01*
X679783Y677383D01*
X680090D01*
X680435Y677228D01*
X680703Y676970D01*
X680895Y676660D01*
X681048Y676143D01*
X681086Y675678D01*
X681010Y675213D01*
X680895Y674903D01*
X680665Y674593D01*
X680396Y674386D01*
X680128Y674283D01*
X679860D01*
X679591Y674386D01*
X679361Y674541D01*
X679170Y674748D01*
G01X677680Y674645D02*
X677411Y674386D01*
X677105Y674283D01*
X676798Y674386D01*
X676530Y674696D01*
X676338Y675161D01*
X676261Y675626D01*
Y676195D01*
X676338Y676660D01*
X676530Y677073D01*
X676760Y677280D01*
X677028Y677383D01*
X677335Y677280D01*
X677565Y677073D01*
X677718Y676763D01*
X677795Y676350D01*
X677718Y675988D01*
X677526Y675626D01*
X677296Y675420D01*
X677028Y675368D01*
X676721Y675471D01*
X676491Y675730D01*
X676261Y676195D01*
G01X673928Y674283D02*
Y677383D01*
X674388Y676763D01*
G01Y674283D02*
X673468D01*
G01X671480Y674645D02*
X671211Y674386D01*
X670905Y674283D01*
X670598Y674386D01*
X670330Y674696D01*
X670138Y675161D01*
X670061Y675626D01*
Y676195D01*
X670138Y676660D01*
X670330Y677073D01*
X670560Y677280D01*
X670828Y677383D01*
X671135Y677280D01*
X671365Y677073D01*
X671518Y676763D01*
X671595Y676350D01*
X671518Y675988D01*
X671326Y675626D01*
X671096Y675420D01*
X670828Y675368D01*
X670521Y675471D01*
X670291Y675730D01*
X670061Y676195D01*
G01X738841Y782281D02*
X682600D01*
G01X685286Y794708D02*
X684328Y797808D01*
X683370Y794708D01*
G01X683715Y795793D02*
X684941D01*
G01X681228Y794708D02*
Y797808D01*
X681688Y797188D01*
G01Y794708D02*
X680768D01*
G01X678856Y797291D02*
X678626Y797601D01*
X678358Y797756D01*
X678051Y797808D01*
X677668Y797705D01*
X677400Y797446D01*
X677323Y797136D01*
X677361Y796826D01*
X677515Y796568D01*
X678281Y796051D01*
X678626Y795690D01*
X678856Y795173D01*
X678933Y794708D01*
X677323D01*
G01X696532Y20278D02*
Y23378D01*
X696992Y22758D01*
G01Y20278D02*
X696072D01*
G01X686800Y31377D02*
X686570Y31687D01*
X686302Y31842D01*
X685995Y31894D01*
X685612Y31791D01*
X685344Y31532D01*
X685267Y31222D01*
X685305Y30912D01*
X685459Y30654D01*
X686225Y30137D01*
X686570Y29776D01*
X686800Y29259D01*
X686877Y28794D01*
X685267D01*
G01X685562Y37764D02*
Y40864D01*
X686022Y40244D01*
G01Y37764D02*
X685102D01*
G01X702280Y389800D02*
X702510Y389955D01*
X702778Y390058D01*
X703085D01*
X703430Y389903D01*
X703698Y389645D01*
X703890Y389335D01*
X704043Y388818D01*
X704081Y388353D01*
X704005Y387888D01*
X703890Y387578D01*
X703660Y387268D01*
X703391Y387061D01*
X703123Y386958D01*
X702855D01*
X702586Y387061D01*
X702356Y387216D01*
X702165Y387423D01*
G01X700866Y387578D02*
X700636Y387216D01*
X700330Y387010D01*
X699985Y386958D01*
X699678Y387010D01*
X699371Y387268D01*
X699180Y387578D01*
X699141Y387888D01*
X699218Y388250D01*
X699486Y388508D01*
X699755Y388611D01*
X700100D01*
G01X699755D02*
X699525Y388766D01*
X699333Y389025D01*
X699256Y389335D01*
X699333Y389645D01*
X699525Y389903D01*
X699870Y390058D01*
X700215Y390006D01*
X700560Y389800D01*
G01X697651Y388250D02*
X697383Y388611D01*
X697153Y388818D01*
X696846Y388921D01*
X696578Y388818D01*
X696386Y388611D01*
X696233Y388301D01*
X696195Y387940D01*
X696233Y387630D01*
X696386Y387320D01*
X696616Y387061D01*
X696885Y386958D01*
X697191Y387061D01*
X697460Y387371D01*
X697613Y387836D01*
X697651Y388353D01*
X697575Y389025D01*
X697460Y389386D01*
X697268Y389748D01*
X697000Y390006D01*
X696731Y390058D01*
X696463Y389955D01*
X696271Y389696D01*
G01X693823Y386958D02*
X693555Y387010D01*
X693248Y387165D01*
X693056Y387423D01*
X692980Y387785D01*
X693056Y388146D01*
X693286Y388456D01*
X693631Y388611D01*
X694015D01*
X694245Y388715D01*
X694436Y388973D01*
X694513Y389335D01*
X694398Y389696D01*
X694130Y389955D01*
X693823Y390058D01*
X693516Y389955D01*
X693248Y389696D01*
X693133Y389335D01*
X693210Y388973D01*
X693401Y388715D01*
X693631Y388611D01*
X694015D01*
X694360Y388456D01*
X694590Y388146D01*
X694666Y387785D01*
X694590Y387423D01*
X694398Y387165D01*
X694091Y387010D01*
X693823Y386958D01*
G01X702280Y393847D02*
X702510Y394002D01*
X702778Y394105D01*
X703085D01*
X703430Y393950D01*
X703698Y393692D01*
X703890Y393382D01*
X704043Y392865D01*
X704081Y392400D01*
X704005Y391935D01*
X703890Y391625D01*
X703660Y391315D01*
X703391Y391108D01*
X703123Y391005D01*
X702855D01*
X702586Y391108D01*
X702356Y391263D01*
X702165Y391470D01*
G01X700866Y391625D02*
X700636Y391263D01*
X700330Y391057D01*
X699985Y391005D01*
X699678Y391057D01*
X699371Y391315D01*
X699180Y391625D01*
X699141Y391935D01*
X699218Y392297D01*
X699486Y392555D01*
X699755Y392658D01*
X700100D01*
G01X699755D02*
X699525Y392813D01*
X699333Y393072D01*
X699256Y393382D01*
X699333Y393692D01*
X699525Y393950D01*
X699870Y394105D01*
X700215Y394053D01*
X700560Y393847D01*
G01X697000Y391005D02*
X696923Y391677D01*
X696808Y392245D01*
X696655Y392762D01*
X696463Y393330D01*
X696156Y394105D01*
X697690D01*
G01X694475Y391367D02*
X694206Y391108D01*
X693900Y391005D01*
X693593Y391108D01*
X693325Y391418D01*
X693133Y391883D01*
X693056Y392348D01*
Y392917D01*
X693133Y393382D01*
X693325Y393795D01*
X693555Y394002D01*
X693823Y394105D01*
X694130Y394002D01*
X694360Y393795D01*
X694513Y393485D01*
X694590Y393072D01*
X694513Y392710D01*
X694321Y392348D01*
X694091Y392142D01*
X693823Y392090D01*
X693516Y392193D01*
X693286Y392452D01*
X693056Y392917D01*
G01X702142Y402187D02*
X702372Y402342D01*
X702640Y402445D01*
X702947D01*
X703292Y402290D01*
X703560Y402032D01*
X703752Y401722D01*
X703905Y401205D01*
X703943Y400740D01*
X703867Y400275D01*
X703752Y399965D01*
X703522Y399655D01*
X703253Y399448D01*
X702985Y399345D01*
X702717D01*
X702448Y399448D01*
X702218Y399603D01*
X702027Y399810D01*
G01X700728Y399965D02*
X700498Y399603D01*
X700192Y399397D01*
X699847Y399345D01*
X699540Y399397D01*
X699233Y399655D01*
X699042Y399965D01*
X699003Y400275D01*
X699080Y400637D01*
X699348Y400895D01*
X699617Y400998D01*
X699962D01*
G01X699617D02*
X699387Y401153D01*
X699195Y401412D01*
X699118Y401722D01*
X699195Y402032D01*
X699387Y402290D01*
X699732Y402445D01*
X700077Y402393D01*
X700422Y402187D01*
G01X696862Y399345D02*
X696785Y400017D01*
X696670Y400585D01*
X696517Y401102D01*
X696325Y401670D01*
X696018Y402445D01*
X697552D01*
G01X694528Y399965D02*
X694298Y399603D01*
X693992Y399397D01*
X693647Y399345D01*
X693340Y399397D01*
X693033Y399655D01*
X692842Y399965D01*
X692803Y400275D01*
X692880Y400637D01*
X693148Y400895D01*
X693417Y400998D01*
X693762D01*
G01X693417D02*
X693187Y401153D01*
X692995Y401412D01*
X692918Y401722D01*
X692995Y402032D01*
X693187Y402290D01*
X693532Y402445D01*
X693877Y402393D01*
X694222Y402187D01*
G01X702188Y407363D02*
X702418Y407518D01*
X702686Y407621D01*
X702993D01*
X703338Y407466D01*
X703606Y407208D01*
X703798Y406898D01*
X703951Y406381D01*
X703989Y405916D01*
X703913Y405451D01*
X703798Y405141D01*
X703568Y404831D01*
X703299Y404624D01*
X703031Y404521D01*
X702763D01*
X702494Y404624D01*
X702264Y404779D01*
X702073Y404986D01*
G01X700774Y405141D02*
X700544Y404779D01*
X700238Y404573D01*
X699893Y404521D01*
X699586Y404573D01*
X699279Y404831D01*
X699088Y405141D01*
X699049Y405451D01*
X699126Y405813D01*
X699394Y406071D01*
X699663Y406174D01*
X700008D01*
G01X699663D02*
X699433Y406329D01*
X699241Y406588D01*
X699164Y406898D01*
X699241Y407208D01*
X699433Y407466D01*
X699778Y407621D01*
X700123Y407569D01*
X700468Y407363D01*
G01X696908Y404521D02*
X696831Y405193D01*
X696716Y405761D01*
X696563Y406278D01*
X696371Y406846D01*
X696064Y407621D01*
X697598D01*
G01X693808Y404521D02*
X693731Y405193D01*
X693616Y405761D01*
X693463Y406278D01*
X693271Y406846D01*
X692964Y407621D01*
X694498D01*
G01X702142Y398034D02*
X702372Y398189D01*
X702640Y398292D01*
X702947D01*
X703292Y398137D01*
X703560Y397879D01*
X703752Y397569D01*
X703905Y397052D01*
X703943Y396587D01*
X703867Y396122D01*
X703752Y395812D01*
X703522Y395502D01*
X703253Y395295D01*
X702985Y395192D01*
X702717D01*
X702448Y395295D01*
X702218Y395450D01*
X702027Y395657D01*
G01X700728Y395812D02*
X700498Y395450D01*
X700192Y395244D01*
X699847Y395192D01*
X699540Y395244D01*
X699233Y395502D01*
X699042Y395812D01*
X699003Y396122D01*
X699080Y396484D01*
X699348Y396742D01*
X699617Y396845D01*
X699962D01*
G01X699617D02*
X699387Y397000D01*
X699195Y397259D01*
X699118Y397569D01*
X699195Y397879D01*
X699387Y398137D01*
X699732Y398292D01*
X700077Y398240D01*
X700422Y398034D01*
G01X696862Y395192D02*
X696785Y395864D01*
X696670Y396432D01*
X696517Y396949D01*
X696325Y397517D01*
X696018Y398292D01*
X697552D01*
G01X693685Y395192D02*
Y398292D01*
X694145Y397672D01*
G01Y395192D02*
X693225D01*
G01X688501Y420382D02*
X688656Y420152D01*
X688759Y419884D01*
Y419577D01*
X688604Y419232D01*
X688346Y418964D01*
X688036Y418772D01*
X687519Y418619D01*
X687054Y418581D01*
X686589Y418657D01*
X686279Y418772D01*
X685969Y419002D01*
X685762Y419271D01*
X685659Y419539D01*
Y419807D01*
X685762Y420076D01*
X685917Y420306D01*
X686124Y420497D01*
G01X686279Y421796D02*
X685917Y422026D01*
X685711Y422332D01*
X685659Y422677D01*
X685711Y422984D01*
X685969Y423291D01*
X686279Y423482D01*
X686589Y423521D01*
X686951Y423444D01*
X687209Y423176D01*
X687312Y422907D01*
Y422562D01*
G01Y422907D02*
X687467Y423137D01*
X687726Y423329D01*
X688036Y423406D01*
X688346Y423329D01*
X688604Y423137D01*
X688759Y422792D01*
X688707Y422447D01*
X688501Y422102D01*
G01X685659Y425662D02*
X686331Y425739D01*
X686899Y425854D01*
X687416Y426007D01*
X687984Y426199D01*
X688759Y426506D01*
Y424972D01*
G01X685659Y428839D02*
X685711Y429107D01*
X685866Y429414D01*
X686124Y429606D01*
X686486Y429682D01*
X686847Y429606D01*
X687157Y429376D01*
X687312Y429031D01*
Y428647D01*
X687416Y428417D01*
X687674Y428226D01*
X688036Y428149D01*
X688397Y428264D01*
X688656Y428532D01*
X688759Y428839D01*
X688656Y429146D01*
X688397Y429414D01*
X688036Y429529D01*
X687674Y429452D01*
X687416Y429261D01*
X687312Y429031D01*
Y428647D01*
X687157Y428302D01*
X686847Y428072D01*
X686486Y427996D01*
X686124Y428072D01*
X685866Y428264D01*
X685711Y428571D01*
X685659Y428839D01*
G01X692663Y420382D02*
X692818Y420152D01*
X692921Y419884D01*
Y419577D01*
X692766Y419232D01*
X692508Y418964D01*
X692198Y418772D01*
X691681Y418619D01*
X691216Y418581D01*
X690751Y418657D01*
X690441Y418772D01*
X690131Y419002D01*
X689924Y419271D01*
X689821Y419539D01*
Y419807D01*
X689924Y420076D01*
X690079Y420306D01*
X690286Y420497D01*
G01X690441Y421796D02*
X690079Y422026D01*
X689873Y422332D01*
X689821Y422677D01*
X689873Y422984D01*
X690131Y423291D01*
X690441Y423482D01*
X690751Y423521D01*
X691113Y423444D01*
X691371Y423176D01*
X691474Y422907D01*
Y422562D01*
G01Y422907D02*
X691629Y423137D01*
X691888Y423329D01*
X692198Y423406D01*
X692508Y423329D01*
X692766Y423137D01*
X692921Y422792D01*
X692869Y422447D01*
X692663Y422102D01*
G01X689821Y425662D02*
X690493Y425739D01*
X691061Y425854D01*
X691578Y426007D01*
X692146Y426199D01*
X692921Y426506D01*
Y424972D01*
G01X690286Y427996D02*
X690028Y428226D01*
X689873Y428494D01*
X689821Y428839D01*
X689924Y429184D01*
X690131Y429452D01*
X690493Y429644D01*
X690906Y429682D01*
X691319Y429606D01*
X691578Y429414D01*
X691784Y429146D01*
X691836Y428877D01*
X691784Y428609D01*
X691578Y428264D01*
X692921Y428379D01*
Y429414D01*
G01X696442Y446393D02*
X696597Y446163D01*
X696700Y445895D01*
Y445588D01*
X696545Y445243D01*
X696287Y444975D01*
X695977Y444783D01*
X695460Y444630D01*
X694995Y444592D01*
X694530Y444668D01*
X694220Y444783D01*
X693910Y445013D01*
X693703Y445282D01*
X693600Y445550D01*
Y445818D01*
X693703Y446087D01*
X693858Y446317D01*
X694065Y446508D01*
G01X693600Y448573D02*
X694272Y448650D01*
X694840Y448765D01*
X695357Y448918D01*
X695925Y449110D01*
X696700Y449417D01*
Y447883D01*
G01X693962Y451098D02*
X693703Y451367D01*
X693600Y451673D01*
X693703Y451980D01*
X694013Y452248D01*
X694478Y452440D01*
X694943Y452517D01*
X695512D01*
X695977Y452440D01*
X696390Y452248D01*
X696597Y452018D01*
X696700Y451750D01*
X696597Y451443D01*
X696390Y451213D01*
X696080Y451060D01*
X695667Y450983D01*
X695305Y451060D01*
X694943Y451252D01*
X694737Y451482D01*
X694685Y451750D01*
X694788Y452057D01*
X695047Y452287D01*
X695512Y452517D01*
G01X693600Y454850D02*
X696700D01*
X696080Y454390D01*
G01X693600D02*
Y455310D01*
G01X691861Y441920D02*
X692016Y441690D01*
X692119Y441422D01*
Y441115D01*
X691964Y440770D01*
X691706Y440502D01*
X691396Y440310D01*
X690879Y440157D01*
X690414Y440119D01*
X689949Y440195D01*
X689639Y440310D01*
X689329Y440540D01*
X689122Y440809D01*
X689019Y441077D01*
Y441345D01*
X689122Y441614D01*
X689277Y441844D01*
X689484Y442035D01*
G01X689019Y444100D02*
X689691Y444177D01*
X690259Y444292D01*
X690776Y444445D01*
X691344Y444637D01*
X692119Y444944D01*
Y443410D01*
G01X689019Y447277D02*
X689071Y447545D01*
X689226Y447852D01*
X689484Y448044D01*
X689846Y448120D01*
X690207Y448044D01*
X690517Y447814D01*
X690672Y447469D01*
Y447085D01*
X690776Y446855D01*
X691034Y446664D01*
X691396Y446587D01*
X691757Y446702D01*
X692016Y446970D01*
X692119Y447277D01*
X692016Y447584D01*
X691757Y447852D01*
X691396Y447967D01*
X691034Y447890D01*
X690776Y447699D01*
X690672Y447469D01*
Y447085D01*
X690517Y446740D01*
X690207Y446510D01*
X689846Y446434D01*
X689484Y446510D01*
X689226Y446702D01*
X689071Y447009D01*
X689019Y447277D01*
G01X690311Y449649D02*
X690672Y449917D01*
X690879Y450147D01*
X690982Y450454D01*
X690879Y450722D01*
X690672Y450914D01*
X690362Y451067D01*
X690001Y451105D01*
X689691Y451067D01*
X689381Y450914D01*
X689122Y450684D01*
X689019Y450415D01*
X689122Y450109D01*
X689432Y449840D01*
X689897Y449687D01*
X690414Y449649D01*
X691086Y449725D01*
X691447Y449840D01*
X691809Y450032D01*
X692067Y450300D01*
X692119Y450569D01*
X692016Y450837D01*
X691757Y451029D01*
G01X686826Y452765D02*
X691426D01*
G01X686826Y462965D02*
Y452765D01*
G01X691426D02*
Y462965D01*
G01X685530Y452699D02*
Y462899D01*
G01X692533Y467240D02*
X697133D01*
G01X692533Y462140D02*
X697133D01*
G01X692533Y472340D02*
Y462140D01*
G01X697133D02*
Y472340D01*
G01X691426Y457865D02*
X686826D01*
G01X691426Y462965D02*
X686826D01*
G01X685595Y465730D02*
Y470330D01*
G01X692782Y483806D02*
X697382D01*
G01X692782Y478706D02*
X697382D01*
G01X692782Y488906D02*
Y478706D01*
G01X697382D02*
Y488906D01*
G01X695559Y477792D02*
Y473192D01*
G01D02*
X705759D01*
G01Y477792D02*
X695559D01*
G01X689620Y477342D02*
Y472742D01*
G01X684520D02*
X694720D01*
G01X684520Y477342D02*
Y472742D01*
G01X694720Y477342D02*
X684520D01*
G01X694720Y472742D02*
Y477342D01*
G01X697133Y472340D02*
X692533D01*
G01X700027Y491343D02*
X700182Y491113D01*
X700285Y490845D01*
Y490538D01*
X700130Y490193D01*
X699872Y489925D01*
X699562Y489733D01*
X699045Y489580D01*
X698580Y489542D01*
X698115Y489618D01*
X697805Y489733D01*
X697495Y489963D01*
X697288Y490232D01*
X697185Y490500D01*
Y490768D01*
X697288Y491037D01*
X697443Y491267D01*
X697650Y491458D01*
G01X697185Y493523D02*
X697857Y493600D01*
X698425Y493715D01*
X698942Y493868D01*
X699510Y494060D01*
X700285Y494367D01*
Y492833D01*
G01X697185Y496700D02*
X697237Y496968D01*
X697392Y497275D01*
X697650Y497467D01*
X698012Y497543D01*
X698373Y497467D01*
X698683Y497237D01*
X698838Y496892D01*
Y496508D01*
X698942Y496278D01*
X699200Y496087D01*
X699562Y496010D01*
X699923Y496125D01*
X700182Y496393D01*
X700285Y496700D01*
X700182Y497007D01*
X699923Y497275D01*
X699562Y497390D01*
X699200Y497313D01*
X698942Y497122D01*
X698838Y496892D01*
Y496508D01*
X698683Y496163D01*
X698373Y495933D01*
X698012Y495857D01*
X697650Y495933D01*
X697392Y496125D01*
X697237Y496432D01*
X697185Y496700D01*
G01Y499723D02*
X697857Y499800D01*
X698425Y499915D01*
X698942Y500068D01*
X699510Y500260D01*
X700285Y500567D01*
Y499033D01*
G01X697382Y488906D02*
X692782D01*
G01X685068Y624247D02*
Y630447D01*
G01X685968Y627347D02*
X688968D01*
G01X689068Y624247D02*
Y630447D01*
G01X685868D02*
Y624247D01*
G01D02*
X689068D01*
G01X688885Y639426D02*
X689040Y639196D01*
X689143Y638928D01*
Y638621D01*
X688988Y638276D01*
X688730Y638008D01*
X688420Y637816D01*
X687903Y637663D01*
X687438Y637625D01*
X686973Y637701D01*
X686663Y637816D01*
X686353Y638046D01*
X686146Y638315D01*
X686043Y638583D01*
Y638851D01*
X686146Y639120D01*
X686301Y639350D01*
X686508Y639541D01*
G01Y640840D02*
X686250Y641070D01*
X686095Y641338D01*
X686043Y641683D01*
X686146Y642028D01*
X686353Y642296D01*
X686715Y642488D01*
X687128Y642526D01*
X687541Y642450D01*
X687800Y642258D01*
X688006Y641990D01*
X688058Y641721D01*
X688006Y641453D01*
X687800Y641108D01*
X689143Y641223D01*
Y642258D01*
G01X688626Y644055D02*
X688936Y644285D01*
X689091Y644553D01*
X689143Y644860D01*
X689040Y645243D01*
X688781Y645511D01*
X688471Y645588D01*
X688161Y645550D01*
X687903Y645396D01*
X687386Y644630D01*
X687025Y644285D01*
X686508Y644055D01*
X686043Y643978D01*
Y645588D01*
G01X686663Y647040D02*
X686301Y647270D01*
X686095Y647576D01*
X686043Y647921D01*
X686095Y648228D01*
X686353Y648535D01*
X686663Y648726D01*
X686973Y648765D01*
X687335Y648688D01*
X687593Y648420D01*
X687696Y648151D01*
Y647806D01*
G01Y648151D02*
X687851Y648381D01*
X688110Y648573D01*
X688420Y648650D01*
X688730Y648573D01*
X688988Y648381D01*
X689143Y648036D01*
X689091Y647691D01*
X688885Y647346D01*
G01X689068Y630447D02*
X685868D01*
G01X704006Y793929D02*
X703048Y797029D01*
X702090Y793929D01*
G01X702435Y795014D02*
X703661D01*
G01X699948Y793929D02*
Y797029D01*
X700408Y796409D01*
G01Y793929D02*
X699488D01*
G01X696848D02*
Y797029D01*
X697308Y796409D01*
G01Y793929D02*
X696388D01*
G01X709575Y39179D02*
X709345Y39489D01*
X709077Y39644D01*
X708770Y39696D01*
X708387Y39593D01*
X708119Y39334D01*
X708042Y39024D01*
X708080Y38714D01*
X708234Y38456D01*
X709000Y37939D01*
X709345Y37578D01*
X709575Y37061D01*
X709652Y36596D01*
X708042D01*
G01X708348Y154473D02*
X708118Y154215D01*
X707850Y154060D01*
X707505Y154008D01*
X707160Y154111D01*
X706892Y154318D01*
X706700Y154680D01*
X706662Y155093D01*
X706738Y155506D01*
X706930Y155765D01*
X707198Y155971D01*
X707467Y156023D01*
X707735Y155971D01*
X708080Y155765D01*
X707965Y157108D01*
X706930D01*
G01X707044Y182187D02*
X706776Y182239D01*
X706469Y182394D01*
X706277Y182652D01*
X706201Y183014D01*
X706277Y183375D01*
X706507Y183685D01*
X706852Y183840D01*
X707236D01*
X707466Y183944D01*
X707657Y184202D01*
X707734Y184564D01*
X707619Y184925D01*
X707351Y185184D01*
X707044Y185287D01*
X706737Y185184D01*
X706469Y184925D01*
X706354Y184564D01*
X706431Y184202D01*
X706622Y183944D01*
X706852Y183840D01*
X707236D01*
X707581Y183685D01*
X707811Y183375D01*
X707887Y183014D01*
X707811Y182652D01*
X707619Y182394D01*
X707312Y182239D01*
X707044Y182187D01*
G01X708257Y233526D02*
X708027Y233268D01*
X707759Y233113D01*
X707414Y233061D01*
X707069Y233164D01*
X706801Y233371D01*
X706609Y233733D01*
X706571Y234146D01*
X706647Y234559D01*
X706839Y234818D01*
X707107Y235024D01*
X707376Y235076D01*
X707644Y235024D01*
X707989Y234818D01*
X707874Y236161D01*
X706839D01*
G01X707414Y260872D02*
X707146Y260924D01*
X706839Y261079D01*
X706647Y261337D01*
X706571Y261699D01*
X706647Y262060D01*
X706877Y262370D01*
X707222Y262525D01*
X707606D01*
X707836Y262629D01*
X708027Y262887D01*
X708104Y263249D01*
X707989Y263610D01*
X707721Y263869D01*
X707414Y263972D01*
X707107Y263869D01*
X706839Y263610D01*
X706724Y263249D01*
X706801Y262887D01*
X706992Y262629D01*
X707222Y262525D01*
X707606D01*
X707951Y262370D01*
X708181Y262060D01*
X708257Y261699D01*
X708181Y261337D01*
X707989Y261079D01*
X707682Y260924D01*
X707414Y260872D01*
G01X724431Y470156D02*
X724661Y470311D01*
X724929Y470414D01*
X725236D01*
X725581Y470259D01*
X725849Y470001D01*
X726041Y469691D01*
X726194Y469174D01*
X726232Y468709D01*
X726156Y468244D01*
X726041Y467934D01*
X725811Y467624D01*
X725542Y467417D01*
X725274Y467314D01*
X725006D01*
X724737Y467417D01*
X724507Y467572D01*
X724316Y467779D01*
G01X722251Y467314D02*
X722174Y467986D01*
X722059Y468554D01*
X721906Y469071D01*
X721714Y469639D01*
X721407Y470414D01*
X722941D01*
G01X719074Y467314D02*
X718806Y467366D01*
X718499Y467521D01*
X718307Y467779D01*
X718231Y468141D01*
X718307Y468502D01*
X718537Y468812D01*
X718882Y468967D01*
X719266D01*
X719496Y469071D01*
X719687Y469329D01*
X719764Y469691D01*
X719649Y470052D01*
X719381Y470311D01*
X719074Y470414D01*
X718767Y470311D01*
X718499Y470052D01*
X718384Y469691D01*
X718461Y469329D01*
X718652Y469071D01*
X718882Y468967D01*
X719266D01*
X719611Y468812D01*
X719841Y468502D01*
X719917Y468141D01*
X719841Y467779D01*
X719649Y467521D01*
X719342Y467366D01*
X719074Y467314D01*
G01X716702Y469897D02*
X716472Y470207D01*
X716204Y470362D01*
X715897Y470414D01*
X715514Y470311D01*
X715246Y470052D01*
X715169Y469742D01*
X715207Y469432D01*
X715361Y469174D01*
X716127Y468657D01*
X716472Y468296D01*
X716702Y467779D01*
X716779Y467314D01*
X715169D01*
G01X709295Y470430D02*
Y465830D01*
G01X704195D02*
X714395D01*
G01X704195Y470430D02*
Y465830D01*
G01X714395Y470430D02*
X704195D01*
G01X714395Y465830D02*
Y470430D01*
G01X724459Y464752D02*
X724689Y464907D01*
X724957Y465010D01*
X725264D01*
X725609Y464855D01*
X725877Y464597D01*
X726069Y464287D01*
X726222Y463770D01*
X726260Y463305D01*
X726184Y462840D01*
X726069Y462530D01*
X725839Y462220D01*
X725570Y462013D01*
X725302Y461910D01*
X725034D01*
X724765Y462013D01*
X724535Y462168D01*
X724344Y462375D01*
G01X722279Y461910D02*
X722202Y462582D01*
X722087Y463150D01*
X721934Y463667D01*
X721742Y464235D01*
X721435Y465010D01*
X722969D01*
G01X719102Y461910D02*
X718834Y461962D01*
X718527Y462117D01*
X718335Y462375D01*
X718259Y462737D01*
X718335Y463098D01*
X718565Y463408D01*
X718910Y463563D01*
X719294D01*
X719524Y463667D01*
X719715Y463925D01*
X719792Y464287D01*
X719677Y464648D01*
X719409Y464907D01*
X719102Y465010D01*
X718795Y464907D01*
X718527Y464648D01*
X718412Y464287D01*
X718489Y463925D01*
X718680Y463667D01*
X718910Y463563D01*
X719294D01*
X719639Y463408D01*
X719869Y463098D01*
X719945Y462737D01*
X719869Y462375D01*
X719677Y462117D01*
X719370Y461962D01*
X719102Y461910D01*
G01X716845Y462530D02*
X716615Y462168D01*
X716309Y461962D01*
X715964Y461910D01*
X715657Y461962D01*
X715350Y462220D01*
X715159Y462530D01*
X715120Y462840D01*
X715197Y463202D01*
X715465Y463460D01*
X715734Y463563D01*
X716079D01*
G01X715734D02*
X715504Y463718D01*
X715312Y463977D01*
X715235Y464287D01*
X715312Y464597D01*
X715504Y464855D01*
X715849Y465010D01*
X716194Y464958D01*
X716539Y464752D01*
G01X709295Y464830D02*
Y460230D01*
G01X704195D02*
X714395D01*
G01X704195Y464830D02*
Y460230D01*
G01X714395Y464830D02*
X704195D01*
G01X714395Y460230D02*
Y464830D01*
G01X700659Y473192D02*
Y477792D01*
G01X705759Y473192D02*
Y477792D01*
G01X709761Y627298D02*
X712761D01*
G01X712861Y624198D02*
Y630398D01*
G01X709661D02*
Y624198D01*
G01D02*
X712861D01*
G01X714261Y627298D02*
X717261D01*
G01X714162Y630398D02*
Y624198D01*
G01D02*
X717360D01*
G01X712964Y639621D02*
X713119Y639391D01*
X713222Y639123D01*
Y638816D01*
X713067Y638471D01*
X712809Y638203D01*
X712499Y638011D01*
X711982Y637858D01*
X711517Y637820D01*
X711052Y637896D01*
X710742Y638011D01*
X710432Y638241D01*
X710225Y638510D01*
X710122Y638778D01*
Y639046D01*
X710225Y639315D01*
X710380Y639545D01*
X710587Y639736D01*
G01Y641035D02*
X710329Y641265D01*
X710174Y641533D01*
X710122Y641878D01*
X710225Y642223D01*
X710432Y642491D01*
X710794Y642683D01*
X711207Y642721D01*
X711620Y642645D01*
X711879Y642453D01*
X712085Y642185D01*
X712137Y641916D01*
X712085Y641648D01*
X711879Y641303D01*
X713222Y641418D01*
Y642453D01*
G01X712705Y644250D02*
X713015Y644480D01*
X713170Y644748D01*
X713222Y645055D01*
X713119Y645438D01*
X712860Y645706D01*
X712550Y645783D01*
X712240Y645745D01*
X711982Y645591D01*
X711465Y644825D01*
X711104Y644480D01*
X710587Y644250D01*
X710122Y644173D01*
Y645783D01*
G01X713222Y648078D02*
X713119Y647771D01*
X712860Y647541D01*
X712550Y647388D01*
X712137Y647273D01*
X711672Y647235D01*
X711207Y647273D01*
X710794Y647388D01*
X710484Y647541D01*
X710225Y647771D01*
X710122Y648078D01*
X710225Y648385D01*
X710484Y648615D01*
X710794Y648768D01*
X711207Y648883D01*
X711672Y648921D01*
X712137Y648883D01*
X712550Y648768D01*
X712860Y648615D01*
X713119Y648385D01*
X713222Y648078D01*
G01X712861Y630398D02*
X709661D01*
G01X717033Y639628D02*
X717188Y639398D01*
X717291Y639130D01*
Y638823D01*
X717136Y638478D01*
X716878Y638210D01*
X716568Y638018D01*
X716051Y637865D01*
X715586Y637827D01*
X715121Y637903D01*
X714811Y638018D01*
X714501Y638248D01*
X714294Y638517D01*
X714191Y638785D01*
Y639053D01*
X714294Y639322D01*
X714449Y639552D01*
X714656Y639743D01*
G01Y641042D02*
X714398Y641272D01*
X714243Y641540D01*
X714191Y641885D01*
X714294Y642230D01*
X714501Y642498D01*
X714863Y642690D01*
X715276Y642728D01*
X715689Y642652D01*
X715948Y642460D01*
X716154Y642192D01*
X716206Y641923D01*
X716154Y641655D01*
X715948Y641310D01*
X717291Y641425D01*
Y642460D01*
G01X716774Y644257D02*
X717084Y644487D01*
X717239Y644755D01*
X717291Y645062D01*
X717188Y645445D01*
X716929Y645713D01*
X716619Y645790D01*
X716309Y645752D01*
X716051Y645598D01*
X715534Y644832D01*
X715173Y644487D01*
X714656Y644257D01*
X714191Y644180D01*
Y645790D01*
G01Y648545D02*
X717291D01*
X715069Y647127D01*
Y649043D01*
G01X717360Y630398D02*
X714162D01*
G01X710742Y749893D02*
X710897Y749663D01*
X711000Y749395D01*
Y749088D01*
X710845Y748743D01*
X710587Y748475D01*
X710277Y748283D01*
X709760Y748130D01*
X709295Y748092D01*
X708830Y748168D01*
X708520Y748283D01*
X708210Y748513D01*
X708003Y748782D01*
X707900Y749050D01*
Y749318D01*
X708003Y749587D01*
X708158Y749817D01*
X708365Y750008D01*
G01Y751307D02*
X708107Y751537D01*
X707952Y751805D01*
X707900Y752150D01*
X708003Y752495D01*
X708210Y752763D01*
X708572Y752955D01*
X708985Y752993D01*
X709398Y752917D01*
X709657Y752725D01*
X709863Y752457D01*
X709915Y752188D01*
X709863Y751920D01*
X709657Y751575D01*
X711000Y751690D01*
Y752725D01*
G01X708262Y754598D02*
X708003Y754867D01*
X707900Y755173D01*
X708003Y755480D01*
X708313Y755748D01*
X708778Y755940D01*
X709243Y756017D01*
X709812D01*
X710277Y755940D01*
X710690Y755748D01*
X710897Y755518D01*
X711000Y755250D01*
X710897Y754943D01*
X710690Y754713D01*
X710380Y754560D01*
X709967Y754483D01*
X709605Y754560D01*
X709243Y754752D01*
X709037Y754982D01*
X708985Y755250D01*
X709088Y755557D01*
X709347Y755787D01*
X709812Y756017D01*
G01X710483Y757622D02*
X710793Y757852D01*
X710948Y758120D01*
X711000Y758427D01*
X710897Y758810D01*
X710638Y759078D01*
X710328Y759155D01*
X710018Y759117D01*
X709760Y758963D01*
X709243Y758197D01*
X708882Y757852D01*
X708365Y757622D01*
X707900Y757545D01*
Y759155D01*
G01Y738900D02*
X711100D01*
G01X707900Y745100D02*
Y738900D01*
G01X711100D02*
Y745100D01*
G01X708000Y742000D02*
X711000D01*
G01X711100Y745100D02*
X707900D01*
G01X717560Y26361D02*
X717330Y25999D01*
X717024Y25793D01*
X716679Y25741D01*
X716372Y25793D01*
X716065Y26051D01*
X715874Y26361D01*
X715835Y26671D01*
X715912Y27033D01*
X716180Y27291D01*
X716449Y27394D01*
X716794D01*
G01X716449D02*
X716219Y27549D01*
X716027Y27808D01*
X715950Y28118D01*
X716027Y28428D01*
X716219Y28686D01*
X716564Y28841D01*
X716909Y28789D01*
X717254Y28583D01*
G01X728041Y154008D02*
Y157108D01*
X728501Y156488D01*
G01Y154008D02*
X727581D01*
G01X728594Y182002D02*
Y185102D01*
X730012Y182880D01*
X728096D01*
G01X728226Y233154D02*
Y236254D01*
X728686Y235634D01*
G01Y233154D02*
X727766D01*
G01X728503Y261056D02*
Y264156D01*
X729921Y261934D01*
X728005D01*
G01X732594Y475102D02*
X732824Y475257D01*
X733092Y475360D01*
X733399D01*
X733744Y475205D01*
X734012Y474947D01*
X734204Y474637D01*
X734357Y474120D01*
X734395Y473655D01*
X734319Y473190D01*
X734204Y472880D01*
X733974Y472570D01*
X733705Y472363D01*
X733437Y472260D01*
X733169D01*
X732900Y472363D01*
X732670Y472518D01*
X732479Y472725D01*
G01X730414Y472260D02*
X730337Y472932D01*
X730222Y473500D01*
X730069Y474017D01*
X729877Y474585D01*
X729570Y475360D01*
X731104D01*
G01X727237Y472260D02*
X726969Y472312D01*
X726662Y472467D01*
X726470Y472725D01*
X726394Y473087D01*
X726470Y473448D01*
X726700Y473758D01*
X727045Y473913D01*
X727429D01*
X727659Y474017D01*
X727850Y474275D01*
X727927Y474637D01*
X727812Y474998D01*
X727544Y475257D01*
X727237Y475360D01*
X726930Y475257D01*
X726662Y474998D01*
X726547Y474637D01*
X726624Y474275D01*
X726815Y474017D01*
X727045Y473913D01*
X727429D01*
X727774Y473758D01*
X728004Y473448D01*
X728080Y473087D01*
X728004Y472725D01*
X727812Y472467D01*
X727505Y472312D01*
X727237Y472260D01*
G01X724789Y472622D02*
X724520Y472363D01*
X724214Y472260D01*
X723907Y472363D01*
X723639Y472673D01*
X723447Y473138D01*
X723370Y473603D01*
Y474172D01*
X723447Y474637D01*
X723639Y475050D01*
X723869Y475257D01*
X724137Y475360D01*
X724444Y475257D01*
X724674Y475050D01*
X724827Y474740D01*
X724904Y474327D01*
X724827Y473965D01*
X724635Y473603D01*
X724405Y473397D01*
X724137Y473345D01*
X723830Y473448D01*
X723600Y473707D01*
X723370Y474172D01*
G01X718761Y627298D02*
X721761D01*
G01X718662Y630398D02*
Y624198D01*
G01X721860D02*
Y630398D01*
G01X718662Y624198D02*
X721860D01*
G01X717360D02*
Y630398D01*
G01X721054Y639353D02*
X721209Y639123D01*
X721312Y638855D01*
Y638548D01*
X721157Y638203D01*
X720899Y637935D01*
X720589Y637743D01*
X720072Y637590D01*
X719607Y637552D01*
X719142Y637628D01*
X718832Y637743D01*
X718522Y637973D01*
X718315Y638242D01*
X718212Y638510D01*
Y638778D01*
X718315Y639047D01*
X718470Y639277D01*
X718677Y639468D01*
G01Y640767D02*
X718419Y640997D01*
X718264Y641265D01*
X718212Y641610D01*
X718315Y641955D01*
X718522Y642223D01*
X718884Y642415D01*
X719297Y642453D01*
X719710Y642377D01*
X719969Y642185D01*
X720175Y641917D01*
X720227Y641648D01*
X720175Y641380D01*
X719969Y641035D01*
X721312Y641150D01*
Y642185D01*
G01X720795Y643982D02*
X721105Y644212D01*
X721260Y644480D01*
X721312Y644787D01*
X721209Y645170D01*
X720950Y645438D01*
X720640Y645515D01*
X720330Y645477D01*
X720072Y645323D01*
X719555Y644557D01*
X719194Y644212D01*
X718677Y643982D01*
X718212Y643905D01*
Y645515D01*
G01X720795Y647082D02*
X721105Y647312D01*
X721260Y647580D01*
X721312Y647887D01*
X721209Y648270D01*
X720950Y648538D01*
X720640Y648615D01*
X720330Y648577D01*
X720072Y648423D01*
X719555Y647657D01*
X719194Y647312D01*
X718677Y647082D01*
X718212Y647005D01*
Y648615D01*
G01X721860Y630398D02*
X718662D01*
G01X729642Y718493D02*
X729797Y718263D01*
X729900Y717995D01*
Y717688D01*
X729745Y717343D01*
X729487Y717075D01*
X729177Y716883D01*
X728660Y716730D01*
X728195Y716692D01*
X727730Y716768D01*
X727420Y716883D01*
X727110Y717113D01*
X726903Y717382D01*
X726800Y717650D01*
Y717918D01*
X726903Y718187D01*
X727058Y718417D01*
X727265Y718608D01*
G01Y719907D02*
X727007Y720137D01*
X726852Y720405D01*
X726800Y720750D01*
X726903Y721095D01*
X727110Y721363D01*
X727472Y721555D01*
X727885Y721593D01*
X728298Y721517D01*
X728557Y721325D01*
X728763Y721057D01*
X728815Y720788D01*
X728763Y720520D01*
X728557Y720175D01*
X729900Y720290D01*
Y721325D01*
G01X727162Y723198D02*
X726903Y723467D01*
X726800Y723773D01*
X726903Y724080D01*
X727213Y724348D01*
X727678Y724540D01*
X728143Y724617D01*
X728712D01*
X729177Y724540D01*
X729590Y724348D01*
X729797Y724118D01*
X729900Y723850D01*
X729797Y723543D01*
X729590Y723313D01*
X729280Y723160D01*
X728867Y723083D01*
X728505Y723160D01*
X728143Y723352D01*
X727937Y723582D01*
X727885Y723850D01*
X727988Y724157D01*
X728247Y724387D01*
X728712Y724617D01*
G01X726800Y727410D02*
X729900D01*
X727678Y725992D01*
Y727908D01*
G01X731100Y736100D02*
X727900D01*
G01X731100Y729900D02*
Y736100D01*
G01X727900D02*
Y729900D01*
G01X731000Y733000D02*
X728000D01*
G01X727900Y729900D02*
X731100D01*
G01X730742Y750593D02*
X730897Y750363D01*
X731000Y750095D01*
Y749788D01*
X730845Y749443D01*
X730587Y749175D01*
X730277Y748983D01*
X729760Y748830D01*
X729295Y748792D01*
X728830Y748868D01*
X728520Y748983D01*
X728210Y749213D01*
X728003Y749482D01*
X727900Y749750D01*
Y750018D01*
X728003Y750287D01*
X728158Y750517D01*
X728365Y750708D01*
G01Y752007D02*
X728107Y752237D01*
X727952Y752505D01*
X727900Y752850D01*
X728003Y753195D01*
X728210Y753463D01*
X728572Y753655D01*
X728985Y753693D01*
X729398Y753617D01*
X729657Y753425D01*
X729863Y753157D01*
X729915Y752888D01*
X729863Y752620D01*
X729657Y752275D01*
X731000Y752390D01*
Y753425D01*
G01X728262Y755298D02*
X728003Y755567D01*
X727900Y755873D01*
X728003Y756180D01*
X728313Y756448D01*
X728778Y756640D01*
X729243Y756717D01*
X729812D01*
X730277Y756640D01*
X730690Y756448D01*
X730897Y756218D01*
X731000Y755950D01*
X730897Y755643D01*
X730690Y755413D01*
X730380Y755260D01*
X729967Y755183D01*
X729605Y755260D01*
X729243Y755452D01*
X729037Y755682D01*
X728985Y755950D01*
X729088Y756257D01*
X729347Y756487D01*
X729812Y756717D01*
G01X729192Y758322D02*
X729553Y758590D01*
X729760Y758820D01*
X729863Y759127D01*
X729760Y759395D01*
X729553Y759587D01*
X729243Y759740D01*
X728882Y759778D01*
X728572Y759740D01*
X728262Y759587D01*
X728003Y759357D01*
X727900Y759088D01*
X728003Y758782D01*
X728313Y758513D01*
X728778Y758360D01*
X729295Y758322D01*
X729967Y758398D01*
X730328Y758513D01*
X730690Y758705D01*
X730948Y758973D01*
X731000Y759242D01*
X730897Y759510D01*
X730638Y759702D01*
G01X727900Y738900D02*
X731100D01*
G01X727900Y745100D02*
Y738900D01*
G01X728000Y742000D02*
X731000D01*
G01X731100Y745100D02*
X727900D01*
G01X731100Y738900D02*
Y745100D01*
G01X741120Y35095D02*
Y38195D01*
X741580Y37575D01*
G01Y35095D02*
X740660D01*
G01X745532Y475009D02*
X745762Y475164D01*
X746030Y475267D01*
X746337D01*
X746682Y475112D01*
X746950Y474854D01*
X747142Y474544D01*
X747295Y474027D01*
X747333Y473562D01*
X747257Y473097D01*
X747142Y472787D01*
X746912Y472477D01*
X746643Y472270D01*
X746375Y472167D01*
X746107D01*
X745838Y472270D01*
X745608Y472425D01*
X745417Y472632D01*
G01X743352Y472167D02*
X743275Y472839D01*
X743160Y473407D01*
X743007Y473924D01*
X742815Y474492D01*
X742508Y475267D01*
X744042D01*
G01X740175Y472167D02*
X739907Y472219D01*
X739600Y472374D01*
X739408Y472632D01*
X739332Y472994D01*
X739408Y473355D01*
X739638Y473665D01*
X739983Y473820D01*
X740367D01*
X740597Y473924D01*
X740788Y474182D01*
X740865Y474544D01*
X740750Y474905D01*
X740482Y475164D01*
X740175Y475267D01*
X739868Y475164D01*
X739600Y474905D01*
X739485Y474544D01*
X739562Y474182D01*
X739753Y473924D01*
X739983Y473820D01*
X740367D01*
X740712Y473665D01*
X740942Y473355D01*
X741018Y472994D01*
X740942Y472632D01*
X740750Y472374D01*
X740443Y472219D01*
X740175Y472167D01*
G01X737075D02*
X736807Y472219D01*
X736500Y472374D01*
X736308Y472632D01*
X736232Y472994D01*
X736308Y473355D01*
X736538Y473665D01*
X736883Y473820D01*
X737267D01*
X737497Y473924D01*
X737688Y474182D01*
X737765Y474544D01*
X737650Y474905D01*
X737382Y475164D01*
X737075Y475267D01*
X736768Y475164D01*
X736500Y474905D01*
X736385Y474544D01*
X736462Y474182D01*
X736653Y473924D01*
X736883Y473820D01*
X737267D01*
X737612Y473665D01*
X737842Y473355D01*
X737918Y472994D01*
X737842Y472632D01*
X737650Y472374D01*
X737343Y472219D01*
X737075Y472167D01*
G01X736886Y794838D02*
X735928Y797938D01*
X734970Y794838D01*
G01X735315Y795923D02*
X736541D01*
G01X732828Y794838D02*
Y797938D01*
X733288Y797318D01*
G01Y794838D02*
X732368D01*
G01X750802Y37678D02*
X750572Y37988D01*
X750304Y38143D01*
X749997Y38195D01*
X749614Y38092D01*
X749346Y37833D01*
X749269Y37523D01*
X749307Y37213D01*
X749461Y36955D01*
X750227Y36438D01*
X750572Y36077D01*
X750802Y35560D01*
X750879Y35095D01*
X749269D01*
M02*
